G04 ================== begin FILE IDENTIFICATION RECORD ==================*
G04 Layout Name:  15126-1b.brd*
G04 Film Name:    SE_REF_L10*
G04 File Format:  Gerber RS274X*
G04 File Origin:  Cadence Allegro 16.6-2015-S079*
G04 Origin Date:  Fri Feb 10 17:23:36 2017*
G04 *
G04 Layer:  BOARD GEOMETRY/PANEL_OUTLINE*
G04 Layer:  BOARD GEOMETRY/SE_REF_L10_TBL*
G04 Layer:  BOARD GEOMETRY/SE_REF_L10_L10*
G04 *
G04 Offset:    (0.00 0.00)*
G04 Mirror:    No*
G04 Mode:      Positive*
G04 Rotation:  0*
G04 FullContactRelief:  No*
G04 UndefLineWidth:     6.00*
G04 ================== end FILE IDENTIFICATION RECORD ====================*
%FSLAX35Y35*MOIN*%
%IR0*IPPOS*OFA0.00000B0.00000*MIA0B0*SFA1.00000B1.00000*%
%ADD10C,.02*%
%ADD11C,.006*%
%ADD12C,.0035*%
%ADD13C,.00352*%
%ADD14C,.0056*%
G75*
%LPD*%
G75*
G54D10*
G01X2026678Y631398D02*
Y527448D01*
G01D02*
X2779178D01*
G01X2026678Y562098D02*
X2779178D01*
G01X2026678Y596748D02*
X2779178D01*
G01X2026678Y631398D02*
X2779178D01*
G01X2201678D02*
Y527448D01*
G01X2464178Y631398D02*
Y527448D01*
G01X2569178Y631398D02*
Y527448D01*
G01X2779178Y631398D02*
Y527448D01*
G54D11*
G01X-17372Y-95792D02*
Y-113292D01*
G01X-22394Y-95792D02*
X-12350D01*
G01X-3584Y-113292D02*
Y-95792D01*
G01Y-104250D02*
X-2492Y-102792D01*
X-1400Y-101917D01*
X346Y-101626D01*
X1656Y-101917D01*
X3185Y-103084D01*
X3840Y-104834D01*
Y-113292D01*
G01X17628Y-101626D02*
Y-113292D01*
G01Y-96959D02*
X17191Y-96667D01*
Y-96084D01*
X17628Y-95792D01*
X18065Y-96084D01*
Y-96667D01*
X17628Y-96959D01*
G01X31853Y-111251D02*
X32945Y-112417D01*
X34473Y-113292D01*
X35783D01*
X37093Y-112709D01*
X37966Y-111834D01*
X38403Y-110668D01*
X38185Y-108917D01*
X37311Y-108042D01*
X33381Y-106292D01*
X32508Y-104250D01*
X32945Y-102792D01*
X33818Y-101917D01*
X35128Y-101626D01*
X36438Y-101917D01*
X37748Y-102792D01*
G01X67071Y-117667D02*
X68600Y-118834D01*
X70346Y-119125D01*
X71874Y-118834D01*
X73185Y-117376D01*
X74058Y-115334D01*
Y-101626D01*
G01Y-103959D02*
X73185Y-102792D01*
X71874Y-101917D01*
X70346Y-101626D01*
X68600Y-102209D01*
X67508Y-103375D01*
X66634Y-105417D01*
X66198Y-107459D01*
X66416Y-109209D01*
X67290Y-111251D01*
X68600Y-112709D01*
X70346Y-113292D01*
X71656Y-113000D01*
X73185Y-111834D01*
X74058Y-110668D01*
G01X84353Y-105417D02*
X91340D01*
X90685Y-103375D01*
X89593Y-102209D01*
X88065Y-101626D01*
X86536Y-101917D01*
X85226Y-102792D01*
X84353Y-104834D01*
X83916Y-106584D01*
Y-108334D01*
X84353Y-110084D01*
X85445Y-111834D01*
X86755Y-113000D01*
X88283Y-113292D01*
X89811Y-112709D01*
X91340Y-110959D01*
G01X102071Y-113292D02*
Y-101626D01*
G01Y-103959D02*
X103163Y-102792D01*
X104255Y-101917D01*
X105783Y-101626D01*
X106874Y-101917D01*
X108185Y-102792D01*
G01X118698Y-113292D02*
Y-95792D01*
G01Y-104542D02*
X119790Y-102792D01*
X121100Y-101917D01*
X122410Y-101626D01*
X124374Y-102209D01*
X125685Y-103375D01*
X126558Y-105417D01*
Y-107750D01*
X126121Y-110084D01*
X125248Y-111834D01*
X123720Y-113000D01*
X122410Y-113292D01*
X121100Y-113000D01*
X119790Y-112126D01*
X118698Y-110668D01*
G01X136853Y-105417D02*
X143840D01*
X143185Y-103375D01*
X142093Y-102209D01*
X140565Y-101626D01*
X139036Y-101917D01*
X137726Y-102792D01*
X136853Y-104834D01*
X136416Y-106584D01*
Y-108334D01*
X136853Y-110084D01*
X137945Y-111834D01*
X139255Y-113000D01*
X140783Y-113292D01*
X142311Y-112709D01*
X143840Y-110959D01*
G01X154571Y-113292D02*
Y-101626D01*
G01Y-103959D02*
X155663Y-102792D01*
X156755Y-101917D01*
X158283Y-101626D01*
X159374Y-101917D01*
X160685Y-102792D01*
G01X192628Y-101626D02*
Y-113292D01*
G01Y-96959D02*
X192191Y-96667D01*
Y-96084D01*
X192628Y-95792D01*
X193065Y-96084D01*
Y-96667D01*
X192628Y-96959D01*
G01X206853Y-111251D02*
X207945Y-112417D01*
X209473Y-113292D01*
X210783D01*
X212093Y-112709D01*
X212966Y-111834D01*
X213403Y-110668D01*
X213185Y-108917D01*
X212311Y-108042D01*
X208381Y-106292D01*
X207508Y-104250D01*
X207945Y-102792D01*
X208818Y-101917D01*
X210128Y-101626D01*
X211438Y-101917D01*
X212748Y-102792D01*
G01X241634Y-117667D02*
X243163Y-118834D01*
X244473Y-119125D01*
X246220Y-118542D01*
X247530Y-117084D01*
X248185Y-114458D01*
Y-101626D01*
G01Y-96959D02*
X247748Y-96667D01*
Y-96084D01*
X248185Y-95792D01*
X248621Y-96084D01*
Y-96667D01*
X248185Y-96959D01*
G01X258916Y-101626D02*
Y-109792D01*
X259790Y-111834D01*
X261100Y-113000D01*
X262628Y-113292D01*
X264156Y-113000D01*
X265466Y-111834D01*
X266340Y-109792D01*
G01Y-113292D02*
Y-101626D01*
G01X276853Y-111251D02*
X277945Y-112417D01*
X279473Y-113292D01*
X280783D01*
X282093Y-112709D01*
X282966Y-111834D01*
X283403Y-110668D01*
X283185Y-108917D01*
X282311Y-108042D01*
X278381Y-106292D01*
X277508Y-104250D01*
X277945Y-102792D01*
X278818Y-101917D01*
X280128Y-101626D01*
X281438Y-101917D01*
X282748Y-102792D01*
G01X297628Y-95792D02*
Y-113292D01*
G01X294571Y-101626D02*
X300685D01*
G01X331318Y-113292D02*
Y-98417D01*
X331755Y-96959D01*
X332628Y-96084D01*
X333938Y-95792D01*
X335248Y-96375D01*
X335903Y-97834D01*
G01X333283Y-102792D02*
X328916D01*
G01X350128Y-113292D02*
X348818Y-113000D01*
X347508Y-111834D01*
X346634Y-109792D01*
X346198Y-107459D01*
X346634Y-105125D01*
X347508Y-103084D01*
X348818Y-101917D01*
X350128Y-101626D01*
X351438Y-101917D01*
X352748Y-103084D01*
X353621Y-105125D01*
X353840Y-107459D01*
X353621Y-109792D01*
X352748Y-111834D01*
X351438Y-113000D01*
X350128Y-113292D01*
G01X364571D02*
Y-101626D01*
G01Y-103959D02*
X365663Y-102792D01*
X366755Y-101917D01*
X368283Y-101626D01*
X369374Y-101917D01*
X370685Y-102792D01*
G01X398043Y-118542D02*
X399353Y-119125D01*
X401100Y-118542D01*
X402191Y-117376D01*
X403065Y-115917D01*
X404374Y-111251D01*
X407213Y-101626D01*
G01X400226D02*
X404374Y-111251D01*
G01X420128Y-113292D02*
X418818Y-113000D01*
X417508Y-111834D01*
X416634Y-109792D01*
X416198Y-107459D01*
X416634Y-105125D01*
X417508Y-103084D01*
X418818Y-101917D01*
X420128Y-101626D01*
X421438Y-101917D01*
X422748Y-103084D01*
X423621Y-105125D01*
X423840Y-107459D01*
X423621Y-109792D01*
X422748Y-111834D01*
X421438Y-113000D01*
X420128Y-113292D01*
G01X433916Y-101626D02*
Y-109792D01*
X434790Y-111834D01*
X436100Y-113000D01*
X437628Y-113292D01*
X439156Y-113000D01*
X440466Y-111834D01*
X441340Y-109792D01*
G01Y-113292D02*
Y-101626D01*
G01X452071Y-113292D02*
Y-101626D01*
G01Y-103959D02*
X453163Y-102792D01*
X454255Y-101917D01*
X455783Y-101626D01*
X456874Y-101917D01*
X458185Y-102792D01*
G01X487071Y-113292D02*
Y-101626D01*
G01Y-103959D02*
X488163Y-102792D01*
X489255Y-101917D01*
X490783Y-101626D01*
X491874Y-101917D01*
X493185Y-102792D01*
G01X504353Y-105417D02*
X511340D01*
X510685Y-103375D01*
X509593Y-102209D01*
X508065Y-101626D01*
X506536Y-101917D01*
X505226Y-102792D01*
X504353Y-104834D01*
X503916Y-106584D01*
Y-108334D01*
X504353Y-110084D01*
X505445Y-111834D01*
X506755Y-113000D01*
X508283Y-113292D01*
X509811Y-112709D01*
X511340Y-110959D01*
G01X523818Y-113292D02*
Y-98417D01*
X524255Y-96959D01*
X525128Y-96084D01*
X526438Y-95792D01*
X527748Y-96375D01*
X528403Y-97834D01*
G01X525783Y-102792D02*
X521416D01*
G01X539353Y-105417D02*
X546340D01*
X545685Y-103375D01*
X544593Y-102209D01*
X543065Y-101626D01*
X541536Y-101917D01*
X540226Y-102792D01*
X539353Y-104834D01*
X538916Y-106584D01*
Y-108334D01*
X539353Y-110084D01*
X540445Y-111834D01*
X541755Y-113000D01*
X543283Y-113292D01*
X544811Y-112709D01*
X546340Y-110959D01*
G01X557071Y-113292D02*
Y-101626D01*
G01Y-103959D02*
X558163Y-102792D01*
X559255Y-101917D01*
X560783Y-101626D01*
X561874Y-101917D01*
X563185Y-102792D01*
G01X574353Y-105417D02*
X581340D01*
X580685Y-103375D01*
X579593Y-102209D01*
X578065Y-101626D01*
X576536Y-101917D01*
X575226Y-102792D01*
X574353Y-104834D01*
X573916Y-106584D01*
Y-108334D01*
X574353Y-110084D01*
X575445Y-111834D01*
X576755Y-113000D01*
X578283Y-113292D01*
X579811Y-112709D01*
X581340Y-110959D01*
G01X591416Y-113292D02*
Y-101626D01*
G01Y-104542D02*
X592290Y-103084D01*
X593600Y-101917D01*
X595346Y-101626D01*
X596874Y-101917D01*
X598185Y-103084D01*
X598840Y-105125D01*
Y-113292D01*
G01X616121Y-103084D02*
X614593Y-101917D01*
X613283Y-101626D01*
X611536Y-102209D01*
X610226Y-103375D01*
X609353Y-105417D01*
X609134Y-107459D01*
X609353Y-109501D01*
X610226Y-111251D01*
X611536Y-112709D01*
X613283Y-113292D01*
X614811Y-112709D01*
X616121Y-111542D01*
G01X626853Y-105417D02*
X633840D01*
X633185Y-103375D01*
X632093Y-102209D01*
X630565Y-101626D01*
X629036Y-101917D01*
X627726Y-102792D01*
X626853Y-104834D01*
X626416Y-106584D01*
Y-108334D01*
X626853Y-110084D01*
X627945Y-111834D01*
X629255Y-113000D01*
X630783Y-113292D01*
X632311Y-112709D01*
X633840Y-110959D01*
G01X665128Y-95792D02*
Y-113292D01*
G01X662071Y-101626D02*
X668185D01*
G01X682628Y-113292D02*
X681318Y-113000D01*
X680008Y-111834D01*
X679134Y-109792D01*
X678698Y-107459D01*
X679134Y-105125D01*
X680008Y-103084D01*
X681318Y-101917D01*
X682628Y-101626D01*
X683938Y-101917D01*
X685248Y-103084D01*
X686121Y-105125D01*
X686340Y-107459D01*
X686121Y-109792D01*
X685248Y-111834D01*
X683938Y-113000D01*
X682628Y-113292D01*
G01X716318D02*
Y-98417D01*
X716755Y-96959D01*
X717628Y-96084D01*
X718938Y-95792D01*
X720248Y-96375D01*
X720903Y-97834D01*
G01X718283Y-102792D02*
X713916D01*
G01X735128Y-101626D02*
Y-113292D01*
G01Y-96959D02*
X734691Y-96667D01*
Y-96084D01*
X735128Y-95792D01*
X735565Y-96084D01*
Y-96667D01*
X735128Y-96959D01*
G01X748916Y-113292D02*
Y-101626D01*
G01Y-104542D02*
X749790Y-103084D01*
X751100Y-101917D01*
X752846Y-101626D01*
X754374Y-101917D01*
X755685Y-103084D01*
X756340Y-105125D01*
Y-113292D01*
G01X774058Y-95792D02*
Y-113292D01*
G01Y-110668D02*
X773185Y-112126D01*
X771874Y-113000D01*
X770346Y-113292D01*
X768600Y-112709D01*
X767290Y-111251D01*
X766416Y-109501D01*
X766198Y-107459D01*
X766416Y-105417D01*
X767290Y-103667D01*
X768600Y-102209D01*
X770346Y-101626D01*
X771874Y-101917D01*
X772966Y-102501D01*
X774058Y-103667D01*
G01X805128Y-95792D02*
Y-113292D01*
G01X802071Y-101626D02*
X808185D01*
G01X818916Y-113292D02*
Y-95792D01*
G01Y-104250D02*
X820008Y-102792D01*
X821100Y-101917D01*
X822846Y-101626D01*
X824156Y-101917D01*
X825685Y-103084D01*
X826340Y-104834D01*
Y-113292D01*
G01X836853Y-105417D02*
X843840D01*
X843185Y-103375D01*
X842093Y-102209D01*
X840565Y-101626D01*
X839036Y-101917D01*
X837726Y-102792D01*
X836853Y-104834D01*
X836416Y-106584D01*
Y-108334D01*
X836853Y-110084D01*
X837945Y-111834D01*
X839255Y-113000D01*
X840783Y-113292D01*
X842311Y-112709D01*
X843840Y-110959D01*
G01X870543D02*
X872290Y-112417D01*
X874255Y-113292D01*
X876001D01*
X877748Y-112417D01*
X879058Y-110959D01*
X879713Y-108917D01*
X879276Y-106876D01*
X878185Y-105125D01*
X876220Y-103959D01*
X873600Y-103375D01*
X872071Y-102209D01*
X871416Y-100167D01*
X871853Y-98125D01*
X872945Y-96667D01*
X874473Y-95792D01*
X876001D01*
X877530Y-96375D01*
X878840Y-97834D01*
G01X896995Y-113292D02*
X888261D01*
Y-95792D01*
X896995D01*
G01X893501Y-104250D02*
X888261D01*
G01X927628Y-101626D02*
Y-113292D01*
G01Y-96959D02*
X927191Y-96667D01*
Y-96084D01*
X927628Y-95792D01*
X928065Y-96084D01*
Y-96667D01*
X927628Y-96959D01*
G01X938578Y-113292D02*
Y-101626D01*
G01Y-104834D02*
X939233Y-103375D01*
X940325Y-102209D01*
X941853Y-101626D01*
X943381Y-102209D01*
X944473Y-103375D01*
X945128Y-104834D01*
Y-113292D01*
G01Y-104834D02*
X945783Y-103375D01*
X946874Y-102209D01*
X948403Y-101626D01*
X949931Y-102209D01*
X951023Y-103375D01*
X951678Y-105125D01*
Y-113292D01*
G01X958698Y-119125D02*
Y-101626D01*
G01Y-104250D02*
X959790Y-102792D01*
X960881Y-101917D01*
X962628Y-101626D01*
X964156Y-101917D01*
X965685Y-103375D01*
X966340Y-105417D01*
X966558Y-107459D01*
X966340Y-109501D01*
X965685Y-111542D01*
X964374Y-112709D01*
X962628Y-113292D01*
X961100Y-113000D01*
X959571Y-112126D01*
X958698Y-110959D01*
G01X976853Y-105417D02*
X983840D01*
X983185Y-103375D01*
X982093Y-102209D01*
X980565Y-101626D01*
X979036Y-101917D01*
X977726Y-102792D01*
X976853Y-104834D01*
X976416Y-106584D01*
Y-108334D01*
X976853Y-110084D01*
X977945Y-111834D01*
X979255Y-113000D01*
X980783Y-113292D01*
X982311Y-112709D01*
X983840Y-110959D01*
G01X1001558Y-95792D02*
Y-113292D01*
G01Y-110668D02*
X1000685Y-112126D01*
X999374Y-113000D01*
X997846Y-113292D01*
X996100Y-112709D01*
X994790Y-111251D01*
X993916Y-109501D01*
X993698Y-107459D01*
X993916Y-105417D01*
X994790Y-103667D01*
X996100Y-102209D01*
X997846Y-101626D01*
X999374Y-101917D01*
X1000466Y-102501D01*
X1001558Y-103667D01*
G01X1019058Y-113292D02*
Y-101626D01*
G01Y-103667D02*
X1018185Y-102501D01*
X1016874Y-101917D01*
X1015346Y-101626D01*
X1013818Y-102209D01*
X1012508Y-103375D01*
X1011634Y-105125D01*
X1011198Y-107459D01*
X1011634Y-109792D01*
X1012508Y-111542D01*
X1013818Y-112709D01*
X1015346Y-113292D01*
X1016874Y-113000D01*
X1018185Y-112126D01*
X1019058Y-110959D01*
G01X1028916Y-113292D02*
Y-101626D01*
G01Y-104542D02*
X1029790Y-103084D01*
X1031100Y-101917D01*
X1032846Y-101626D01*
X1034374Y-101917D01*
X1035685Y-103084D01*
X1036340Y-105125D01*
Y-113292D01*
G01X1053621Y-103084D02*
X1052093Y-101917D01*
X1050783Y-101626D01*
X1049036Y-102209D01*
X1047726Y-103375D01*
X1046853Y-105417D01*
X1046634Y-107459D01*
X1046853Y-109501D01*
X1047726Y-111251D01*
X1049036Y-112709D01*
X1050783Y-113292D01*
X1052311Y-112709D01*
X1053621Y-111542D01*
G01X1064353Y-105417D02*
X1071340D01*
X1070685Y-103375D01*
X1069593Y-102209D01*
X1068065Y-101626D01*
X1066536Y-101917D01*
X1065226Y-102792D01*
X1064353Y-104834D01*
X1063916Y-106584D01*
Y-108334D01*
X1064353Y-110084D01*
X1065445Y-111834D01*
X1066755Y-113000D01*
X1068283Y-113292D01*
X1069811Y-112709D01*
X1071340Y-110959D01*
G01X1102628Y-95792D02*
Y-113292D01*
G01X1099571Y-101626D02*
X1105685D01*
G01X1117071Y-113292D02*
Y-101626D01*
G01Y-103959D02*
X1118163Y-102792D01*
X1119255Y-101917D01*
X1120783Y-101626D01*
X1121874Y-101917D01*
X1123185Y-102792D01*
G01X1141558Y-113292D02*
Y-101626D01*
G01Y-103667D02*
X1140685Y-102501D01*
X1139374Y-101917D01*
X1137846Y-101626D01*
X1136318Y-102209D01*
X1135008Y-103375D01*
X1134134Y-105125D01*
X1133698Y-107459D01*
X1134134Y-109792D01*
X1135008Y-111542D01*
X1136318Y-112709D01*
X1137846Y-113292D01*
X1139374Y-113000D01*
X1140685Y-112126D01*
X1141558Y-110959D01*
G01X1158621Y-103084D02*
X1157093Y-101917D01*
X1155783Y-101626D01*
X1154036Y-102209D01*
X1152726Y-103375D01*
X1151853Y-105417D01*
X1151634Y-107459D01*
X1151853Y-109501D01*
X1152726Y-111251D01*
X1154036Y-112709D01*
X1155783Y-113292D01*
X1157311Y-112709D01*
X1158621Y-111542D01*
G01X1169353Y-105417D02*
X1176340D01*
X1175685Y-103375D01*
X1174593Y-102209D01*
X1173065Y-101626D01*
X1171536Y-101917D01*
X1170226Y-102792D01*
X1169353Y-104834D01*
X1168916Y-106584D01*
Y-108334D01*
X1169353Y-110084D01*
X1170445Y-111834D01*
X1171755Y-113000D01*
X1173283Y-113292D01*
X1174811Y-112709D01*
X1176340Y-110959D01*
G01X1186853Y-111251D02*
X1187945Y-112417D01*
X1189473Y-113292D01*
X1190783D01*
X1192093Y-112709D01*
X1192966Y-111834D01*
X1193403Y-110668D01*
X1193185Y-108917D01*
X1192311Y-108042D01*
X1188381Y-106292D01*
X1187508Y-104250D01*
X1187945Y-102792D01*
X1188818Y-101917D01*
X1190128Y-101626D01*
X1191438Y-101917D01*
X1192748Y-102792D01*
G01X1225128Y-101626D02*
Y-113292D01*
G01Y-96959D02*
X1224691Y-96667D01*
Y-96084D01*
X1225128Y-95792D01*
X1225565Y-96084D01*
Y-96667D01*
X1225128Y-96959D01*
G01X1238916Y-113292D02*
Y-101626D01*
G01Y-104542D02*
X1239790Y-103084D01*
X1241100Y-101917D01*
X1242846Y-101626D01*
X1244374Y-101917D01*
X1245685Y-103084D01*
X1246340Y-105125D01*
Y-113292D01*
G01X1277628D02*
Y-95792D01*
G01X1299058Y-113292D02*
Y-101626D01*
G01Y-103667D02*
X1298185Y-102501D01*
X1296874Y-101917D01*
X1295346Y-101626D01*
X1293818Y-102209D01*
X1292508Y-103375D01*
X1291634Y-105125D01*
X1291198Y-107459D01*
X1291634Y-109792D01*
X1292508Y-111542D01*
X1293818Y-112709D01*
X1295346Y-113292D01*
X1296874Y-113000D01*
X1298185Y-112126D01*
X1299058Y-110959D01*
G01X1308043Y-118542D02*
X1309353Y-119125D01*
X1311100Y-118542D01*
X1312191Y-117376D01*
X1313065Y-115917D01*
X1314374Y-111251D01*
X1317213Y-101626D01*
G01X1310226D02*
X1314374Y-111251D01*
G01X1326853Y-105417D02*
X1333840D01*
X1333185Y-103375D01*
X1332093Y-102209D01*
X1330565Y-101626D01*
X1329036Y-101917D01*
X1327726Y-102792D01*
X1326853Y-104834D01*
X1326416Y-106584D01*
Y-108334D01*
X1326853Y-110084D01*
X1327945Y-111834D01*
X1329255Y-113000D01*
X1330783Y-113292D01*
X1332311Y-112709D01*
X1333840Y-110959D01*
G01X1344571Y-113292D02*
Y-101626D01*
G01Y-103959D02*
X1345663Y-102792D01*
X1346755Y-101917D01*
X1348283Y-101626D01*
X1349374Y-101917D01*
X1350685Y-102792D01*
G01X1378261Y-95792D02*
Y-113292D01*
X1386995D01*
G01X1400128D02*
Y-95792D01*
X1397508Y-99292D01*
G01Y-113292D02*
X1402748D01*
G01X1417628Y-95792D02*
X1415881Y-96375D01*
X1414571Y-97834D01*
X1413698Y-99583D01*
X1413043Y-101917D01*
X1412825Y-104542D01*
X1413043Y-107167D01*
X1413698Y-109501D01*
X1414571Y-111251D01*
X1415881Y-112709D01*
X1417628Y-113292D01*
X1419374Y-112709D01*
X1420685Y-111251D01*
X1421558Y-109501D01*
X1422213Y-107167D01*
X1422431Y-104542D01*
X1422213Y-101917D01*
X1421558Y-99583D01*
X1420685Y-97834D01*
X1419374Y-96375D01*
X1417628Y-95792D01*
G01X1435128Y-113875D02*
X1434691Y-113584D01*
Y-113000D01*
X1435128Y-112709D01*
X1435565Y-113000D01*
Y-113584D01*
X1435128Y-113875D01*
G01X2083125Y539822D02*
X2084434Y538364D01*
X2085963Y537490D01*
X2087928Y537198D01*
X2089893Y537781D01*
X2091421Y538948D01*
X2092513Y540989D01*
X2092731Y543323D01*
X2092295Y545656D01*
X2091203Y547115D01*
X2089674Y548281D01*
X2088146Y548573D01*
X2086618Y548281D01*
X2084653Y547115D01*
X2085308Y554698D01*
X2091203D01*
G01X2105428D02*
X2103681Y554115D01*
X2102371Y552656D01*
X2101498Y550907D01*
X2100843Y548573D01*
X2100625Y545948D01*
X2100843Y543323D01*
X2101498Y540989D01*
X2102371Y539239D01*
X2103681Y537781D01*
X2105428Y537198D01*
X2107174Y537781D01*
X2108485Y539239D01*
X2109358Y540989D01*
X2110013Y543323D01*
X2110231Y545948D01*
X2110013Y548573D01*
X2109358Y550907D01*
X2108485Y552656D01*
X2107174Y554115D01*
X2105428Y554698D01*
G01X2122928Y536615D02*
X2122491Y536906D01*
Y537490D01*
X2122928Y537781D01*
X2123365Y537490D01*
Y536906D01*
X2122928Y536615D01*
G01X2140428Y554698D02*
X2138681Y554115D01*
X2137371Y552656D01*
X2136498Y550907D01*
X2135843Y548573D01*
X2135625Y545948D01*
X2135843Y543323D01*
X2136498Y540989D01*
X2137371Y539239D01*
X2138681Y537781D01*
X2140428Y537198D01*
X2142174Y537781D01*
X2143485Y539239D01*
X2144358Y540989D01*
X2145013Y543323D01*
X2145231Y545948D01*
X2145013Y548573D01*
X2144358Y550907D01*
X2143485Y552656D01*
X2142174Y554115D01*
X2140428Y554698D01*
G01X2090548Y571848D02*
Y589348D01*
X2082469Y576806D01*
X2093387D01*
G01X2105428Y589348D02*
X2103681Y588765D01*
X2102371Y587306D01*
X2101498Y585557D01*
X2100843Y583223D01*
X2100625Y580598D01*
X2100843Y577973D01*
X2101498Y575639D01*
X2102371Y573889D01*
X2103681Y572431D01*
X2105428Y571848D01*
X2107174Y572431D01*
X2108485Y573889D01*
X2109358Y575639D01*
X2110013Y577973D01*
X2110231Y580598D01*
X2110013Y583223D01*
X2109358Y585557D01*
X2108485Y587306D01*
X2107174Y588765D01*
X2105428Y589348D01*
G01X2122928Y571265D02*
X2122491Y571556D01*
Y572140D01*
X2122928Y572431D01*
X2123365Y572140D01*
Y571556D01*
X2122928Y571265D01*
G01X2140428Y589348D02*
X2138681Y588765D01*
X2137371Y587306D01*
X2136498Y585557D01*
X2135843Y583223D01*
X2135625Y580598D01*
X2135843Y577973D01*
X2136498Y575639D01*
X2137371Y573889D01*
X2138681Y572431D01*
X2140428Y571848D01*
X2142174Y572431D01*
X2143485Y573889D01*
X2144358Y575639D01*
X2145013Y577973D01*
X2145231Y580598D01*
X2145013Y583223D01*
X2144358Y585557D01*
X2143485Y587306D01*
X2142174Y588765D01*
X2140428Y589348D01*
G01X2050308Y623998D02*
X2055548D01*
G01X2052928D02*
Y606498D01*
G01X2050308D02*
X2055548D01*
G01X2064751D02*
Y623998D01*
X2070428Y609415D01*
X2076105Y623998D01*
Y606498D01*
G01X2083561D02*
Y623998D01*
X2088801D01*
X2090548Y623123D01*
X2091858Y621081D01*
X2092295Y618748D01*
X2091858Y616415D01*
X2090766Y614665D01*
X2088801Y613789D01*
X2083561D01*
G01X2104336Y600665D02*
X2102153Y603581D01*
X2101061Y606498D01*
Y618164D01*
X2102153Y621081D01*
X2104336Y623998D01*
G01X2122928Y606498D02*
X2121181Y606790D01*
X2119653Y607956D01*
X2118343Y609706D01*
X2117469Y611748D01*
X2117033Y614081D01*
Y616415D01*
X2117469Y618748D01*
X2118343Y620790D01*
X2119653Y622539D01*
X2121181Y623706D01*
X2122928Y623998D01*
X2124674Y623706D01*
X2126203Y622539D01*
X2127513Y620790D01*
X2128387Y618748D01*
X2128823Y616415D01*
Y614081D01*
X2128387Y611748D01*
X2127513Y609706D01*
X2126203Y607956D01*
X2124674Y606790D01*
X2122928Y606498D01*
G01X2136716D02*
Y623998D01*
G01Y615540D02*
X2137808Y616998D01*
X2138900Y617873D01*
X2140646Y618164D01*
X2141956Y617873D01*
X2143485Y616706D01*
X2144140Y614956D01*
Y606498D01*
G01X2151378D02*
Y618164D01*
G01Y614956D02*
X2152033Y616415D01*
X2153125Y617581D01*
X2154653Y618164D01*
X2156181Y617581D01*
X2157273Y616415D01*
X2157928Y614956D01*
Y606498D01*
G01Y614956D02*
X2158583Y616415D01*
X2159674Y617581D01*
X2161203Y618164D01*
X2162731Y617581D01*
X2163823Y616415D01*
X2164478Y614665D01*
Y606498D01*
G01X2176520Y600665D02*
X2178703Y603581D01*
X2179795Y606498D01*
Y618164D01*
X2178703Y621081D01*
X2176520Y623998D01*
G01X2028643Y643481D02*
X2030390Y642023D01*
X2032355Y641148D01*
X2034101D01*
X2035848Y642023D01*
X2037158Y643481D01*
X2037813Y645523D01*
X2037376Y647564D01*
X2036285Y649315D01*
X2034320Y650481D01*
X2031700Y651065D01*
X2030171Y652231D01*
X2029516Y654273D01*
X2029953Y656315D01*
X2031045Y657773D01*
X2032573Y658648D01*
X2034101D01*
X2035630Y658065D01*
X2036940Y656606D01*
G01X2055095Y641148D02*
X2046361D01*
Y658648D01*
X2055095D01*
G01X2051601Y650190D02*
X2046361D01*
G01X2083108Y658648D02*
X2088348D01*
G01X2085728D02*
Y641148D01*
G01X2083108D02*
X2088348D01*
G01X2097551D02*
Y658648D01*
X2103228Y644065D01*
X2108905Y658648D01*
Y641148D01*
G01X2116361D02*
Y658648D01*
X2121601D01*
X2123348Y657773D01*
X2124658Y655731D01*
X2125095Y653398D01*
X2124658Y651065D01*
X2123566Y649315D01*
X2121601Y648439D01*
X2116361D01*
G01X2142595Y641148D02*
X2133861D01*
Y658648D01*
X2142595D01*
G01X2139101Y650190D02*
X2133861D01*
G01X2150925Y641148D02*
Y658648D01*
X2155291D01*
X2157038Y657773D01*
X2158348Y656606D01*
X2159440Y654857D01*
X2160313Y652814D01*
X2160531Y649898D01*
X2160313Y646981D01*
X2159440Y644939D01*
X2158348Y643189D01*
X2157038Y642023D01*
X2155291Y641148D01*
X2150925D01*
G01X2167769D02*
X2173228Y658648D01*
X2178687Y641148D01*
G01X2176721Y647273D02*
X2169734D01*
G01X2185706Y641148D02*
Y658648D01*
X2195750Y641148D01*
Y658648D01*
G01X2213031Y657189D02*
X2211721Y658065D01*
X2210193Y658648D01*
X2208446D01*
X2206481Y657773D01*
X2204953Y656315D01*
X2203861Y654564D01*
X2202988Y651648D01*
X2202769Y649023D01*
X2203206Y646398D01*
X2203861Y644648D01*
X2205171Y642898D01*
X2206700Y641731D01*
X2208228Y641148D01*
X2209756D01*
X2211285Y641731D01*
X2212595Y642606D01*
X2213687Y643772D01*
G01X2230095Y641148D02*
X2221361D01*
Y658648D01*
X2230095D01*
G01X2226601Y650190D02*
X2221361D01*
G01X2260728Y658648D02*
Y641148D01*
G01X2255706Y658648D02*
X2265750D01*
G01X2272769Y641148D02*
X2278228Y658648D01*
X2283687Y641148D01*
G01X2281721Y647273D02*
X2274734D01*
G01X2297474Y650481D02*
X2298348Y651356D01*
X2299003Y652814D01*
X2299440Y654857D01*
X2299003Y656606D01*
X2298130Y657773D01*
X2296601Y658648D01*
X2290706D01*
Y641148D01*
X2297911D01*
X2299440Y642314D01*
X2300313Y644065D01*
X2300750Y646106D01*
X2300313Y648148D01*
X2299003Y649898D01*
X2297474Y650481D01*
X2290706D01*
G01X2308861Y658648D02*
Y641148D01*
X2317595D01*
G01X2335095D02*
X2326361D01*
Y658648D01*
X2335095D01*
G01X2331601Y650190D02*
X2326361D01*
G01X2348228Y640565D02*
X2347791Y640856D01*
Y641440D01*
X2348228Y641731D01*
X2348665Y641440D01*
Y640856D01*
X2348228Y640565D01*
G01Y648439D02*
X2347791Y648731D01*
Y649315D01*
X2348228Y649606D01*
X2348665Y649315D01*
Y648731D01*
X2348228Y648439D01*
G01X2378861Y658648D02*
Y641148D01*
X2387595D01*
G01X2400728D02*
Y658648D01*
X2398108Y655148D01*
G01Y641148D02*
X2403348D01*
G01X2418228Y658648D02*
X2416481Y658065D01*
X2415171Y656606D01*
X2414298Y654857D01*
X2413643Y652523D01*
X2413425Y649898D01*
X2413643Y647273D01*
X2414298Y644939D01*
X2415171Y643189D01*
X2416481Y641731D01*
X2418228Y641148D01*
X2419974Y641731D01*
X2421285Y643189D01*
X2422158Y644939D01*
X2422813Y647273D01*
X2423031Y649898D01*
X2422813Y652523D01*
X2422158Y654857D01*
X2421285Y656606D01*
X2419974Y658065D01*
X2418228Y658648D01*
G01X2238878Y623998D02*
X2241934Y606498D01*
X2245428Y623998D01*
X2248921Y606498D01*
X2251978Y623998D01*
G01X2260308D02*
X2265548D01*
G01X2262928D02*
Y606498D01*
G01X2260308D02*
X2265548D01*
G01X2275625D02*
Y623998D01*
X2279991D01*
X2281738Y623123D01*
X2283048Y621956D01*
X2284140Y620207D01*
X2285013Y618164D01*
X2285231Y615248D01*
X2285013Y612331D01*
X2284140Y610289D01*
X2283048Y608539D01*
X2281738Y607373D01*
X2279991Y606498D01*
X2275625D01*
G01X2297928Y623998D02*
Y606498D01*
G01X2292906Y623998D02*
X2302950D01*
G01X2310843Y606498D02*
Y623998D01*
G01X2320013D02*
Y606498D01*
G01Y615248D02*
X2310843D01*
G01X2331836Y600665D02*
X2329653Y603581D01*
X2328561Y606498D01*
Y618164D01*
X2329653Y621081D01*
X2331836Y623998D01*
G01X2343878Y606498D02*
Y618164D01*
G01Y614956D02*
X2344533Y616415D01*
X2345625Y617581D01*
X2347153Y618164D01*
X2348681Y617581D01*
X2349773Y616415D01*
X2350428Y614956D01*
Y606498D01*
G01Y614956D02*
X2351083Y616415D01*
X2352174Y617581D01*
X2353703Y618164D01*
X2355231Y617581D01*
X2356323Y616415D01*
X2356978Y614665D01*
Y606498D01*
G01X2367928Y618164D02*
Y606498D01*
G01Y622831D02*
X2367491Y623123D01*
Y623706D01*
X2367928Y623998D01*
X2368365Y623706D01*
Y623123D01*
X2367928Y622831D01*
G01X2385428Y606498D02*
Y623998D01*
G01X2399653Y608539D02*
X2400745Y607373D01*
X2402273Y606498D01*
X2403583D01*
X2404893Y607081D01*
X2405766Y607956D01*
X2406203Y609122D01*
X2405985Y610873D01*
X2405111Y611748D01*
X2401181Y613498D01*
X2400308Y615540D01*
X2400745Y616998D01*
X2401618Y617873D01*
X2402928Y618164D01*
X2404238Y617873D01*
X2405548Y616998D01*
G01X2421520Y600665D02*
X2423703Y603581D01*
X2424795Y606498D01*
Y618164D01*
X2423703Y621081D01*
X2421520Y623998D01*
G01X2301875Y540698D02*
X2303184Y538656D01*
X2304931Y537490D01*
X2306896Y537198D01*
X2308643Y537490D01*
X2310390Y538948D01*
X2311481Y540698D01*
X2311700Y542448D01*
X2311263Y544489D01*
X2309735Y545948D01*
X2308206Y546531D01*
X2306241D01*
G01X2308206D02*
X2309516Y547406D01*
X2310608Y548864D01*
X2311045Y550614D01*
X2310608Y552365D01*
X2309516Y553823D01*
X2307551Y554698D01*
X2305586Y554406D01*
X2303621Y553239D01*
G01X2324178Y536615D02*
X2323741Y536906D01*
Y537490D01*
X2324178Y537781D01*
X2324615Y537490D01*
Y536906D01*
X2324178Y536615D01*
G01X2336875Y539822D02*
X2338184Y538364D01*
X2339713Y537490D01*
X2341678Y537198D01*
X2343643Y537781D01*
X2345171Y538948D01*
X2346263Y540989D01*
X2346481Y543323D01*
X2346045Y545656D01*
X2344953Y547115D01*
X2343424Y548281D01*
X2341896Y548573D01*
X2340368Y548281D01*
X2338403Y547115D01*
X2339058Y554698D01*
X2344953D01*
G01X2355030Y551781D02*
X2356340Y553531D01*
X2357868Y554406D01*
X2359615Y554698D01*
X2361798Y554115D01*
X2363326Y552656D01*
X2363763Y550907D01*
X2363545Y549156D01*
X2362671Y547698D01*
X2358305Y544781D01*
X2356340Y542740D01*
X2355030Y539822D01*
X2354593Y537198D01*
X2363763D01*
G01X2310625Y574472D02*
X2311934Y573014D01*
X2313463Y572140D01*
X2315428Y571848D01*
X2317393Y572431D01*
X2318921Y573598D01*
X2320013Y575639D01*
X2320231Y577973D01*
X2319795Y580306D01*
X2318703Y581765D01*
X2317174Y582931D01*
X2315646Y583223D01*
X2314118Y582931D01*
X2312153Y581765D01*
X2312808Y589348D01*
X2318703D01*
G01X2332928Y571265D02*
X2332491Y571556D01*
Y572140D01*
X2332928Y572431D01*
X2333365Y572140D01*
Y571556D01*
X2332928Y571265D01*
G01X2346280Y579139D02*
X2347808Y581181D01*
X2349118Y582348D01*
X2350865Y582931D01*
X2352393Y582348D01*
X2353485Y581181D01*
X2354358Y579431D01*
X2354576Y577390D01*
X2354358Y575639D01*
X2353485Y573889D01*
X2352174Y572431D01*
X2350646Y571848D01*
X2348900Y572431D01*
X2347371Y574181D01*
X2346498Y576806D01*
X2346280Y579723D01*
X2346716Y583514D01*
X2347371Y585557D01*
X2348463Y587598D01*
X2349991Y589056D01*
X2351520Y589348D01*
X2353048Y588765D01*
X2354140Y587306D01*
G01X2503343Y539531D02*
X2505090Y538073D01*
X2507055Y537198D01*
X2508801D01*
X2510548Y538073D01*
X2511858Y539531D01*
X2512513Y541573D01*
X2512076Y543614D01*
X2510985Y545365D01*
X2509020Y546531D01*
X2506400Y547115D01*
X2504871Y548281D01*
X2504216Y550323D01*
X2504653Y552365D01*
X2505745Y553823D01*
X2507273Y554698D01*
X2508801D01*
X2510330Y554115D01*
X2511640Y552656D01*
G01X2529795Y537198D02*
X2521061D01*
Y554698D01*
X2529795D01*
G01X2526301Y546240D02*
X2521061D01*
G01X2503343Y574181D02*
X2505090Y572723D01*
X2507055Y571848D01*
X2508801D01*
X2510548Y572723D01*
X2511858Y574181D01*
X2512513Y576223D01*
X2512076Y578264D01*
X2510985Y580015D01*
X2509020Y581181D01*
X2506400Y581765D01*
X2504871Y582931D01*
X2504216Y584973D01*
X2504653Y587015D01*
X2505745Y588473D01*
X2507273Y589348D01*
X2508801D01*
X2510330Y588765D01*
X2511640Y587306D01*
G01X2529795Y571848D02*
X2521061D01*
Y589348D01*
X2529795D01*
G01X2526301Y580890D02*
X2521061D01*
G01X2490428Y623998D02*
Y606498D01*
G01X2485406Y623998D02*
X2495450D01*
G01X2507928Y606498D02*
Y614373D01*
X2503561Y623998D01*
G01X2512295D02*
X2507928Y614373D01*
G01X2521061Y606498D02*
Y623998D01*
X2526301D01*
X2528048Y623123D01*
X2529358Y621081D01*
X2529795Y618748D01*
X2529358Y616415D01*
X2528266Y614665D01*
X2526301Y613789D01*
X2521061D01*
G01X2547295Y606498D02*
X2538561D01*
Y623998D01*
X2547295D01*
G01X2543801Y615540D02*
X2538561D01*
G01X2626061Y554698D02*
Y537198D01*
X2634795D01*
G01X2644216Y539239D02*
X2645745Y537781D01*
X2647491Y537198D01*
X2649238Y537781D01*
X2650766Y539531D01*
X2651858Y542156D01*
X2652295Y544781D01*
Y547989D01*
X2651858Y550614D01*
X2650766Y552948D01*
X2649456Y554115D01*
X2647928Y554698D01*
X2646181Y554115D01*
X2644871Y552948D01*
X2643998Y551198D01*
X2643561Y548864D01*
X2643998Y546823D01*
X2645090Y544781D01*
X2646400Y543614D01*
X2647928Y543323D01*
X2649674Y543906D01*
X2650985Y545365D01*
X2652295Y547989D01*
G01X2661498Y536615D02*
X2669358Y554698D01*
G01X2678561D02*
Y537198D01*
X2687295D01*
G01X2700428D02*
Y554698D01*
X2697808Y551198D01*
G01Y537198D02*
X2703048D01*
G01X2717928D02*
Y554698D01*
X2715308Y551198D01*
G01Y537198D02*
X2720548D01*
G01X2626061Y589348D02*
Y571848D01*
X2634795D01*
G01X2644216Y573889D02*
X2645745Y572431D01*
X2647491Y571848D01*
X2649238Y572431D01*
X2650766Y574181D01*
X2651858Y576806D01*
X2652295Y579431D01*
Y582639D01*
X2651858Y585264D01*
X2650766Y587598D01*
X2649456Y588765D01*
X2647928Y589348D01*
X2646181Y588765D01*
X2644871Y587598D01*
X2643998Y585848D01*
X2643561Y583514D01*
X2643998Y581473D01*
X2645090Y579431D01*
X2646400Y578264D01*
X2647928Y577973D01*
X2649674Y578556D01*
X2650985Y580015D01*
X2652295Y582639D01*
G01X2661498Y571265D02*
X2669358Y589348D01*
G01X2678561D02*
Y571848D01*
X2687295D01*
G01X2700428D02*
Y589348D01*
X2697808Y585848D01*
G01Y571848D02*
X2703048D01*
G01X2717928D02*
Y589348D01*
X2715308Y585848D01*
G01Y571848D02*
X2720548D01*
G01X2591061Y606498D02*
Y623998D01*
X2596520D01*
X2598266Y623123D01*
X2599358Y621956D01*
X2599795Y619623D01*
X2599358Y617289D01*
X2598048Y615831D01*
X2596520Y614956D01*
X2591061D01*
G01X2596520D02*
X2599795Y606498D01*
G01X2609653Y614373D02*
X2616640D01*
X2615985Y616415D01*
X2614893Y617581D01*
X2613365Y618164D01*
X2611836Y617873D01*
X2610526Y616998D01*
X2609653Y614956D01*
X2609216Y613206D01*
Y611456D01*
X2609653Y609706D01*
X2610745Y607956D01*
X2612055Y606790D01*
X2613583Y606498D01*
X2615111Y607081D01*
X2616640Y608831D01*
G01X2629118Y606498D02*
Y621373D01*
X2629555Y622831D01*
X2630428Y623706D01*
X2631738Y623998D01*
X2633048Y623415D01*
X2633703Y621956D01*
G01X2631083Y616998D02*
X2626716D01*
G01X2647928Y605915D02*
X2647491Y606206D01*
Y606790D01*
X2647928Y607081D01*
X2648365Y606790D01*
Y606206D01*
X2647928Y605915D01*
G01X2678561Y606498D02*
Y623998D01*
X2683801D01*
X2685548Y623123D01*
X2686858Y621081D01*
X2687295Y618748D01*
X2686858Y616415D01*
X2685766Y614665D01*
X2683801Y613789D01*
X2678561D01*
G01X2700428Y606498D02*
Y623998D01*
G01X2721858Y606498D02*
Y618164D01*
G01Y616123D02*
X2720985Y617289D01*
X2719674Y617873D01*
X2718146Y618164D01*
X2716618Y617581D01*
X2715308Y616415D01*
X2714434Y614665D01*
X2713998Y612331D01*
X2714434Y609998D01*
X2715308Y608248D01*
X2716618Y607081D01*
X2718146Y606498D01*
X2719674Y606790D01*
X2720985Y607664D01*
X2721858Y608831D01*
G01X2731716Y606498D02*
Y618164D01*
G01Y615248D02*
X2732590Y616706D01*
X2733900Y617873D01*
X2735646Y618164D01*
X2737174Y617873D01*
X2738485Y616706D01*
X2739140Y614665D01*
Y606498D01*
G01X2749653Y614373D02*
X2756640D01*
X2755985Y616415D01*
X2754893Y617581D01*
X2753365Y618164D01*
X2751836Y617873D01*
X2750526Y616998D01*
X2749653Y614956D01*
X2749216Y613206D01*
Y611456D01*
X2749653Y609706D01*
X2750745Y607956D01*
X2752055Y606790D01*
X2753583Y606498D01*
X2755111Y607081D01*
X2756640Y608831D01*
G01X2870728Y548864D02*
Y537198D01*
G01Y553531D02*
X2870291Y553823D01*
Y554406D01*
X2870728Y554698D01*
X2871165Y554406D01*
Y553823D01*
X2870728Y553531D01*
G01X2884516Y537198D02*
Y548864D01*
G01Y545948D02*
X2885390Y547406D01*
X2886700Y548573D01*
X2888446Y548864D01*
X2889974Y548573D01*
X2891285Y547406D01*
X2891940Y545365D01*
Y537198D01*
G01X2902453Y539239D02*
X2903545Y538073D01*
X2905073Y537198D01*
X2906383D01*
X2907693Y537781D01*
X2908566Y538656D01*
X2909003Y539822D01*
X2908785Y541573D01*
X2907911Y542448D01*
X2903981Y544198D01*
X2903108Y546240D01*
X2903545Y547698D01*
X2904418Y548573D01*
X2905728Y548864D01*
X2907038Y548573D01*
X2908348Y547698D01*
G01X2923228Y548864D02*
Y537198D01*
G01Y553531D02*
X2922791Y553823D01*
Y554406D01*
X2923228Y554698D01*
X2923665Y554406D01*
Y553823D01*
X2923228Y553531D01*
G01X2944658Y554698D02*
Y537198D01*
G01Y539822D02*
X2943785Y538364D01*
X2942474Y537490D01*
X2940946Y537198D01*
X2939200Y537781D01*
X2937890Y539239D01*
X2937016Y540989D01*
X2936798Y543031D01*
X2937016Y545073D01*
X2937890Y546823D01*
X2939200Y548281D01*
X2940946Y548864D01*
X2942474Y548573D01*
X2943566Y547989D01*
X2944658Y546823D01*
G01X2954953Y545073D02*
X2961940D01*
X2961285Y547115D01*
X2960193Y548281D01*
X2958665Y548864D01*
X2957136Y548573D01*
X2955826Y547698D01*
X2954953Y545656D01*
X2954516Y543906D01*
Y542156D01*
X2954953Y540406D01*
X2956045Y538656D01*
X2957355Y537490D01*
X2958883Y537198D01*
X2960411Y537781D01*
X2961940Y539531D01*
G01X2989298Y537198D02*
Y554698D01*
G01Y545948D02*
X2990390Y547698D01*
X2991700Y548573D01*
X2993010Y548864D01*
X2994974Y548281D01*
X2996285Y547115D01*
X2997158Y545073D01*
Y542740D01*
X2996721Y540406D01*
X2995848Y538656D01*
X2994320Y537490D01*
X2993010Y537198D01*
X2991700Y537490D01*
X2990390Y538364D01*
X2989298Y539822D01*
G01X3010728Y537198D02*
X3009418Y537490D01*
X3008108Y538656D01*
X3007234Y540698D01*
X3006798Y543031D01*
X3007234Y545365D01*
X3008108Y547406D01*
X3009418Y548573D01*
X3010728Y548864D01*
X3012038Y548573D01*
X3013348Y547406D01*
X3014221Y545365D01*
X3014440Y543031D01*
X3014221Y540698D01*
X3013348Y538656D01*
X3012038Y537490D01*
X3010728Y537198D01*
G01X3032158D02*
Y548864D01*
G01Y546823D02*
X3031285Y547989D01*
X3029974Y548573D01*
X3028446Y548864D01*
X3026918Y548281D01*
X3025608Y547115D01*
X3024734Y545365D01*
X3024298Y543031D01*
X3024734Y540698D01*
X3025608Y538948D01*
X3026918Y537781D01*
X3028446Y537198D01*
X3029974Y537490D01*
X3031285Y538364D01*
X3032158Y539531D01*
G01X3042671Y537198D02*
Y548864D01*
G01Y546531D02*
X3043763Y547698D01*
X3044855Y548573D01*
X3046383Y548864D01*
X3047474Y548573D01*
X3048785Y547698D01*
G01X3067158Y554698D02*
Y537198D01*
G01Y539822D02*
X3066285Y538364D01*
X3064974Y537490D01*
X3063446Y537198D01*
X3061700Y537781D01*
X3060390Y539239D01*
X3059516Y540989D01*
X3059298Y543031D01*
X3059516Y545073D01*
X3060390Y546823D01*
X3061700Y548281D01*
X3063446Y548864D01*
X3064974Y548573D01*
X3066066Y547989D01*
X3067158Y546823D01*
G01X3098228Y537198D02*
X3096918Y537490D01*
X3095608Y538656D01*
X3094734Y540698D01*
X3094298Y543031D01*
X3094734Y545365D01*
X3095608Y547406D01*
X3096918Y548573D01*
X3098228Y548864D01*
X3099538Y548573D01*
X3100848Y547406D01*
X3101721Y545365D01*
X3101940Y543031D01*
X3101721Y540698D01*
X3100848Y538656D01*
X3099538Y537490D01*
X3098228Y537198D01*
G01X3112016Y548864D02*
Y540698D01*
X3112890Y538656D01*
X3114200Y537490D01*
X3115728Y537198D01*
X3117256Y537490D01*
X3118566Y538656D01*
X3119440Y540698D01*
G01Y537198D02*
Y548864D01*
G01X3133228Y554698D02*
Y537198D01*
G01X3130171Y548864D02*
X3136285D01*
G01X3150728Y537198D02*
Y554698D01*
G01X3168228Y548864D02*
Y537198D01*
G01Y553531D02*
X3167791Y553823D01*
Y554406D01*
X3168228Y554698D01*
X3168665Y554406D01*
Y553823D01*
X3168228Y553531D01*
G01X3182016Y537198D02*
Y548864D01*
G01Y545948D02*
X3182890Y547406D01*
X3184200Y548573D01*
X3185946Y548864D01*
X3187474Y548573D01*
X3188785Y547406D01*
X3189440Y545365D01*
Y537198D01*
G01X3199953Y545073D02*
X3206940D01*
X3206285Y547115D01*
X3205193Y548281D01*
X3203665Y548864D01*
X3202136Y548573D01*
X3200826Y547698D01*
X3199953Y545656D01*
X3199516Y543906D01*
Y542156D01*
X3199953Y540406D01*
X3201045Y538656D01*
X3202355Y537490D01*
X3203883Y537198D01*
X3205411Y537781D01*
X3206940Y539531D01*
G01X3220728Y536615D02*
X3220291Y536906D01*
Y537490D01*
X3220728Y537781D01*
X3221165Y537490D01*
Y536906D01*
X3220728Y536615D01*
G01X2870728Y583514D02*
Y571848D01*
G01Y588181D02*
X2870291Y588473D01*
Y589056D01*
X2870728Y589348D01*
X2871165Y589056D01*
Y588473D01*
X2870728Y588181D01*
G01X2884953Y573889D02*
X2886045Y572723D01*
X2887573Y571848D01*
X2888883D01*
X2890193Y572431D01*
X2891066Y573306D01*
X2891503Y574472D01*
X2891285Y576223D01*
X2890411Y577098D01*
X2886481Y578848D01*
X2885608Y580890D01*
X2886045Y582348D01*
X2886918Y583223D01*
X2888228Y583514D01*
X2889538Y583223D01*
X2890848Y582348D01*
G01X2918206Y571848D02*
Y589348D01*
X2928250Y571848D01*
Y589348D01*
G01X2940728Y571848D02*
X2938981Y572140D01*
X2937453Y573306D01*
X2936143Y575056D01*
X2935269Y577098D01*
X2934833Y579431D01*
Y581765D01*
X2935269Y584098D01*
X2936143Y586140D01*
X2937453Y587889D01*
X2938981Y589056D01*
X2940728Y589348D01*
X2942474Y589056D01*
X2944003Y587889D01*
X2945313Y586140D01*
X2946187Y584098D01*
X2946623Y581765D01*
Y579431D01*
X2946187Y577098D01*
X2945313Y575056D01*
X2944003Y573306D01*
X2942474Y572140D01*
X2940728Y571848D01*
G01X2958228Y589348D02*
Y571848D01*
G01X2953206Y589348D02*
X2963250D01*
G01X2989516Y583514D02*
Y575348D01*
X2990390Y573306D01*
X2991700Y572140D01*
X2993228Y571848D01*
X2994756Y572140D01*
X2996066Y573306D01*
X2996940Y575348D01*
G01Y571848D02*
Y583514D01*
G01X3007453Y573889D02*
X3008545Y572723D01*
X3010073Y571848D01*
X3011383D01*
X3012693Y572431D01*
X3013566Y573306D01*
X3014003Y574472D01*
X3013785Y576223D01*
X3012911Y577098D01*
X3008981Y578848D01*
X3008108Y580890D01*
X3008545Y582348D01*
X3009418Y583223D01*
X3010728Y583514D01*
X3012038Y583223D01*
X3013348Y582348D01*
G01X3024953Y579723D02*
X3031940D01*
X3031285Y581765D01*
X3030193Y582931D01*
X3028665Y583514D01*
X3027136Y583223D01*
X3025826Y582348D01*
X3024953Y580306D01*
X3024516Y578556D01*
Y576806D01*
X3024953Y575056D01*
X3026045Y573306D01*
X3027355Y572140D01*
X3028883Y571848D01*
X3030411Y572431D01*
X3031940Y574181D01*
G01X3049658Y589348D02*
Y571848D01*
G01Y574472D02*
X3048785Y573014D01*
X3047474Y572140D01*
X3045946Y571848D01*
X3044200Y572431D01*
X3042890Y573889D01*
X3042016Y575639D01*
X3041798Y577681D01*
X3042016Y579723D01*
X3042890Y581473D01*
X3044200Y582931D01*
X3045946Y583514D01*
X3047474Y583223D01*
X3048566Y582639D01*
X3049658Y581473D01*
G01X3080728Y583514D02*
Y571848D01*
G01Y588181D02*
X3080291Y588473D01*
Y589056D01*
X3080728Y589348D01*
X3081165Y589056D01*
Y588473D01*
X3080728Y588181D01*
G01X3094516Y571848D02*
Y583514D01*
G01Y580598D02*
X3095390Y582056D01*
X3096700Y583223D01*
X3098446Y583514D01*
X3099974Y583223D01*
X3101285Y582056D01*
X3101940Y580015D01*
Y571848D01*
G01X3133228Y589348D02*
Y571848D01*
G01X3130171Y583514D02*
X3136285D01*
G01X3147016Y571848D02*
Y589348D01*
G01Y580890D02*
X3148108Y582348D01*
X3149200Y583223D01*
X3150946Y583514D01*
X3152256Y583223D01*
X3153785Y582056D01*
X3154440Y580306D01*
Y571848D01*
G01X3168228Y583514D02*
Y571848D01*
G01Y588181D02*
X3167791Y588473D01*
Y589056D01*
X3168228Y589348D01*
X3168665Y589056D01*
Y588473D01*
X3168228Y588181D01*
G01X3182453Y573889D02*
X3183545Y572723D01*
X3185073Y571848D01*
X3186383D01*
X3187693Y572431D01*
X3188566Y573306D01*
X3189003Y574472D01*
X3188785Y576223D01*
X3187911Y577098D01*
X3183981Y578848D01*
X3183108Y580890D01*
X3183545Y582348D01*
X3184418Y583223D01*
X3185728Y583514D01*
X3187038Y583223D01*
X3188348Y582348D01*
G01X3220728Y571848D02*
Y589348D01*
G01X3242158Y571848D02*
Y583514D01*
G01Y581473D02*
X3241285Y582639D01*
X3239974Y583223D01*
X3238446Y583514D01*
X3236918Y582931D01*
X3235608Y581765D01*
X3234734Y580015D01*
X3234298Y577681D01*
X3234734Y575348D01*
X3235608Y573598D01*
X3236918Y572431D01*
X3238446Y571848D01*
X3239974Y572140D01*
X3241285Y573014D01*
X3242158Y574181D01*
G01X3251143Y566598D02*
X3252453Y566015D01*
X3254200Y566598D01*
X3255291Y567764D01*
X3256165Y569223D01*
X3257474Y573889D01*
X3260313Y583514D01*
G01X3253326D02*
X3257474Y573889D01*
G01X3269953Y579723D02*
X3276940D01*
X3276285Y581765D01*
X3275193Y582931D01*
X3273665Y583514D01*
X3272136Y583223D01*
X3270826Y582348D01*
X3269953Y580306D01*
X3269516Y578556D01*
Y576806D01*
X3269953Y575056D01*
X3271045Y573306D01*
X3272355Y572140D01*
X3273883Y571848D01*
X3275411Y572431D01*
X3276940Y574181D01*
G01X3287671Y571848D02*
Y583514D01*
G01Y581181D02*
X3288763Y582348D01*
X3289855Y583223D01*
X3291383Y583514D01*
X3292474Y583223D01*
X3293785Y582348D01*
G01X2795925Y605915D02*
X2805531Y618748D01*
G01X2800728Y621081D02*
Y603581D01*
G01X2805531Y605915D02*
X2795925Y618748D01*
G01X2794178Y612331D02*
X2807278D01*
G01X2832890D02*
X2838566D01*
G01X2865925Y606498D02*
Y623998D01*
X2870291D01*
X2872038Y623123D01*
X2873348Y621956D01*
X2874440Y620207D01*
X2875313Y618164D01*
X2875531Y615248D01*
X2875313Y612331D01*
X2874440Y610289D01*
X2873348Y608539D01*
X2872038Y607373D01*
X2870291Y606498D01*
X2865925D01*
G01X2884953Y614373D02*
X2891940D01*
X2891285Y616415D01*
X2890193Y617581D01*
X2888665Y618164D01*
X2887136Y617873D01*
X2885826Y616998D01*
X2884953Y614956D01*
X2884516Y613206D01*
Y611456D01*
X2884953Y609706D01*
X2886045Y607956D01*
X2887355Y606790D01*
X2888883Y606498D01*
X2890411Y607081D01*
X2891940Y608831D01*
G01X2902016Y606498D02*
Y618164D01*
G01Y615248D02*
X2902890Y616706D01*
X2904200Y617873D01*
X2905946Y618164D01*
X2907474Y617873D01*
X2908785Y616706D01*
X2909440Y614665D01*
Y606498D01*
G01X2923228D02*
X2921918Y606790D01*
X2920608Y607956D01*
X2919734Y609998D01*
X2919298Y612331D01*
X2919734Y614665D01*
X2920608Y616706D01*
X2921918Y617873D01*
X2923228Y618164D01*
X2924538Y617873D01*
X2925848Y616706D01*
X2926721Y614665D01*
X2926940Y612331D01*
X2926721Y609998D01*
X2925848Y607956D01*
X2924538Y606790D01*
X2923228Y606498D01*
G01X2940728Y623998D02*
Y606498D01*
G01X2937671Y618164D02*
X2943785D01*
G01X2954953Y614373D02*
X2961940D01*
X2961285Y616415D01*
X2960193Y617581D01*
X2958665Y618164D01*
X2957136Y617873D01*
X2955826Y616998D01*
X2954953Y614956D01*
X2954516Y613206D01*
Y611456D01*
X2954953Y609706D01*
X2956045Y607956D01*
X2957355Y606790D01*
X2958883Y606498D01*
X2960411Y607081D01*
X2961940Y608831D01*
G01X2972453Y608539D02*
X2973545Y607373D01*
X2975073Y606498D01*
X2976383D01*
X2977693Y607081D01*
X2978566Y607956D01*
X2979003Y609122D01*
X2978785Y610873D01*
X2977911Y611748D01*
X2973981Y613498D01*
X2973108Y615540D01*
X2973545Y616998D01*
X2974418Y617873D01*
X2975728Y618164D01*
X2977038Y617873D01*
X2978348Y616998D01*
G01X3010728Y623998D02*
Y606498D01*
G01X3007671Y618164D02*
X3013785D01*
G01X3024516Y606498D02*
Y623998D01*
G01Y615540D02*
X3025608Y616998D01*
X3026700Y617873D01*
X3028446Y618164D01*
X3029756Y617873D01*
X3031285Y616706D01*
X3031940Y614956D01*
Y606498D01*
G01X3049658D02*
Y618164D01*
G01Y616123D02*
X3048785Y617289D01*
X3047474Y617873D01*
X3045946Y618164D01*
X3044418Y617581D01*
X3043108Y616415D01*
X3042234Y614665D01*
X3041798Y612331D01*
X3042234Y609998D01*
X3043108Y608248D01*
X3044418Y607081D01*
X3045946Y606498D01*
X3047474Y606790D01*
X3048785Y607664D01*
X3049658Y608831D01*
G01X3063228Y623998D02*
Y606498D01*
G01X3060171Y618164D02*
X3066285D01*
G01X3091678Y623998D02*
X3094734Y606498D01*
X3098228Y623998D01*
X3101721Y606498D01*
X3104778Y623998D01*
G01X3113108D02*
X3118348D01*
G01X3115728D02*
Y606498D01*
G01X3113108D02*
X3118348D01*
G01X3128425D02*
Y623998D01*
X3132791D01*
X3134538Y623123D01*
X3135848Y621956D01*
X3136940Y620207D01*
X3137813Y618164D01*
X3138031Y615248D01*
X3137813Y612331D01*
X3136940Y610289D01*
X3135848Y608539D01*
X3134538Y607373D01*
X3132791Y606498D01*
X3128425D01*
G01X3150728Y623998D02*
Y606498D01*
G01X3145706Y623998D02*
X3155750D01*
G01X3163643Y606498D02*
Y623998D01*
G01X3172813D02*
Y606498D01*
G01Y615248D02*
X3163643D01*
G01X-7874Y-31496D02*
X-19685D01*
G01X-7874D02*
X-19685D01*
G01D02*
G03X-23622Y-35433I0J-3937D01*
G01D02*
Y-59055D01*
G01Y-35433D02*
Y-59055D01*
G01X-19685Y-31496D02*
G03X-23622Y-35433I0J-3937D01*
G01Y-59055D02*
G03X-19685Y-62992I3937J0D01*
G01D02*
X1972441D01*
G01X-19685D02*
X1972441D01*
G01X-23622Y-59055D02*
G03X-19685Y-62992I3937J0D01*
G01Y-23622D02*
X1972441D01*
G01X-19685D02*
X1972441D01*
G01X-19685D02*
X1972441D01*
G01X-19685D02*
X1972441D01*
G01X-23622Y622441D02*
Y-19685D01*
G01Y622441D02*
Y-19685D01*
G01Y622441D02*
Y-19685D01*
G01Y622441D02*
Y-19685D01*
G01D02*
G03X-19685Y-23622I3937J0D01*
G01X-23622Y-19685D02*
G03X-19685Y-23622I3937J0D01*
G01X-23622Y-19685D02*
G03X-19685Y-23622I3937J0D01*
G01X-23622Y-19685D02*
G03X-19685Y-23622I3937J0D01*
G01X1972441Y626378D02*
X-19685D01*
G01X1972441D02*
X-19685D01*
G01X1972441D02*
X-19685D01*
G01X1972441D02*
X-19685D01*
G01D02*
G03X-23622Y622441I0J-3937D01*
G01X-19685Y626378D02*
G03X-23622Y622441I0J-3937D01*
G01X-19685Y626378D02*
G03X-23622Y622441I0J-3937D01*
G01X-19685Y626378D02*
G03X-23622Y622441I0J-3937D01*
G01X-19685Y634252D02*
X-7874D01*
G01X-19685D02*
X-7874D01*
G01X-23622Y661811D02*
Y638189D01*
G01Y661811D02*
Y638189D01*
G01D02*
G03X-19685Y634252I3937J0D01*
G01X-23622Y638189D02*
G03X-19685Y634252I3937J0D01*
G01X1972441Y665748D02*
X-19685D01*
G01X1972441D02*
X-19685D01*
G01D02*
G03X-23622Y661811I0J-3937D01*
G01X-19685Y665748D02*
G03X-23622Y661811I0J-3937D01*
G01X-7874Y-31496D02*
G03Y-23622I0J3937D01*
G01Y-31496D02*
G03Y-23622I0J3937D01*
G01X22835D02*
G03Y-31496I0J-3937D01*
G01X137795D02*
X22835D01*
G01X137795D02*
X22835D01*
G01Y-23622D02*
G03Y-31496I0J-3937D01*
G01X0Y616535D02*
G03Y604724I0J-5905D01*
G01Y616535D02*
G03Y604724I0J-5905D01*
G01Y616535D02*
X2646D01*
G01X2644D02*
X0D01*
G01Y604724D02*
X2644D01*
G01X2646D02*
X0D01*
G01X2646D02*
X0D01*
G01D02*
X2644D01*
G01Y616535D02*
X0D01*
G01D02*
X2646D01*
G01X0D02*
G03Y604724I0J-5905D01*
G01Y616535D02*
G03Y604724I0J-5905D01*
G01X2646Y616535D02*
G03X7595Y618285I0J7874D01*
G01X2644Y616535D02*
G03X7593Y618285I0J7874D01*
G01X2644Y616535D02*
G03X7593Y618285I0J7874D01*
G01X7595Y602975D02*
G03X2646Y604724I-4948J-6125D01*
G01X7593Y602975D02*
G03X2644Y604724I-4948J-6125D01*
G01X7593Y602975D02*
G03X2644Y604724I-4948J-6125D01*
G01X7593Y602975D02*
G03X2644Y604724I-4948J-6125D01*
G01X7593Y602975D02*
G03X2644Y604724I-4948J-6125D01*
G01X7595Y602975D02*
G03X2646Y604724I-4948J-6125D01*
G01X2644Y616535D02*
G03X7593Y618285I0J7874D01*
G01X2644Y616535D02*
G03X7593Y618285I0J7874D01*
G01X2646Y616535D02*
G03X7595Y618285I0J7874D01*
G01Y602975D02*
G03Y618285I6186J7655D01*
G01X7593Y602975D02*
G03Y618285I6187J7655D01*
G01Y602975D02*
G03Y618285I6187J7655D01*
G01Y602975D02*
G03Y618285I6187J7655D01*
G01Y602975D02*
G03Y618285I6187J7655D01*
G01X7595Y602975D02*
G03Y618285I6186J7655D01*
G01X-7874Y626378D02*
G03Y634252I0J3937D01*
G01Y626378D02*
G03Y634252I0J3937D01*
G01X22835D02*
G03Y626378I0J-3937D01*
G01Y634252D02*
X137795D01*
G01X22835D02*
X137795D01*
G01X22835D02*
G03Y626378I0J-3937D01*
G01X168504Y-23622D02*
G03Y-31496I0J-3937D01*
G01X137795D02*
G03Y-23622I0J3937D01*
G01X341732Y-31496D02*
X168504D01*
G01X341732D02*
X168504D01*
G01X137795D02*
G03Y-23622I0J3937D01*
G01X168504D02*
G03Y-31496I0J-3937D01*
G01Y634252D02*
G03Y626378I0J-3937D01*
G01X137795D02*
G03Y634252I0J3937D01*
G01X168504D02*
X341732D01*
G01X168504D02*
X341732D01*
G01X137795Y626378D02*
G03Y634252I0J3937D01*
G01X168504D02*
G03Y626378I0J-3937D01*
G01X341732Y-31496D02*
G03Y-23622I0J3937D01*
G01Y-31496D02*
G03Y-23622I0J3937D01*
G01Y626378D02*
G03Y634252I0J3937D01*
G01Y626378D02*
G03Y634252I0J3937D01*
G01X372441Y-23622D02*
G03Y-31496I0J-3937D01*
G01X529921D02*
X372441D01*
G01X529921D02*
X372441D01*
G01Y-23622D02*
G03Y-31496I0J-3937D01*
G01Y634252D02*
G03Y626378I0J-3937D01*
G01Y634252D02*
X529921D01*
G01X372441D02*
X529921D01*
G01X372441D02*
G03Y626378I0J-3937D01*
G01X529921Y-31496D02*
G03Y-23622I0J3937D01*
G01Y-31496D02*
G03Y-23622I0J3937D01*
G01Y626378D02*
G03Y634252I0J3937D01*
G01Y626378D02*
G03Y634252I0J3937D01*
G01X560630Y-23622D02*
G03Y-31496I0J-3937D01*
G01X788976D02*
X560630D01*
G01X788976D02*
X560630D01*
G01Y-23622D02*
G03Y-31496I0J-3937D01*
G01Y634252D02*
G03Y626378I0J-3937D01*
G01Y634252D02*
X788976D01*
G01X560630D02*
X788976D01*
G01X560630D02*
G03Y626378I0J-3937D01*
G01X684760Y-15529D02*
G03Y-219I6187J7655D01*
G01X684759Y-15529D02*
G03X679809Y-13780I-4948J-6125D01*
G01X679811Y-1969D02*
G03X684760Y-219I0J7874D01*
G01X677165Y-1969D02*
X679811D01*
G01X677165D02*
G03Y-13780I0J-5906D01*
G01D02*
X679809D01*
G01X684760Y602975D02*
G03Y618285I6187J7655D01*
G01X684759Y602975D02*
G03Y618285I6186J7655D01*
G01Y602975D02*
G03Y618285I6186J7655D01*
G01Y602975D02*
G03Y618285I6186J7655D01*
G01Y602975D02*
G03Y618285I6186J7655D01*
G01X684760Y602975D02*
G03Y618285I6187J7655D01*
G01X679811Y616535D02*
G03X684760Y618285I0J7874D01*
G01X679809Y616535D02*
G03X684759Y618285I0J7874D01*
G01X679809Y616535D02*
G03X684759Y618285I0J7874D01*
G01X684760Y602975D02*
G03X679811Y604724I-4948J-6125D01*
G01X684759Y602975D02*
G03X679809Y604724I-4948J-6125D01*
G01X684759Y602975D02*
G03X679809Y604724I-4948J-6125D01*
G01X684759Y602975D02*
G03X679809Y604724I-4948J-6125D01*
G01X684759Y602975D02*
G03X679809Y604724I-4948J-6125D01*
G01X684760Y602975D02*
G03X679811Y604724I-4948J-6125D01*
G01X679809Y616535D02*
G03X684759Y618285I0J7874D01*
G01X679809Y616535D02*
G03X684759Y618285I0J7874D01*
G01X679811Y616535D02*
G03X684760Y618285I0J7874D01*
G01X677165Y616535D02*
X679811D01*
G01X677165D02*
G03Y604724I0J-5905D01*
G01D02*
X679809D01*
G01X788976Y-31496D02*
G03Y-23622I0J3937D01*
G01Y-31496D02*
G03Y-23622I0J3937D01*
G01X819685D02*
G03Y-31496I0J-3937D01*
G01X975591D02*
X819685D01*
G01X975591D02*
X819685D01*
G01Y-23622D02*
G03Y-31496I0J-3937D01*
G01X788976Y626378D02*
G03Y634252I0J3937D01*
G01Y626378D02*
G03Y634252I0J3937D01*
G01X819685D02*
G03Y626378I0J-3937D01*
G01Y634252D02*
X975591D01*
G01X819685D02*
X975591D01*
G01X819685D02*
G03Y626378I0J-3937D01*
G01X975591Y-31496D02*
G03Y-23622I0J3937D01*
G01Y-31496D02*
G03Y-23622I0J3937D01*
G01X1006299D02*
G03Y-31496I0J-3937D01*
G01X1162205D02*
X1006299D01*
G01X1162205D02*
X1006299D01*
G01Y-23622D02*
G03Y-31496I0J-3937D01*
G01Y634252D02*
X1162205D01*
G01X1006299D02*
X1162205D01*
G01X975591Y626378D02*
G03Y634252I0J3937D01*
G01Y626378D02*
G03Y634252I0J3937D01*
G01X1006299D02*
G03Y626378I0J-3937D01*
G01Y634252D02*
G03Y626378I0J-3937D01*
G01X1162205Y-31496D02*
G03Y-23622I0J3937D01*
G01Y-31496D02*
G03Y-23622I0J3937D01*
G01X1192913D02*
G03Y-31496I0J-3937D01*
G01X1398425D02*
X1192913D01*
G01X1398425D02*
X1192913D01*
G01Y-23622D02*
G03Y-31496I0J-3937D01*
G01Y634252D02*
X1394488D01*
G01X1192913D02*
X1394488D01*
G01X1162205Y626378D02*
G03Y634252I0J3937D01*
G01Y626378D02*
G03Y634252I0J3937D01*
G01X1192913D02*
G03Y626378I0J-3937D01*
G01Y634252D02*
G03Y626378I0J-3937D01*
G01X1398425Y-31496D02*
G03Y-23622I0J3937D01*
G01Y-31496D02*
G03Y-23622I0J3937D01*
G01X1405512Y-1968D02*
G03Y-13779I0J-5906D01*
G01Y-1968D02*
G03Y-13779I0J-5906D01*
G01Y-1968D02*
G03Y-13779I0J-5906D01*
G01Y-1968D02*
G03Y-13779I0J-5906D01*
G01X1394488Y626378D02*
G03Y634252I0J3937D01*
G01Y626378D02*
G03Y634252I0J3937D01*
G01X1405512Y616535D02*
G03Y604724I0J-5905D01*
G01Y616535D02*
G03Y604724I0J-5905D01*
G01Y616535D02*
G03Y604724I0J-5905D01*
G01Y616535D02*
G03Y604724I0J-5905D01*
G01X1429134Y-23622D02*
G03Y-31496I0J-3937D01*
G01X1851181D02*
X1429134D01*
G01X1851181D02*
X1429134D01*
G01Y-23622D02*
G03Y-31496I0J-3937D01*
G01X1413107Y-15529D02*
G03Y-218I6186J7655D01*
G01X1413105Y-15529D02*
G03Y-218I6186J7655D01*
G01Y-15529D02*
G03Y-218I6186J7655D01*
G01Y-15529D02*
G03Y-218I6186J7655D01*
G01Y-15529D02*
G03Y-218I6186J7655D01*
G01X1413107Y-15529D02*
G03Y-218I6186J7655D01*
G01X1408157Y-1968D02*
G03X1413107Y-218I1J7874D01*
G01X1408156Y-1968D02*
G03X1413105Y-218I0J7874D01*
G01X1408156Y-1968D02*
G03X1413105Y-218I0J7874D01*
G01X1408156Y-1968D02*
G03X1413105Y-218I0J7874D01*
G01X1408156Y-1968D02*
G03X1413105Y-218I0J7874D01*
G01X1408157Y-1968D02*
G03X1413107Y-218I1J7874D01*
G01Y-15529D02*
G03X1408157Y-13779I-4949J-6124D01*
G01X1413105Y-15529D02*
G03X1408156Y-13779I-4949J-6124D01*
G01X1413105Y-15529D02*
G03X1408156Y-13779I-4949J-6124D01*
G01X1413105Y-15529D02*
G03X1408156Y-13779I-4949J-6124D01*
G01X1413105Y-15529D02*
G03X1408156Y-13779I-4949J-6124D01*
G01X1413107Y-15529D02*
G03X1408157Y-13779I-4949J-6124D01*
G01X1405512D02*
X1408156D01*
G01X1408157D02*
X1405512D01*
G01X1408157D02*
X1405512D01*
G01D02*
X1408156D01*
G01X1405512Y-1968D02*
X1408157D01*
G01X1408156D02*
X1405512D01*
G01X1408156D02*
X1405512D01*
G01D02*
X1408157D01*
G01X1425197Y634252D02*
X1851181D01*
G01X1425197D02*
X1851181D01*
G01X1425197D02*
G03Y626378I0J-3937D01*
G01Y634252D02*
G03Y626378I0J-3937D01*
G01X1408157Y616535D02*
G03X1413107Y618285I1J7874D01*
G01X1408156Y616535D02*
G03X1413105Y618285I0J7874D01*
G01X1408156Y616535D02*
G03X1413105Y618285I0J7874D01*
G01X1413107Y602975D02*
G03Y618285I6186J7655D01*
G01X1413105Y602975D02*
G03Y618285I6187J7655D01*
G01Y602975D02*
G03Y618285I6187J7655D01*
G01X1413107Y602975D02*
G03X1408157Y604724I-4948J-6125D01*
G01X1413105Y602975D02*
G03X1408156Y604724I-4948J-6125D01*
G01X1413105Y602975D02*
G03X1408156Y604724I-4948J-6125D01*
G01X1413105Y602975D02*
G03X1408156Y604724I-4948J-6125D01*
G01X1413105Y602975D02*
G03X1408156Y604724I-4948J-6125D01*
G01X1413107Y602975D02*
G03X1408157Y604724I-4948J-6125D01*
G01X1413105Y602975D02*
G03Y618285I6187J7655D01*
G01Y602975D02*
G03Y618285I6187J7655D01*
G01X1413107Y602975D02*
G03Y618285I6186J7655D01*
G01X1408156Y616535D02*
G03X1413105Y618285I0J7874D01*
G01X1408156Y616535D02*
G03X1413105Y618285I0J7874D01*
G01X1408157Y616535D02*
G03X1413107Y618285I1J7874D01*
G01X1405512Y616535D02*
X1408157D01*
G01X1408156D02*
X1405512D01*
G01Y604724D02*
X1408156D01*
G01X1408157D02*
X1405512D01*
G01X1408157D02*
X1405512D01*
G01D02*
X1408156D01*
G01Y616535D02*
X1405512D01*
G01D02*
X1408157D01*
G01X1685866Y267244D02*
X1883780D01*
G01X1685866D02*
X1883780D01*
G01X1685866D02*
X1883780D01*
G01X1685866D02*
X1883780D01*
G01X1681929Y271181D02*
G03X1685866Y267244I3937J0D01*
G01X1681929Y271181D02*
G03X1685866Y267244I3937J0D01*
G01X1681929Y271181D02*
G03X1685866Y267244I3937J0D01*
G01X1681929Y271181D02*
G03X1685866Y267244I3937J0D01*
G01X1681929Y428661D02*
Y271181D01*
G01Y428661D02*
Y271181D01*
G01Y428661D02*
Y271181D01*
G01Y428661D02*
Y271181D01*
G01X1685866Y432598D02*
G03X1681929Y428661I0J-3937D01*
G01X1685866Y432598D02*
G03X1681929Y428661I0J-3937D01*
G01X1972441Y432598D02*
X1685866D01*
G01X1972441D02*
X1685866D01*
G01X1972441D02*
X1685866D01*
G01X1972441D02*
X1685866D01*
G01D02*
G03X1681929Y428661I0J-3937D01*
G01X1685866Y432598D02*
G03X1681929Y428661I0J-3937D01*
G01X1851181Y-31496D02*
G03Y-23622I0J3937D01*
G01Y-31496D02*
G03Y-23622I0J3937D01*
G01X1881890D02*
G03Y-31496I0J-3937D01*
G01X1972441D02*
X1881890D01*
G01X1972441D02*
X1881890D01*
G01Y-23622D02*
G03Y-31496I0J-3937D01*
G01X1861926Y-15529D02*
G03X1856976Y-13780I-4948J-6125D01*
G01X1861924Y-15529D02*
G03X1856975Y-13780I-4948J-6125D01*
G01X1861924Y-15529D02*
G03X1856975Y-13780I-4948J-6125D01*
G01X1861924Y-15529D02*
G03X1856975Y-13780I-4948J-6125D01*
G01X1861924Y-15529D02*
G03X1856975Y-13780I-4948J-6125D01*
G01X1861926Y-15529D02*
G03X1856976Y-13780I-4948J-6125D01*
G01Y-1969D02*
G03X1861926Y-219I0J7874D01*
G01X1856975Y-1969D02*
G03X1861924Y-219I0J7874D01*
G01X1856975Y-1969D02*
G03X1861924Y-219I0J7874D01*
G01X1861926Y-15529D02*
G03Y-219I6186J7655D01*
G01X1861924Y-15529D02*
G03Y-219I6186J7655D01*
G01Y-15529D02*
G03Y-219I6186J7655D01*
G01Y-15529D02*
G03Y-219I6186J7655D01*
G01Y-15529D02*
G03Y-219I6186J7655D01*
G01X1861926Y-15529D02*
G03Y-219I6186J7655D01*
G01X1856975Y-1969D02*
G03X1861924Y-219I0J7874D01*
G01X1856975Y-1969D02*
G03X1861924Y-219I0J7874D01*
G01X1856976Y-1969D02*
G03X1861926Y-219I0J7874D01*
G01X1854331Y-1969D02*
G03Y-13780I0J-5906D01*
G01Y-1969D02*
G03Y-13780I0J-5906D01*
G01D02*
X1856975D01*
G01X1856976D02*
X1854331D01*
G01X1856976D02*
X1854331D01*
G01D02*
X1856975D01*
G01X1854331Y-1969D02*
G03Y-13780I0J-5906D01*
G01Y-1969D02*
G03Y-13780I0J-5906D01*
G01Y-1969D02*
X1856976D01*
G01X1856975D02*
X1854331D01*
G01X1856975D02*
X1854331D01*
G01D02*
X1856976D01*
G01X1891654Y246772D02*
X1972441D01*
G01X1891654D02*
X1972441D01*
G01X1891654D02*
X1972441D01*
G01X1891654D02*
X1972441D01*
G01X1887717Y250709D02*
G03X1891654Y246772I3937J0D01*
G01X1887717Y250709D02*
G03X1891654Y246772I3937J0D01*
G01X1887717Y263307D02*
Y250709D01*
G01Y263307D02*
Y250709D01*
G01Y263307D02*
Y250709D01*
G01Y263307D02*
Y250709D01*
G01D02*
G03X1891654Y246772I3937J0D01*
G01X1887717Y250709D02*
G03X1891654Y246772I3937J0D01*
G01X1887717Y263307D02*
G03X1883780Y267244I-3937J0D01*
G01X1887717Y263307D02*
G03X1883780Y267244I-3937J0D01*
G01X1887717Y263307D02*
G03X1883780Y267244I-3937J0D01*
G01X1887717Y263307D02*
G03X1883780Y267244I-3937J0D01*
G01X1881890Y634252D02*
G03Y626378I0J-3937D01*
G01Y634252D02*
X1972441D01*
G01X1881890D02*
X1972441D01*
G01X1881890D02*
G03Y626378I0J-3937D01*
G01X1851181D02*
G03Y634252I0J3937D01*
G01Y626378D02*
G03Y634252I0J3937D01*
G01X1856976Y616535D02*
G03X1861926Y618285I0J7874D01*
G01X1856975Y616535D02*
G03X1861924Y618285I0J7874D01*
G01X1856975Y616535D02*
G03X1861924Y618285I0J7874D01*
G01X1861926Y602975D02*
G03Y618285I6186J7655D01*
G01X1861924Y602975D02*
G03Y618285I6186J7655D01*
G01Y602975D02*
G03Y618285I6186J7655D01*
G01Y602975D02*
G03Y618285I6186J7655D01*
G01Y602975D02*
G03Y618285I6186J7655D01*
G01X1861926Y602975D02*
G03Y618285I6186J7655D01*
G01X1856975Y616535D02*
G03X1861924Y618285I0J7874D01*
G01X1856975Y616535D02*
G03X1861924Y618285I0J7874D01*
G01X1856976Y616535D02*
G03X1861926Y618285I0J7874D01*
G01Y602975D02*
G03X1856976Y604724I-4948J-6125D01*
G01X1861924Y602975D02*
G03X1856975Y604724I-4948J-6125D01*
G01X1861924Y602975D02*
G03X1856975Y604724I-4948J-6125D01*
G01X1861924Y602975D02*
G03X1856975Y604724I-4948J-6125D01*
G01X1861924Y602975D02*
G03X1856975Y604724I-4948J-6125D01*
G01X1861926Y602975D02*
G03X1856976Y604724I-4948J-6125D01*
G01X1854331Y616535D02*
G03Y604724I0J-5905D01*
G01Y616535D02*
G03Y604724I0J-5905D01*
G01D02*
X1856975D01*
G01X1856976D02*
X1854331D01*
G01X1856976D02*
X1854331D01*
G01D02*
X1856975D01*
G01X1854331Y616535D02*
G03Y604724I0J-5905D01*
G01Y616535D02*
G03Y604724I0J-5905D01*
G01Y616535D02*
X1856976D01*
G01X1856975D02*
X1854331D01*
G01X1856975D02*
X1854331D01*
G01D02*
X1856976D01*
G01X1972441Y-11811D02*
X1906890D01*
G01X1904921Y-9843D02*
G03X1906890Y-11811I1969J1D01*
G01X1904921Y53150D02*
Y-9843D01*
G01X1972441Y-11811D02*
X1906890D01*
G01X1904921Y-9843D02*
G03X1906890Y-11811I1969J1D01*
G01X1904921Y53150D02*
Y-9843D01*
G01X1923071Y53150D02*
Y-9843D01*
G01X1940787Y-3937D02*
X1972441D01*
G01X1940787D02*
G03X1938819Y-5906I0J-1968D01*
G01Y-9843D02*
Y-5906D01*
G01Y-9843D02*
G03X1940787Y-11811I1968J0D01*
G01X1921102D02*
G03X1923071Y-9843I0J1969D01*
G01X1906890Y55118D02*
G03X1904921Y53150I0J-1969D01*
G01X1972441Y55118D02*
X1906890D01*
G01X1972441D02*
X1906890D01*
G01X1972441D02*
X1906890D01*
G01X1972441D02*
X1906890D01*
G01D02*
G03X1904921Y53150I0J-1969D01*
G01X1923071D02*
G03X1921102Y55118I-1969J-1D01*
G01X1940787D02*
G03X1938819Y53150I0J-1968D01*
G01Y49213D02*
Y53150D01*
G01Y49213D02*
G03X1940787Y47244I1968J-1D01*
G01X1972441D02*
X1940787D01*
G01X1976378Y-35433D02*
G03X1972441Y-31496I-3937J0D01*
G01X1976378Y-59055D02*
Y-35433D01*
G01Y-59055D02*
Y-35433D01*
G01D02*
G03X1972441Y-31496I-3937J0D01*
G01Y-62992D02*
G03X1976378Y-59055I0J3937D01*
G01X1972441Y-62992D02*
G03X1976378Y-59055I0J3937D01*
G01X1972441Y-23622D02*
G03X1976378Y-19685I0J3937D01*
G01X1972441Y-23622D02*
G03X1976378Y-19685I0J3937D01*
G01X1972441Y-23622D02*
G03X1976378Y-19685I0J3937D01*
G01X1972441Y-23622D02*
G03X1976378Y-19685I0J3937D01*
G01D02*
Y-15748D01*
G01Y-19685D02*
Y-15748D01*
G01Y-19685D02*
Y-15748D01*
G01Y-19685D02*
Y-15748D01*
G01D02*
G03X1972441Y-11811I-3937J0D01*
G01X1976378Y-15748D02*
G03X1972441Y-11811I-3937J0D01*
G01X1976378Y-15748D02*
G03X1972441Y-11811I-3937J0D01*
G01X1976378Y-15748D02*
G03X1972441Y-11811I-3937J0D01*
G01X1976378Y0D02*
Y43307D01*
G01X1972441Y-3937D02*
G03X1976378Y0I0J3937D01*
G01X1972441Y55118D02*
G03X1976378Y59055I0J3937D01*
G01X1972441Y55118D02*
G03X1976378Y59055I0J3937D01*
G01X1972441Y55118D02*
G03X1976378Y59055I0J3937D01*
G01X1972441Y55118D02*
G03X1976378Y59055I0J3937D01*
G01D02*
Y242835D01*
G01Y59055D02*
Y242835D01*
G01Y59055D02*
Y242835D01*
G01Y59055D02*
Y242835D01*
G01Y43307D02*
G03X1972441Y47244I-3937J0D01*
G01X1976378Y242835D02*
G03X1972441Y246772I-3937J0D01*
G01X1976378Y242835D02*
G03X1972441Y246772I-3937J0D01*
G01X1976378Y242835D02*
G03X1972441Y246772I-3937J0D01*
G01X1976378Y242835D02*
G03X1972441Y246772I-3937J0D01*
G01Y432598D02*
G03X1976378Y436535I0J3937D01*
G01X1972441Y432598D02*
G03X1976378Y436535I0J3937D01*
G01X1972441Y432598D02*
G03X1976378Y436535I0J3937D01*
G01X1972441Y432598D02*
G03X1976378Y436535I0J3937D01*
G01D02*
Y622441D01*
G01Y436535D02*
Y622441D01*
G01Y436535D02*
Y622441D01*
G01Y436535D02*
Y622441D01*
G01D02*
G03X1972441Y626378I-3937J0D01*
G01X1976378Y622441D02*
G03X1972441Y626378I-3937J0D01*
G01X1976378Y622441D02*
G03X1972441Y626378I-3937J0D01*
G01X1976378Y622441D02*
G03X1972441Y626378I-3937J0D01*
G01Y634252D02*
G03X1976378Y638189I0J3937D01*
G01X1972441Y634252D02*
G03X1976378Y638189I0J3937D01*
G01D02*
Y661811D01*
G01Y638189D02*
Y661811D01*
G01D02*
G03X1972441Y665748I-3937J0D01*
G01X1976378Y661811D02*
G03X1972441Y665748I-3937J0D01*
G54D12*
G01X351204Y258525D02*
X352357Y257860D01*
G01X351121Y258835D02*
X351204Y258525D01*
G01X352357Y259435D02*
G03X351121Y258835I1J-1575D01*
G01X352442Y259435D02*
X352357D01*
G01X354397Y262880D02*
G02X352442Y259435I-2040J-1120D01*
G01X354372Y262922D02*
X354397Y262880D01*
G01X354353Y262956D02*
X354372Y262922D01*
G01Y264497D02*
G03X354353Y262956I1365J-787D01*
G01X354397Y266780D02*
G02X354372Y264497I-2040J-1119D01*
G01X354375Y266817D02*
X354397Y266780D01*
G01X354374Y266817D02*
X354375D01*
G01X354371Y266821D02*
X354374Y266817D01*
G01X353963Y268904D02*
G03X354371Y266821I3245J-446D01*
G01X353963Y307685D02*
Y268904D01*
G01X353722Y257072D02*
G02X355652Y258234I2015J-1163D01*
G01X352416Y256285D02*
G03X353722Y257072I-59J1575D01*
G01X352287Y256285D02*
X352416D01*
G01X350342Y255122D02*
G02X352287Y256285I2015J-1162D01*
G01X350329Y255099D02*
X350342Y255122D01*
G01X349205Y254351D02*
G03X350329Y255099I-226J1559D01*
G01X348978Y254578D02*
X349205Y254351D01*
G01X348978Y255909D02*
Y254578D01*
G01X350131Y259144D02*
X348978Y259809D01*
G01X350483Y259239D02*
X350131Y259144D01*
G01X352287Y260185D02*
G03X350483Y259239I69J-2325D01*
G01X352416Y260185D02*
X352287D01*
G01X353741Y262513D02*
G02X352416Y260185I-1384J-753D01*
G01X353722Y262547D02*
X353741Y262513D01*
G01X353697Y262589D02*
X353722Y262547D01*
G01Y264872D02*
G03X353697Y262589I2015J-1164D01*
G01X353741Y266413D02*
G02X353722Y264872I-1384J-754D01*
G01Y266447D02*
X353741Y266413D01*
G01X353214Y268953D02*
G03X353722Y266447I3994J-495D01*
G01X353214Y308180D02*
Y268953D01*
G01X350931Y269051D02*
Y309613D01*
G01Y269044D02*
G03Y269051I-4399J4D01*
G01X350342Y266822D02*
G03X350931Y269044I-3809J2199D01*
G01X350342Y266818D02*
Y266822D01*
G01X350307Y266762D02*
X350342Y266818D01*
G01Y264496D02*
G02X350307Y266762I2015J1164D01*
G01X348978Y262134D02*
G03X350342Y264496I0J1575D01*
G01X348893Y262134D02*
X348978D01*
G01X346963Y260972D02*
G02X348893Y262134I2015J-1163D01*
G01X345826Y260201D02*
G03X346963Y260972I-228J1560D01*
G01X345598Y260429D02*
X345826Y260201D01*
G01X345598Y261760D02*
Y260429D01*
G01Y259191D02*
Y257860D01*
G01X345854Y259447D02*
X345598Y259191D01*
G01X347613Y260597D02*
G02X345854Y259447I-2015J1162D01*
G01X348919Y261384D02*
G03X347613Y260597I59J-1575D01*
G01X349048Y261384D02*
X348919D01*
G01X350993Y264873D02*
G02X349048Y261384I-2014J-1164D01*
G01X350993Y266447D02*
G03Y264873I1364J-787D01*
G01X351680Y269057D02*
G02X350993Y266447I-5148J-40D01*
G01X351680Y309302D02*
Y269057D01*
G01X348978Y253340D02*
Y252009D01*
G01X349235Y253597D02*
X348978Y253340D01*
G01X350993Y254747D02*
G02X349235Y253597I-2015J1162D01*
G01X351006Y254770D02*
X350993Y254747D01*
G01X352357Y255535D02*
G03X351006Y254770I0J-1575D01*
G01X352442Y255535D02*
X352357D01*
G01X354372Y256697D02*
G02X352442Y255535I-2015J1163D01*
G01X355678Y257484D02*
G03X354372Y256697I59J-1575D01*
G01X356413Y310135D02*
X353963Y307685D01*
G01X355918Y310884D02*
X353214Y308180D01*
G01X350931Y309613D02*
X356102Y314784D01*
G01X356413Y314035D02*
X351680Y309302D01*
G01X368407Y268762D02*
X433725D01*
G01X366858Y267214D02*
X368407Y268762D01*
G01X365889Y264966D02*
X366858Y267214D01*
G01X365256Y264429D02*
G03X365889Y264966I-226J908D01*
G01X364327Y263726D02*
G02X365256Y264429I1294J-745D01*
G01X363863Y262921D02*
X364327Y263726D01*
G01X362554Y262133D02*
G03X363863Y262921I-57J1576D01*
G01X362541Y262133D02*
X362554D01*
G01X362540Y262134D02*
X362541Y262133D01*
G01X362412Y262134D02*
X362540D01*
G01X360482Y260972D02*
G02X362412Y262134I2015J-1163D01*
G01X359176Y260185D02*
G03X360482Y260972I-59J1575D01*
G01X359047Y260185D02*
X359176D01*
G01X357102Y259022D02*
G02X359047Y260185I2015J-1162D01*
G01X355781Y258234D02*
G03X357102Y259022I-44J1575D01*
G01X355652Y258234D02*
X355781D01*
G01X355807Y257484D02*
X355678D01*
G01X357752Y258647D02*
G02X355807Y257484I-2015J1162D01*
G01X359073Y259435D02*
G03X357752Y258647I44J-1575D01*
G01X359202Y259435D02*
X359073D01*
G01X361132Y260597D02*
G02X359202Y259435I-2015J1163D01*
G01X362438Y261384D02*
G03X361132Y260597I59J-1575D01*
G01X362567Y261384D02*
X362438D01*
G01X364512Y262547D02*
G02X362567Y261384I-2015J1162D01*
G01X364976Y263352D02*
X364512Y262547D01*
G01X365439Y263702D02*
G03X364976Y263352I182J-721D01*
G01X366577Y264669D02*
G02X365439Y263702I-1547J667D01*
G01X367490Y266785D02*
X366577Y264669D01*
G01X368718Y268013D02*
X367490Y266785D01*
G01X434036Y268013D02*
X368718D01*
G01X359235Y310135D02*
X356413D01*
G01X365618Y316518D02*
X359235Y310135D01*
G01X447924Y316518D02*
X365618D01*
G01X358924Y310884D02*
X355918D01*
G01X365307Y317267D02*
X358924Y310884D01*
G01X447613Y317267D02*
X365307D01*
G01X364483Y318862D02*
X436200D01*
G01X360405Y314784D02*
X364483Y318862D01*
G01X356102Y314784D02*
X360405D01*
G01X360716Y314035D02*
X356413D01*
G01X364794Y318113D02*
X360716Y314035D01*
G01X436511Y318113D02*
X364794D01*
G01X475706Y270575D02*
X478594D01*
G01X472856Y273425D02*
X475706Y270575D01*
G01X438388Y273425D02*
X472856D01*
G01X433725Y268762D02*
X438388Y273425D01*
G01X437712Y271689D02*
X434036Y268013D01*
G01X459484Y271689D02*
X437712D01*
G01X460471Y272676D02*
X459484Y271689D01*
G01X472545Y272676D02*
X460471D01*
G01X475395Y269826D02*
X472545Y272676D01*
G01X478283Y269826D02*
X475395D01*
G01X468048Y336642D02*
X447924Y316518D01*
G01X471953Y336642D02*
X468048D01*
G01X472794Y337483D02*
X471953Y336642D01*
G01X473083Y337940D02*
X472794Y337483D01*
G01X474354Y338671D02*
G03X473083Y337940I60J-1574D01*
G01X474483Y338671D02*
X474354D01*
G01X476428Y339834D02*
G02X474483Y338671I-2015J1162D01*
G01X476441Y339857D02*
X476428Y339834D01*
G01X479157D02*
G03X476441Y339857I-1365J-787D01*
G01X460961Y330615D02*
X447613Y317267D01*
G01X460961Y335333D02*
Y330615D01*
G01X463019Y337391D02*
X460961Y335333D01*
G01X471642Y337391D02*
X463019D01*
G01X472189Y337938D02*
X471642Y337391D01*
G01X472442Y338338D02*
X472189Y337938D01*
G01X474328Y339421D02*
G03X472442Y338338I84J-2330D01*
G01X474413Y339421D02*
X474328D01*
G01X475764Y340186D02*
G02X474413Y339421I-1351J810D01*
G01X475777Y340209D02*
X475764Y340186D01*
G01X477722Y341372D02*
G03X475777Y340209I70J-2325D01*
G01X469062Y340287D02*
G02X470948Y341370I1970J-1247D01*
G01X468889Y340013D02*
X469062Y340287D01*
G01X467790Y338914D02*
X468889Y340013D01*
G01X462422Y338914D02*
X467790D01*
G01X458873Y335365D02*
X462422Y338914D01*
G01X458873Y332754D02*
Y335365D01*
G01X453932Y327813D02*
X458873Y332754D01*
G01X445151Y327813D02*
X453932D01*
G01X436200Y318862D02*
X445151Y327813D01*
G01X445462Y327064D02*
X436511Y318113D01*
G01X455145Y327064D02*
X445462D01*
G01X459622Y331541D02*
X455145Y327064D01*
G01X459622Y335054D02*
Y331541D01*
G01X462733Y338165D02*
X459622Y335054D01*
G01X468147Y338165D02*
X462733D01*
G01X469414Y339432D02*
X468147Y338165D01*
G01X469703Y339889D02*
X469414Y339432D01*
G01X470974Y340620D02*
G03X469703Y339889I60J-1574D01*
G01X471393Y340648D02*
G02X470974Y340620I-369J2370D01*
G01X473048Y341784D02*
G02X471393Y340648I-2012J1158D01*
G01X477862Y341372D02*
X477722D01*
G01X479807Y340209D02*
G03X477862Y341372I-2015J-1162D01*
G01Y345272D02*
G02X479807Y344109I-70J-2325D01*
G01X477722Y345272D02*
X477862D01*
G01X475777Y344109D02*
G02X477722Y345272I2015J-1162D01*
G01X475764Y344086D02*
X475777Y344109D01*
G01X474413Y343321D02*
G03X475764Y344086I0J1575D01*
G01X474328Y343321D02*
X474413D01*
G01X472398Y342159D02*
G02X474328Y343321I2015J-1163D01*
G01X471336Y341400D02*
G03X472398Y342159I-303J1547D01*
G01X470948Y341370D02*
G03X471336Y341400I66J1676D01*
G01X474354Y342571D02*
G03X473048Y341784I59J-1575D01*
G01X474483Y342571D02*
X474354D01*
G01X476428Y343734D02*
G02X474483Y342571I-2015J1162D01*
G01X476441Y343757D02*
X476428Y343734D01*
G01X479157D02*
G03X476441Y343757I-1365J-787D01*
G01X524022Y250922D02*
X523400Y250300D01*
G01X525155Y250922D02*
X524022D01*
G01X526476Y250134D02*
G03X525155Y250922I-1365J-787D01*
G01X528421Y248971D02*
G02X526476Y250134I70J2325D01*
G01X528550Y248971D02*
X528421D01*
G01X529875Y246643D02*
G03X528550Y248971I-1384J753D01*
G01X529856Y246609D02*
X529875Y246643D01*
G01X529831Y246567D02*
X529856Y246609D01*
G01Y244284D02*
G02X529831Y246567I2015J1164D01*
G01X529875Y242743D02*
G03X529856Y244284I-1384J754D01*
G01Y242709D02*
X529875Y242743D01*
G01X529831Y242667D02*
X529856Y242709D01*
G01Y240384D02*
G02X529831Y242667I2015J1164D01*
G01X530272Y239666D02*
X529856Y240384D01*
G01X530272Y236527D02*
Y239666D01*
G01X531434Y235365D02*
X530272Y236527D01*
G01X516987Y277433D02*
G03Y279759I-2015J1163D01*
G01Y275859D02*
G02Y277433I1365J787D01*
G01X517012Y273576D02*
G03X516987Y275859I-2040J1119D01*
G01Y273534D02*
X517012Y273576D01*
G01X516968Y273500D02*
X516987Y273534D01*
G01Y271959D02*
G02X516968Y273500I1365J787D01*
G01X517012Y269676D02*
G03X516987Y271959I-2040J1119D01*
G01Y269634D02*
X517012Y269676D01*
G01X516516Y268334D02*
G02X516987Y269634I3897J-677D01*
G01X516516Y260116D02*
Y268334D01*
G01X511157Y254757D02*
X516516Y260116D01*
G01X511143Y254757D02*
X511157D01*
G01X510227Y252459D02*
G02X511143Y254757I1365J787D01*
G01X508282Y248971D02*
G03X510227Y252459I-70J2325D01*
G01X508153Y248971D02*
X508282D01*
G01X506975Y248372D02*
G02X508153Y248971I1238J-976D01*
G01X507058Y248062D02*
X506975Y248372D01*
G01X508212Y247396D02*
X507058Y248062D01*
G01X498131Y278972D02*
G03X499437Y279759I-59J1575D01*
G01X498002Y278972D02*
X498131D01*
G01X496057Y277809D02*
G02X498002Y278972I2015J-1162D01*
G01X494736Y277021D02*
G03X496057Y277809I-44J1575D01*
G01X494607Y277021D02*
X494736D01*
G01X492677Y275859D02*
G02X494607Y277021I2015J-1163D01*
G01X491371Y275072D02*
G03X492677Y275859I-59J1575D01*
G01X491242Y275072D02*
X491371D01*
G01X489297Y273909D02*
G02X491242Y275072I2015J-1162D01*
G01X487976Y273121D02*
G03X489297Y273909I-44J1575D01*
G01X487847Y273121D02*
X487976D01*
G01X485917Y271959D02*
G02X487847Y273121I2015J-1163D01*
G01X484611Y271172D02*
G03X485917Y271959I-59J1575D01*
G01X484482Y271172D02*
X484611D01*
G01X482584Y270091D02*
G02X484482Y271172I1967J-1248D01*
G01X482053Y269239D02*
X482584Y270091D01*
G01X481685Y268969D02*
G03X482053Y269239I-154J595D01*
G01X481683Y268971D02*
X481685Y268969D01*
G01X480198Y268971D02*
X481683D01*
G01X478594Y270575D02*
X480198Y268971D01*
G01X505986Y248681D02*
X504832Y249347D01*
G01X506338Y248776D02*
X505986Y248681D01*
G01X508127Y249721D02*
G03X506338Y248776I84J-2325D01*
G01X508256Y249721D02*
X508127D01*
G01X509577Y252084D02*
G02X508256Y249721I-1365J-788D01*
G01X510736Y255410D02*
G03X509577Y252084I856J-2163D01*
G01X515766Y260440D02*
X510736Y255410D01*
G01X515766Y268334D02*
Y260440D01*
G01X516084Y269557D02*
G03X515766Y268334I2193J-1223D01*
G01X516347Y270028D02*
X516084Y269557D01*
G01X516337Y271584D02*
G02X516347Y270028I-1365J-787D01*
G01X516312Y273867D02*
G03X516337Y271584I2040J-1119D01*
G01Y273909D02*
X516312Y273867D01*
G01X516337Y275483D02*
G02Y273909I-1365J-787D01*
G01Y277809D02*
G03Y275483I2015J-1163D01*
G01X516356Y277843D02*
X516337Y277809D01*
G01Y279384D02*
G02X516356Y277843I-1365J-787D01*
G01X516312Y281667D02*
G03X516337Y279384I2040J-1119D01*
G01X530924Y240035D02*
X533057Y239293D01*
G01X530506Y240759D02*
X530924Y240035D01*
G01X530487Y242300D02*
G03X530506Y240759I1384J-754D01*
G01Y242334D02*
X530487Y242300D01*
G01X530531Y242376D02*
X530506Y242334D01*
G01Y244659D02*
G02X530531Y242376I-2015J-1164D01*
G01X530487Y246200D02*
G03X530506Y244659I1384J-754D01*
G01Y246234D02*
X530487Y246200D01*
G01X530531Y246276D02*
X530506Y246234D01*
G01X528576Y249721D02*
G02X530531Y246276I-85J-2325D01*
G01X528447Y249721D02*
X528576D01*
G01X527126Y250509D02*
G03X528447Y249721I1365J787D01*
G01X525181Y251672D02*
G02X527126Y250509I-70J-2325D01*
G01X524128Y251672D02*
X525181D01*
G01X522600Y253200D02*
X524128Y251672D01*
G01X510716Y235316D02*
X510941D01*
G01X503815Y235315D02*
X505985D01*
G01X498884D02*
X499802Y234397D01*
G01X496915Y235315D02*
X498884D01*
G01X496500Y234900D02*
X496915Y235315D01*
G01X479929Y268180D02*
X478283Y269826D01*
G01X481796Y268180D02*
X479929D01*
G01X482538Y268592D02*
G02X481796Y268180I-742J461D01*
G01X483224Y269692D02*
X482538Y268592D01*
G01X484508Y270422D02*
G03X483224Y269692I45J-1573D01*
G01X484637Y270422D02*
X484508D01*
G01X486567Y271584D02*
G02X484637Y270422I-2015J1163D01*
G01X487873Y272371D02*
G03X486567Y271584I59J-1575D01*
G01X488002Y272371D02*
X487873D01*
G01X489947Y273534D02*
G02X488002Y272371I-2015J1162D01*
G01X491268Y274322D02*
G03X489947Y273534I44J-1575D01*
G01X491397Y274322D02*
X491268D01*
G01X493327Y275484D02*
G02X491397Y274322I-2015J1163D01*
G01X494633Y276271D02*
G03X493327Y275484I59J-1575D01*
G01X494762Y276271D02*
X494633D01*
G01X496707Y277434D02*
G02X494762Y276271I-2015J1162D01*
G01X498028Y278222D02*
G03X496707Y277434I44J-1575D01*
G01X498157Y278222D02*
X498028D01*
G01X500087Y279384D02*
G02X498157Y278222I-2015J1163D01*
G01X501393Y280171D02*
G03X500087Y279384I59J-1575D01*
G01X481102Y338671D02*
G02X479157Y339834I70J2325D01*
G01X481242Y338671D02*
X481102D01*
G01X483187Y339834D02*
G02X481242Y338671I-2015J1162D01*
G01X485917Y339834D02*
G03X483187I-1365J-787D01*
G01X487862Y338671D02*
G02X485917Y339834I70J2325D01*
G01X488002Y338671D02*
X487862D01*
G01X489947Y339834D02*
G02X488002Y338671I-2015J1162D01*
G01X492677Y339834D02*
G03X489947I-1365J-787D01*
G01X494622Y338671D02*
G02X492677Y339834I70J2325D01*
G01X494762Y338671D02*
X494622D01*
G01X496707Y339834D02*
G02X494762Y338671I-2015J1162D01*
G01X499437Y339834D02*
G03X496707I-1365J-787D01*
G01X501382Y338671D02*
G02X499437Y339834I70J2325D01*
G01X501522Y338671D02*
X501382D01*
G01X503467Y339834D02*
G02X501522Y338671I-2015J1162D01*
G01X506197Y339834D02*
G03X503467I-1365J-787D01*
G01X508142Y338671D02*
G02X506197Y339834I70J2325D01*
G01X508282Y338671D02*
X508142D01*
G01X510227Y339834D02*
G02X508282Y338671I-2015J1162D01*
G01X512957Y339834D02*
G03X510227I-1365J-787D01*
G01X514902Y338671D02*
G02X512957Y339834I70J2325D01*
G01X515042Y338671D02*
X514902D01*
G01X516987Y339834D02*
G02X515042Y338671I-2015J1162D01*
G01X519703Y339857D02*
G03X516987Y339834I-1351J-810D01*
G01X519716D02*
X519703Y339857D01*
G01X521661Y338671D02*
G02X519716Y339834I70J2325D01*
G01X521801Y338671D02*
X521661D01*
G01X523746Y339834D02*
G02X521801Y338671I-2015J1162D01*
G01X526476Y339834D02*
G03X523746I-1365J-787D01*
G01X528421Y338671D02*
G02X526476Y339834I70J2325D01*
G01X528561Y338671D02*
X528421D01*
G01X530506Y339834D02*
G02X528561Y338671I-2015J1162D01*
G01X533236Y339834D02*
G03X530506I-1365J-787D01*
G01X535181Y338671D02*
G02X533236Y339834I70J2325D01*
G01X535321Y338671D02*
X535181D01*
G01X537266Y339834D02*
G02X535321Y338671I-2015J1162D01*
G01X539996Y339834D02*
G03X537266I-1365J-787D01*
G01X538716Y305522D02*
G03X540646Y306684I-85J2325D01*
G01X538587Y305522D02*
X538716D01*
G01X537266Y304734D02*
G02X538587Y305522I1365J-787D01*
G01X535321Y303571D02*
G03X537266Y304734I-70J2325D01*
G01X535192Y303571D02*
X535321D01*
G01X533886Y302784D02*
G02X535192Y303571I1365J-788D01*
G01X531956Y301622D02*
G03X533886Y302784I-85J2325D01*
G01X531827Y301622D02*
X531956D01*
G01X530506Y300834D02*
G02X531827Y301622I1365J-787D01*
G01X528561Y299671D02*
G03X530506Y300834I-70J2325D01*
G01X528432Y299671D02*
X528561D01*
G01X527126Y298884D02*
G02X528432Y299671I1365J-788D01*
G01X525196Y297722D02*
G03X527126Y298884I-85J2325D01*
G01X525067Y297722D02*
X525196D01*
G01X523746Y296934D02*
G02X525067Y297722I1365J-787D01*
G01X521801Y295771D02*
G03X523746Y296934I-70J2325D01*
G01X521731Y295771D02*
X521801D01*
G01X520380Y295006D02*
G02X521731Y295771I1351J-810D01*
G01X520367Y294983D02*
X520380Y295006D01*
G01X518422Y293821D02*
G03X520367Y294983I-70J2326D01*
G01X518333Y293821D02*
X518422D01*
G01X516968Y291492D02*
G02X518333Y293821I1384J753D01*
G01X516987Y291458D02*
X516968Y291492D01*
G01X516987Y289134D02*
G03Y291458I-2015J1162D01*
G01X516968Y289100D02*
X516987Y289134D01*
G01Y287559D02*
G02X516968Y289100I1365J787D01*
G01X517012Y285276D02*
G03X516987Y287559I-2040J1119D01*
G01Y285234D02*
X517012Y285276D01*
G01X516968Y285200D02*
X516987Y285234D01*
G01Y283659D02*
G02X516968Y285200I1365J787D01*
G01X517012Y281376D02*
G03X516987Y283659I-2040J1119D01*
G01Y281334D02*
X517012Y281376D01*
G01X516968Y281300D02*
X516987Y281334D01*
G01Y279759D02*
G02X516968Y281300I1365J787D01*
G01X538702Y321872D02*
G03X539996Y322659I-71J1574D01*
G01X538561Y321872D02*
X538702D01*
G01X536616Y320709D02*
G02X538561Y321872I2015J-1162D01*
G01X535295Y319921D02*
G03X536616Y320709I-44J1575D01*
G01X535166Y319921D02*
X535295D01*
G01X533236Y318759D02*
G02X535166Y319921I2015J-1163D01*
G01X531930Y317972D02*
G03X533236Y318759I-59J1575D01*
G01X531801Y317972D02*
X531930D01*
G01X529856Y316809D02*
G02X531801Y317972I2015J-1162D01*
G01X528535Y316021D02*
G03X529856Y316809I-44J1575D01*
G01X528406Y316021D02*
X528535D01*
G01X526476Y314859D02*
G02X528406Y316021I2015J-1163D01*
G01X525170Y314072D02*
G03X526476Y314859I-59J1575D01*
G01X525041Y314072D02*
X525170D01*
G01X523096Y312909D02*
G02X525041Y314072I2015J-1162D01*
G01X521802Y312122D02*
G03X523096Y312909I-71J1574D01*
G01X521646Y312122D02*
X521802D01*
G01X519716Y310960D02*
G02X521646Y312122I2015J-1163D01*
G01X519703Y310937D02*
X519716Y310960D01*
G01X518352Y310172D02*
G03X519703Y310937I0J1575D01*
G01X518267Y310172D02*
X518352D01*
G01X516337Y309010D02*
G02X518267Y310172I2015J-1163D01*
G01X515016Y308222D02*
G03X516337Y309010I-44J1575D01*
G01X514921Y308222D02*
X515016D01*
G01X512932Y304776D02*
G02X514921Y308222I2040J1120D01*
G01X512957Y304734D02*
X512932Y304776D01*
G01X512976Y304700D02*
X512957Y304734D01*
G01Y303159D02*
G03X512976Y304700I-1365J787D01*
G01X512932Y300876D02*
G02X512957Y303159I2040J1119D01*
G01Y300834D02*
X512932Y300876D01*
G01X512976Y300800D02*
X512957Y300834D01*
G01Y299259D02*
G03X512976Y300800I-1365J787D01*
G01X512932Y296976D02*
G02X512957Y299259I2040J1119D01*
G01Y296934D02*
X512932Y296976D01*
G01X512976Y296900D02*
X512957Y296934D01*
G01Y295359D02*
G03X512976Y296900I-1365J787D01*
G01X512957Y293033D02*
G02Y295359I2015J1163D01*
G01X512976Y291492D02*
G03X512957Y293033I-1384J754D01*
G01Y291458D02*
X512976Y291492D01*
G01X512957Y289134D02*
G02Y291458I2015J1162D01*
G01X512976Y289100D02*
X512957Y289134D01*
G01X511651Y286772D02*
G03X512976Y289100I-59J1575D01*
G01X511522Y286772D02*
X511651D01*
G01X509577Y285609D02*
G02X511522Y286772I2015J-1162D01*
G01X508256Y284821D02*
G03X509577Y285609I-44J1575D01*
G01X508127Y284821D02*
X508256D01*
G01X506197Y283659D02*
G02X508127Y284821I2015J-1163D01*
G01X504891Y282872D02*
G03X506197Y283659I-59J1575D01*
G01X504762Y282872D02*
X504891D01*
G01X502817Y281709D02*
G02X504762Y282872I2015J-1162D01*
G01X501496Y280921D02*
G03X502817Y281709I-44J1575D01*
G01X501367Y280921D02*
X501496D01*
G01X499437Y279759D02*
G02X501367Y280921I2015J-1163D01*
G01X516337Y281709D02*
X516312Y281667D01*
G01X516356Y281743D02*
X516337Y281709D01*
G01Y283284D02*
G02X516356Y281743I-1365J-787D01*
G01X516312Y285567D02*
G03X516337Y283284I2040J-1119D01*
G01Y285609D02*
X516312Y285567D01*
G01X516356Y285643D02*
X516337Y285609D01*
G01Y287184D02*
G02X516356Y285643I-1365J-787D01*
G01X516312Y289467D02*
G03X516337Y287184I2040J-1119D01*
G01Y289509D02*
X516312Y289467D01*
G01X516337Y291083D02*
G02Y289509I-1365J-787D01*
G01X516312Y291125D02*
X516337Y291083D01*
G01X518301Y294571D02*
G03X516312Y291125I51J-2326D01*
G01X518352Y294571D02*
X518301D01*
G01X519685Y295306D02*
G02X518352Y294571I-1333J841D01*
G01X519716Y295360D02*
X519685Y295306D01*
G01X521633Y296521D02*
G03X519716Y295360I98J-2325D01*
G01X521775Y296521D02*
X521633D01*
G01X523096Y297309D02*
G02X521775Y296521I-1365J787D01*
G01X525041Y298472D02*
G03X523096Y297309I70J-2325D01*
G01X525170Y298472D02*
X525041D01*
G01X526476Y299259D02*
G02X525170Y298472I-1365J788D01*
G01X528406Y300421D02*
G03X526476Y299259I85J-2325D01*
G01X528535Y300421D02*
X528406D01*
G01X529856Y301209D02*
G02X528535Y300421I-1365J787D01*
G01X531801Y302372D02*
G03X529856Y301209I70J-2325D01*
G01X531930Y302372D02*
X531801D01*
G01X533236Y303159D02*
G02X531930Y302372I-1365J788D01*
G01X535166Y304321D02*
G03X533236Y303159I85J-2325D01*
G01X535295Y304321D02*
X535166D01*
G01X536616Y305109D02*
G02X535295Y304321I-1365J787D01*
G01X538561Y306272D02*
G03X536616Y305109I70J-2325D01*
G01X538690Y306272D02*
X538561D01*
G01X539996Y307059D02*
G02X538690Y306272I-1365J788D01*
G01X482537Y340209D02*
G02X479807I-1365J787D01*
G01X484482Y341372D02*
G03X482537Y340209I70J-2325D01*
G01X486567D02*
G03X484622Y341372I-2015J-1162D01*
G01X489297Y340209D02*
G02X486567I-1365J787D01*
G01X491242Y341372D02*
G03X489297Y340209I70J-2325D01*
G01X493327D02*
G03X491382Y341372I-2015J-1162D01*
G01X496057Y340209D02*
G02X493327I-1365J787D01*
G01X498002Y341372D02*
G03X496057Y340209I70J-2325D01*
G01X500087D02*
G03X498142Y341372I-2015J-1162D01*
G01X502817Y340209D02*
G02X500087I-1365J787D01*
G01X504762Y341372D02*
G03X502817Y340209I70J-2325D01*
G01X506847D02*
G03X504902Y341372I-2015J-1162D01*
G01X509577Y340209D02*
G02X506847I-1365J787D01*
G01X511522Y341372D02*
G03X509577Y340209I70J-2325D01*
G01X513607D02*
G03X511662Y341372I-2015J-1162D01*
G01X516337Y340209D02*
G02X513607I-1365J787D01*
G01X518282Y341372D02*
G03X516337Y340209I70J-2325D01*
G01X520367D02*
G03X518422Y341372I-2015J-1162D01*
G01X520380Y340186D02*
X520367Y340209D01*
G01X523096D02*
G02X520380Y340186I-1365J787D01*
G01X525041Y341372D02*
G03X523096Y340209I70J-2325D01*
G01X527126D02*
G03X525181Y341372I-2015J-1162D01*
G01X529856Y340209D02*
G02X527126I-1365J787D01*
G01X531801Y341372D02*
G03X529856Y340209I70J-2325D01*
G01X533886D02*
G03X531941Y341372I-2015J-1162D01*
G01X536616Y340209D02*
G02X533886I-1365J787D01*
G01X538561Y341372D02*
G03X536616Y340209I70J-2325D01*
G01X540646D02*
G03X538701Y341372I-2015J-1162D01*
G01X501522Y280171D02*
X501393D01*
G01X503467Y281334D02*
G02X501522Y280171I-2015J1162D01*
G01X504788Y282122D02*
G03X503467Y281334I44J-1575D01*
G01X504917Y282122D02*
X504788D01*
G01X506847Y283284D02*
G02X504917Y282122I-2015J1163D01*
G01X508153Y284071D02*
G03X506847Y283284I59J-1575D01*
G01X508282Y284071D02*
X508153D01*
G01X510227Y285234D02*
G02X508282Y284071I-2015J1162D01*
G01X511548Y286022D02*
G03X510227Y285234I44J-1575D01*
G01X511677Y286022D02*
X511548D01*
G01X513632Y289467D02*
G02X511677Y286022I-2040J-1120D01*
G01X513607Y289509D02*
X513632Y289467D01*
G01X513607Y291083D02*
G03Y289509I1365J-787D01*
G01X513632Y291125D02*
X513607Y291083D01*
G01Y293408D02*
G02X513632Y291125I-2015J-1164D01*
G01X513607Y294984D02*
G03Y293408I1365J-788D01*
G01X513632Y297267D02*
G02X513607Y294984I-2040J-1119D01*
G01Y297309D02*
X513632Y297267D01*
G01X513588Y297343D02*
X513607Y297309D01*
G01Y298884D02*
G03X513588Y297343I1365J-787D01*
G01X513632Y301167D02*
G02X513607Y298884I-2040J-1119D01*
G01Y301209D02*
X513632Y301167D01*
G01X513588Y301243D02*
X513607Y301209D01*
G01Y302784D02*
G03X513588Y301243I1365J-787D01*
G01X513632Y305067D02*
G02X513607Y302784I-2040J-1119D01*
G01Y305109D02*
X513632Y305067D01*
G01X513588Y305143D02*
X513607Y305109D01*
G01X514913Y307471D02*
G03X513588Y305143I59J-1575D01*
G01X515023Y307471D02*
X514913D01*
G01X516987Y308634D02*
G02X515023Y307471I-2015J1163D01*
G01X518308Y309422D02*
G03X516987Y308634I44J-1575D01*
G01X518437Y309422D02*
X518308D01*
G01X520367Y310584D02*
G02X518437Y309422I-2015J1163D01*
G01X521683Y311371D02*
G03X520367Y310584I48J-1574D01*
G01X521801Y311371D02*
X521683D01*
G01X523746Y312534D02*
G02X521801Y311371I-2015J1162D01*
G01X525067Y313322D02*
G03X523746Y312534I44J-1575D01*
G01X525196Y313322D02*
X525067D01*
G01X527126Y314484D02*
G02X525196Y313322I-2015J1163D01*
G01X528432Y315271D02*
G03X527126Y314484I59J-1575D01*
G01X528561Y315271D02*
X528432D01*
G01X530506Y316434D02*
G02X528561Y315271I-2015J1162D01*
G01X531827Y317222D02*
G03X530506Y316434I44J-1575D01*
G01X531956Y317222D02*
X531827D01*
G01X533886Y318384D02*
G02X531956Y317222I-2015J1163D01*
G01X535192Y319171D02*
G03X533886Y318384I59J-1575D01*
G01X535321Y319171D02*
X535192D01*
G01X537266Y320334D02*
G02X535321Y319171I-2015J1162D01*
G01X538560Y321121D02*
G03X537266Y320334I71J-1574D01*
G01X538716Y321121D02*
X538560D01*
G01X540646Y322283D02*
G02X538716Y321121I-2015J1163D01*
G01X484622Y341372D02*
X484482D01*
G01X491382D02*
X491242D01*
G01X498142D02*
X498002D01*
G01X504902D02*
X504762D01*
G01X511662D02*
X511522D01*
G01X518422D02*
X518282D01*
G01X525181D02*
X525041D01*
G01X531941D02*
X531801D01*
G01X538701D02*
X538561D01*
G01X538701Y345272D02*
G02X540646Y344109I-70J-2325D01*
G01X538561Y345272D02*
X538701D01*
G01X536616Y344109D02*
G02X538561Y345272I2015J-1162D01*
G01X533886Y344109D02*
G03X536616I1365J787D01*
G01X531941Y345272D02*
G02X533886Y344109I-70J-2325D01*
G01X531801Y345272D02*
X531941D01*
G01X529856Y344109D02*
G02X531801Y345272I2015J-1162D01*
G01X527126Y344109D02*
G03X529856I1365J787D01*
G01X523096D02*
G02X527126I2015J-1162D01*
G01X520393Y344064D02*
G03X523096Y344109I1338J832D01*
G01X520367D02*
X520393Y344064D01*
G01X516337Y344109D02*
G02X520367I2015J-1162D01*
G01X513607D02*
G03X516337I1365J787D01*
G01X511662Y345272D02*
G02X513607Y344109I-70J-2325D01*
G01X511522Y345272D02*
X511662D01*
G01X509577Y344109D02*
G02X511522Y345272I2015J-1162D01*
G01X506847Y344109D02*
G03X509577I1365J787D01*
G01X504902Y345272D02*
G02X506847Y344109I-70J-2325D01*
G01X504762Y345272D02*
X504902D01*
G01X502817Y344109D02*
G02X504762Y345272I2015J-1162D01*
G01X500087Y344109D02*
G03X502817I1365J787D01*
G01X498142Y345272D02*
G02X500087Y344109I-70J-2325D01*
G01X498002Y345272D02*
X498142D01*
G01X496057Y344109D02*
G02X498002Y345272I2015J-1162D01*
G01X493327Y344109D02*
G03X496057I1365J787D01*
G01X491382Y345272D02*
G02X493327Y344109I-70J-2325D01*
G01X491242Y345272D02*
X491382D01*
G01X489297Y344109D02*
G02X491242Y345272I2015J-1162D01*
G01X486567Y344109D02*
G03X489297I1365J787D01*
G01X484622Y345272D02*
G02X486567Y344109I-70J-2325D01*
G01X484482Y345272D02*
X484622D01*
G01X482537Y344109D02*
G02X484482Y345272I2015J-1162D01*
G01X479807Y344109D02*
G03X482537I1365J787D01*
G01X481102Y342571D02*
G02X479157Y343734I70J2325D01*
G01X481242Y342571D02*
X481102D01*
G01X483187Y343734D02*
G02X481242Y342571I-2015J1162D01*
G01X485917Y343734D02*
G03X483187I-1365J-787D01*
G01X487862Y342571D02*
G02X485917Y343734I70J2325D01*
G01X488002Y342571D02*
X487862D01*
G01X489947Y343734D02*
G02X488002Y342571I-2015J1162D01*
G01X492677Y343734D02*
G03X489947I-1365J-787D01*
G01X494622Y342571D02*
G02X492677Y343734I70J2325D01*
G01X494762Y342571D02*
X494622D01*
G01X496707Y343734D02*
G02X494762Y342571I-2015J1162D01*
G01X499437Y343734D02*
G03X496707I-1365J-787D01*
G01X501382Y342571D02*
G02X499437Y343734I70J2325D01*
G01X501522Y342571D02*
X501382D01*
G01X503467Y343734D02*
G02X501522Y342571I-2015J1162D01*
G01X506197Y343734D02*
G03X503467I-1365J-787D01*
G01X508142Y342571D02*
G02X506197Y343734I70J2325D01*
G01X508282Y342571D02*
X508142D01*
G01X510227Y343734D02*
G02X508282Y342571I-2015J1162D01*
G01X512957Y343734D02*
G03X510227I-1365J-787D01*
G01X514902Y342571D02*
G02X512957Y343734I70J2325D01*
G01X515042Y342571D02*
X514902D01*
G01X516987Y343734D02*
G02X515042Y342571I-2015J1162D01*
G01X519690Y343779D02*
G03X516987Y343734I-1338J-832D01*
G01X519716D02*
X519690Y343779D01*
G01X523746Y343734D02*
G02X519716I-2015J1162D01*
G01X526476D02*
G03X523746I-1365J-787D01*
G01X528421Y342571D02*
G02X526476Y343734I70J2325D01*
G01X528561Y342571D02*
X528421D01*
G01X530506Y343734D02*
G02X528561Y342571I-2015J1162D01*
G01X533236Y343734D02*
G03X530506I-1365J-787D01*
G01X535181Y342571D02*
G02X533236Y343734I70J2325D01*
G01X535321Y342571D02*
X535181D01*
G01X537266Y343734D02*
G02X535321Y342571I-2015J1162D01*
G01X539996Y343734D02*
G03X537266I-1365J-787D01*
G01X548830Y229471D02*
X547421D01*
G01X550136Y228684D02*
G03X548830Y229471I-1365J-788D01*
G01X552066Y227522D02*
G02X550136Y228684I85J2325D01*
G01X552236Y227522D02*
X552066D01*
G01X554166Y228684D02*
G02X552236Y227522I-2015J1163D01*
G01X555472Y229471D02*
G03X554166Y228684I59J-1575D01*
G01X555590Y229471D02*
X555472D01*
G01X556896Y228684D02*
G03X555590Y229471I-1365J-788D01*
G01X558826Y227522D02*
G02X556896Y228684I85J2325D01*
G01X559778Y227522D02*
X558826D01*
G01X561100Y226200D02*
X559778Y227522D01*
G01X559872Y228272D02*
X561200Y229600D01*
G01X558852Y228272D02*
X559872D01*
G01X557546Y229059D02*
G03X558852Y228272I1365J788D01*
G01X553516Y229059D02*
G02X557546I2015J-1163D01*
G01X552210Y228272D02*
G03X553516Y229059I-59J1575D01*
G01X552092Y228272D02*
X552210D01*
G01X550786Y229059D02*
G03X552092Y228272I1365J788D01*
G01X548822Y230222D02*
G02X550786Y229059I-51J-2326D01*
G01X547801Y230222D02*
X548822D01*
G01X547800Y230221D02*
X547801Y230222D01*
G01X547421Y230600D02*
X547800Y230221D01*
G01X547100Y230600D02*
X547421D01*
G01X541941Y338671D02*
G02X539996Y339834I70J2325D01*
G01X542081Y338671D02*
X541941D01*
G01X544026Y339834D02*
G02X542081Y338671I-2015J1162D01*
G01X546756Y339834D02*
G03X544026I-1365J-787D01*
G01X548701Y338671D02*
G02X546756Y339834I70J2325D01*
G01X548841Y338671D02*
X548701D01*
G01X550786Y339834D02*
G02X548841Y338671I-2015J1162D01*
G01X553516Y339834D02*
G03X550786I-1365J-787D01*
G01X555461Y338671D02*
G02X553516Y339834I70J2325D01*
G01X555601Y338671D02*
X555461D01*
G01X557546Y339834D02*
G02X555601Y338671I-2015J1162D01*
G01X558867Y340622D02*
G03X557546Y339834I44J-1575D01*
G01X559566Y340622D02*
X558867D01*
G01X560419Y339845D02*
G03X559566Y340622I-1508J-798D01*
G01X561793Y338671D02*
G02X560419Y339845I798J2325D01*
G01X563624Y338671D02*
X561793D01*
G01X560212Y321121D02*
X570596Y326728D01*
G01X558553Y321121D02*
X560212D01*
G01X557703Y320345D02*
G02X558553Y321121I1508J-798D01*
G01X556214Y319135D02*
G03X557703Y320345I-683J2361D01*
G01X555165Y319057D02*
X556214Y319135D01*
G01X554317Y318310D02*
G02X555165Y319057I1514J-864D01*
G01X554255Y317078D02*
G02X554317Y318310I1249J555D01*
G01X554323Y314495D02*
G03X554255Y317078I-2321J1231D01*
G01X552951Y313322D02*
G03X554323Y314495I-800J2325D01*
G01X552107Y313322D02*
X552951D01*
G01X550786Y312534D02*
G02X552107Y313322I1365J-787D01*
G01X548841Y311371D02*
G03X550786Y312534I-70J2325D01*
G01X548700Y311371D02*
X548841D01*
G01X547406Y310584D02*
G02X548700Y311371I1365J-787D01*
G01X545476Y309422D02*
G03X547406Y310584I-85J2325D01*
G01X545347Y309422D02*
X545476D01*
G01X544026Y308634D02*
G02X545347Y309422I1365J-787D01*
G01X542062Y307471D02*
G03X544026Y308634I-51J2326D01*
G01X541952Y307471D02*
X542062D01*
G01X540646Y306684D02*
G02X541952Y307471I1365J-788D01*
G01X561791Y335521D02*
X564189D01*
G01X560419Y334348D02*
G02X561791Y335521I2172J-1152D01*
G01X559458Y333530D02*
G03X560419Y334348I-547J1617D01*
G01X558373Y333450D02*
X559458Y333530D01*
G01X557045Y332335D02*
G02X558373Y333450I2166J-1232D01*
G01X556274Y331621D02*
G03X557045Y332335I-743J1575D01*
G01X555446Y331621D02*
X556274D01*
G01X553516Y330459D02*
G02X555446Y331621I2015J-1163D01*
G01X552210Y329672D02*
G03X553516Y330459I-59J1575D01*
G01X552081Y329672D02*
X552210D01*
G01X550136Y328509D02*
G02X552081Y329672I2015J-1162D01*
G01X548815Y327721D02*
G03X550136Y328509I-44J1575D01*
G01X548686Y327721D02*
X548815D01*
G01X546756Y326559D02*
G02X548686Y327721I2015J-1163D01*
G01X545450Y325772D02*
G03X546756Y326559I-59J1575D01*
G01X545340Y325772D02*
X545450D01*
G01X543376Y324609D02*
G02X545340Y325772I2015J-1163D01*
G01X542055Y323821D02*
G03X543376Y324609I-44J1575D01*
G01X541926Y323821D02*
X542055D01*
G01X539996Y322659D02*
G02X541926Y323821I2015J-1163D01*
G01X541960Y308222D02*
G03X539996Y307059I51J-2326D01*
G01X542055Y308222D02*
X541960D01*
G01X543376Y309010D02*
G02X542055Y308222I-1365J787D01*
G01X545306Y310172D02*
G03X543376Y309010I85J-2325D01*
G01X545435Y310172D02*
X545306D01*
G01X546756Y310960D02*
G02X545435Y310172I-1365J787D01*
G01X548686Y312122D02*
G03X546756Y310960I85J-2325D01*
G01X548842Y312122D02*
X548686D01*
G01X550136Y312909D02*
G02X548842Y312122I-1365J787D01*
G01X552081Y314072D02*
G03X550136Y312909I70J-2325D01*
G01X552808Y314072D02*
X552081D01*
G01X553659Y314848D02*
G02X552808Y314072I-1508J799D01*
G01X553612Y316515D02*
G02X553659Y314848I-1448J-875D01*
G01X553321Y317198D02*
G03X553612Y316515I947J0D01*
G01X553666Y318682D02*
G03X553321Y317198I2319J-1321D01*
G01X554995Y319796D02*
G03X553666Y318682I837J-2348D01*
G01X556064Y319875D02*
X554995Y319796D01*
G01X557039Y320698D02*
G02X556064Y319875I-1508J798D01*
G01X558413Y321872D02*
G03X557039Y320698I798J-2325D01*
G01X558416Y321871D02*
X558413Y321872D01*
G01X559742Y321871D02*
X558416D01*
G01X562163Y323177D02*
X559742Y321871D01*
G01X543376Y340209D02*
G02X540646I-1365J787D01*
G01X545321Y341372D02*
G03X543376Y340209I70J-2325D01*
G01X547406D02*
G03X545461Y341372I-2015J-1162D01*
G01X550136Y340209D02*
G02X547406I-1365J787D01*
G01X552081Y341372D02*
G03X550136Y340209I70J-2325D01*
G01X554166D02*
G03X552221Y341372I-2015J-1162D01*
G01X556896Y340209D02*
G02X554166I-1365J787D01*
G01X558841Y341372D02*
G03X556896Y340209I70J-2325D01*
G01X561083Y340198D02*
G03X559709Y341372I-2172J-1151D01*
G01X561936Y339421D02*
G02X561083Y340198I655J1575D01*
G01X563622Y339421D02*
X561936D01*
G01X563624Y339423D02*
X563622Y339421D01*
G01X541967Y323071D02*
G03X540646Y322283I44J-1575D01*
G01X542096Y323071D02*
X541967D01*
G01X544026Y324233D02*
G02X542096Y323071I-2015J1163D01*
G01X545347Y325021D02*
G03X544026Y324233I44J-1575D01*
G01X545442Y325021D02*
X545347D01*
G01X547406Y326184D02*
G02X545442Y325021I-2015J1163D01*
G01X548712Y326971D02*
G03X547406Y326184I59J-1575D01*
G01X548841Y326971D02*
X548712D01*
G01X550786Y328134D02*
G02X548841Y326971I-2015J1162D01*
G01X552107Y328922D02*
G03X550786Y328134I44J-1575D01*
G01X552236Y328922D02*
X552107D01*
G01X554166Y330084D02*
G02X552236Y328922I-2015J1163D01*
G01X555472Y330871D02*
G03X554166Y330084I59J-1575D01*
G01X556428Y330871D02*
X555472D01*
G01X557697Y331964D02*
G02X556428Y330871I-2166J1232D01*
G01X558541Y332711D02*
G03X557697Y331964I670J-1608D01*
G01X559610Y332790D02*
X558541Y332711D01*
G01X561083Y333995D02*
G02X559610Y332790I-2172J1152D01*
G01X561934Y334771D02*
G03X561083Y333995I657J-1575D01*
G01X564589Y334771D02*
X561934D01*
G01X545461Y341372D02*
X545321D01*
G01X552221D02*
X552081D01*
G01X559709D02*
X558841D01*
G01X561936Y343321D02*
X563603D01*
G01X561083Y344098D02*
G03X561936Y343321I1508J798D01*
G01X557294Y344798D02*
G02X561083Y344098I1617J-1851D01*
G01X556896Y344109D02*
X557294Y344798D01*
G01X554166Y344109D02*
G03X556896I1365J787D01*
G01X550136D02*
G02X554166I2015J-1162D01*
G01X547406D02*
G03X550136I1365J787D01*
G01X545461Y345272D02*
G02X547406Y344109I-70J-2325D01*
G01X545321Y345272D02*
X545461D01*
G01X543376Y344109D02*
G02X545321Y345272I2015J-1162D01*
G01X540646Y344109D02*
G03X543376I1365J787D01*
G01X541941Y342571D02*
G02X539996Y343734I70J2325D01*
G01X542081Y342571D02*
X541941D01*
G01X544026Y343734D02*
G02X542081Y342571I-2015J1162D01*
G01X546756Y343734D02*
G03X544026I-1365J-787D01*
G01X550786D02*
G02X546756I-2015J1162D01*
G01X553516D02*
G03X550786I-1365J-787D01*
G01X557546D02*
G02X553516I-2015J1162D01*
G01X557872Y344300D02*
X557546Y343734D01*
G01X560419Y343745D02*
G03X557872Y344300I-1508J-798D01*
G01X561793Y342571D02*
G02X560419Y343745I798J2325D01*
G01X564003Y342571D02*
X561793D01*
G01X1207051Y223836D02*
X1207741Y223034D01*
G01X1206504Y224784D02*
X1207051Y223836D01*
G01X1206479Y227067D02*
G03X1206504Y224784I2040J-1119D01*
G01Y227109D02*
X1206479Y227067D01*
G01X1206523Y227143D02*
X1206504Y227109D01*
G01X1205198Y229471D02*
G02X1206523Y227143I-59J-1575D01*
G01X1205088Y229471D02*
X1205198D01*
G01X1203124Y230634D02*
G03X1205088Y229471I2015J1163D01*
G01X1202814Y231081D02*
X1203124Y230634D01*
G01X1201858Y231900D02*
X1202814Y231081D01*
G01X1203358Y235437D02*
Y238683D01*
G01X1203413Y235382D02*
X1203358Y235437D01*
G01X1203774Y234909D02*
G03X1203413Y235382I-2015J-1163D01*
G01X1205197Y234087D02*
G02X1203774Y234909I0J1642D01*
G01X1207819Y231465D02*
X1205197Y234087D01*
G01X1209120Y231465D02*
X1207819D01*
G01X1210088Y230497D02*
X1209120Y231465D01*
G01X1210088Y229197D02*
Y230497D01*
G01X1208670Y227779D02*
X1210088Y229197D01*
G01X1207776Y227779D02*
X1208670D01*
G01X1207154Y226734D02*
X1207776Y227779D01*
G01X1207135Y226700D02*
X1207154Y226734D01*
G01Y225159D02*
G02X1207135Y226700I1365J787D01*
G01X1207778Y224172D02*
X1207154Y225159D01*
G01X1209439Y222400D02*
X1207778Y224172D01*
G01X1201214Y235321D02*
X1198835Y237700D01*
G01X1201803Y235321D02*
X1201214D01*
G01X1203124Y234533D02*
G03X1201803Y235321I-1365J-787D01*
G01X1203499Y234044D02*
G02X1203124Y234533I1668J1668D01*
G01X1203499Y231470D02*
Y234044D01*
G01X1203774Y231010D02*
X1203499Y231470D01*
G01X1205095Y230222D02*
G02X1203774Y231010I44J1575D01*
G01X1205894Y230222D02*
X1205095D01*
G01X1208519Y229847D02*
X1205894Y230222D01*
G01X1500800Y377599D02*
Y374794D01*
G01X1501962Y379529D02*
G03X1500800Y377599I1163J-2015D01*
G01X1502734Y380666D02*
G02X1501962Y379529I-1559J228D01*
G01X1502506Y380894D02*
X1502734Y380666D01*
G01X1501175Y380894D02*
X1502506D01*
G01X1520931Y382580D02*
X1522625Y384274D01*
G01X1520319Y382580D02*
X1520931D01*
G01X1519888Y382259D02*
G03X1520319Y382580I-1165J2014D01*
G01X1519100Y380938D02*
G02X1519888Y382259I1575J-44D01*
G01X1519100Y380248D02*
Y380938D01*
G01X1519105Y380243D02*
X1519100Y380248D01*
G01X1504700Y377599D02*
Y374200D01*
G01X1505862Y379529D02*
G03X1504700Y377599I1163J-2015D01*
G01X1506650Y380850D02*
G02X1505862Y379529I-1575J44D01*
G01X1506650Y380979D02*
Y380850D01*
G01X1507812Y382909D02*
G03X1506650Y380979I1163J-2015D01*
G01X1508600Y384230D02*
G02X1507812Y382909I-1575J44D01*
G01X1508600Y384359D02*
Y384230D01*
G01X1509762Y386289D02*
G03X1508600Y384359I1163J-2015D01*
G01X1510550Y387610D02*
G02X1509762Y386289I-1575J44D01*
G01X1510550Y387739D02*
Y387610D01*
G01X1511712Y389669D02*
G03X1510550Y387739I1163J-2015D01*
G01X1512500Y390990D02*
G02X1511712Y389669I-1575J44D01*
G01X1512500Y391119D02*
Y390990D01*
G01X1513662Y393049D02*
G03X1512500Y391119I1163J-2015D01*
G01X1514434Y394186D02*
G02X1513662Y393049I-1559J228D01*
G01X1514611Y395398D02*
X1514434Y394186D01*
G01X1513100Y396909D02*
X1514611Y395398D01*
G01X1513100Y398288D02*
Y396909D01*
G01X1513992Y399180D02*
X1513100Y398288D01*
G01X1514444Y400272D02*
X1513992Y399180D01*
G01X1514444Y401623D02*
Y400272D01*
G01X1515601Y402780D02*
X1514444Y401623D01*
G01X1527383Y402780D02*
X1515601D01*
G01X1514450Y379394D02*
X1513255Y378199D01*
G01X1514450Y380979D02*
Y379394D01*
G01X1515612Y382909D02*
G03X1514450Y380979I1163J-2015D01*
G01X1516400Y384230D02*
G02X1515612Y382909I-1575J44D01*
G01X1516400Y384359D02*
Y384230D01*
G01X1517562Y386289D02*
G03X1516400Y384359I1163J-2015D01*
G01X1518350Y387610D02*
G02X1517562Y386289I-1575J44D01*
G01X1518350Y387698D02*
Y387610D01*
G01X1517562Y389019D02*
G02X1518350Y387698I-787J-1365D01*
G01X1516400Y390949D02*
G03X1517562Y389019I2325J85D01*
G01X1516400Y391119D02*
Y390949D01*
G01X1517562Y393049D02*
G03X1516400Y391119I1163J-2015D01*
G01X1518350Y394370D02*
G02X1517562Y393049I-1575J44D01*
G01X1518350Y394458D02*
Y394370D01*
G01X1517562Y395779D02*
G02X1518350Y394458I-787J-1365D01*
G01X1516400Y397709D02*
G03X1517562Y395779I2325J85D01*
G01X1516400Y397879D02*
Y397709D01*
G01X1517562Y399809D02*
G03X1516400Y397879I1163J-2015D01*
G01X1519888Y399809D02*
G03X1517562I-1163J-2015D01*
G01X1521462D02*
G02X1519888I-787J1365D01*
G01X1523788D02*
G03X1521462I-1163J-2015D01*
G01X1524418Y399446D02*
X1523788Y399809D01*
G01X1525431Y399664D02*
G02X1524418Y399446I-855J1510D01*
G01X1527235Y399921D02*
G03X1525431Y399664I-575J-2421D01*
G01X1515200Y379360D02*
X1516395Y378165D01*
G01X1515200Y380938D02*
Y379360D01*
G01X1515988Y382259D02*
G03X1515200Y380938I787J-1365D01*
G01X1517150Y384189D02*
G02X1515988Y382259I-2325J85D01*
G01X1517150Y384318D02*
Y384189D01*
G01X1517938Y385639D02*
G03X1517150Y384318I787J-1365D01*
G01X1519100Y387569D02*
G02X1517938Y385639I-2325J85D01*
G01X1519100Y387739D02*
Y387569D01*
G01X1517938Y389669D02*
G02X1519100Y387739I-1163J-2015D01*
G01X1517938Y392399D02*
G03Y389669I787J-1365D01*
G01X1519100Y394329D02*
G02X1517938Y392399I-2325J85D01*
G01X1519100Y394499D02*
Y394329D01*
G01X1517938Y396429D02*
G02X1519100Y394499I-1163J-2015D01*
G01X1519512Y399159D02*
G03X1517938Y396429I-787J-1365D01*
G01X1521838Y399159D02*
G02X1519512I-1163J2015D01*
G01X1523412D02*
G03X1521838I-787J-1365D01*
G01X1524176Y398718D02*
X1523412Y399159D01*
G01X1525803Y399010D02*
G02X1524176Y398718I-1228J2164D01*
G01X1526986Y399204D02*
G03X1525803Y399010I-328J-1704D01*
G01X1527400Y399000D02*
X1526986Y399204D01*
G01X1495409Y402563D02*
Y403740D01*
G01X1494950Y401259D02*
G02X1495409Y402563I2325J-86D01*
G01X1494950Y401130D02*
Y401259D01*
G01X1494162Y399809D02*
G03X1494950Y401130I-787J1365D01*
G01X1493405Y399109D02*
G02X1494162Y399809I1919J-1316D01*
G01X1492329Y399109D02*
X1493405D01*
G01X1492075Y399363D02*
X1492329Y399109D01*
G01X1486875Y399363D02*
X1492075D01*
G01X1484978Y397466D02*
X1486875Y399363D01*
G01X1481487Y397466D02*
X1484978D01*
G01X1480252Y396231D02*
X1481487Y397466D01*
G01X1480252Y394190D02*
Y396231D01*
G01X1473962Y387900D02*
X1480252Y394190D01*
G01X1510550Y380979D02*
G02X1510925Y384274I14664J0D01*
G01X1510550Y380850D02*
Y380979D01*
G01X1509762Y379529D02*
G03X1510550Y380850I-787J1365D01*
G01X1508600Y377599D02*
G02X1509762Y379529I2325J-85D01*
G01X1508600Y372400D02*
Y377599D01*
G01X1510404Y370596D02*
X1508600Y372400D01*
G01X1510404Y361695D02*
Y370596D01*
G01X1509620Y360911D02*
X1510404Y361695D01*
G01X1509620Y351475D02*
Y360911D01*
G01X1509425Y351280D02*
X1509620Y351475D01*
G01X1509425Y349973D02*
Y351280D01*
G01X1513076Y346322D02*
X1509425Y349973D01*
G01X1495700Y401218D02*
G02X1496488Y402539I1575J-44D01*
G01X1495700Y401089D02*
Y401218D01*
G01X1494538Y399159D02*
G03X1495700Y401089I-1163J2015D01*
G01X1493750Y397838D02*
G02X1494538Y399159I1575J-44D01*
G01X1493750Y397709D02*
Y397838D01*
G01X1492588Y395779D02*
G03X1493750Y397709I-1163J2015D01*
G01X1491800Y394458D02*
G02X1492588Y395779I1575J-44D01*
G01X1491800Y394329D02*
Y394458D01*
G01X1490638Y392399D02*
G03X1491800Y394329I-1163J2015D01*
G01X1489850Y391078D02*
G02X1490638Y392399I1575J-44D01*
G01X1489850Y390949D02*
Y391078D01*
G01X1488688Y389019D02*
G03X1489850Y390949I-1163J2015D01*
G01X1487953Y388060D02*
G02X1488688Y389019I1522J-406D01*
G01X1510138Y392399D02*
G03X1511190Y393703I-1163J2015D01*
G01X1509350Y391078D02*
G02X1510138Y392399I1575J-44D01*
G01X1509350Y390949D02*
Y391078D01*
G01X1508188Y389019D02*
G03X1509350Y390949I-1163J2015D01*
G01X1507400Y387698D02*
G02X1508188Y389019I1575J-44D01*
G01X1507400Y387569D02*
Y387698D01*
G01X1506238Y385639D02*
G03X1507400Y387569I-1163J2015D01*
G01X1505450Y384318D02*
G02X1506238Y385639I1575J-44D01*
G01X1505450Y384189D02*
Y384318D01*
G01X1504288Y382259D02*
G03X1505450Y384189I-1163J2015D01*
G01X1503500Y380938D02*
G02X1504288Y382259I1575J-44D01*
G01X1503500Y380809D02*
Y380938D01*
G01X1502338Y378879D02*
G03X1503500Y380809I-1163J2015D01*
G01X1501550Y377558D02*
G02X1502338Y378879I1575J-44D01*
G01X1501550Y376434D02*
Y377558D01*
G01X1501800Y376184D02*
X1501550Y376434D01*
G01X1501800Y360900D02*
Y369465D01*
G01X1502112Y360588D02*
X1501800Y360900D01*
G01X1502112Y360152D02*
Y360588D01*
G01X1505450Y377558D02*
Y375500D01*
G01X1506238Y378879D02*
G03X1505450Y377558I787J-1365D01*
G01X1507400Y380809D02*
G02X1506238Y378879I-2325J85D01*
G01X1507400Y380938D02*
Y380809D01*
G01X1508188Y382259D02*
G03X1507400Y380938I787J-1365D01*
G01X1509350Y384189D02*
G02X1508188Y382259I-2325J85D01*
G01X1509350Y384318D02*
Y384189D01*
G01X1510138Y385639D02*
G03X1509350Y384318I787J-1365D01*
G01X1511300Y387569D02*
G02X1510138Y385639I-2325J85D01*
G01X1511300Y387698D02*
Y387569D01*
G01X1512088Y389019D02*
G03X1511300Y387698I787J-1365D01*
G01X1513250Y390949D02*
G02X1512088Y389019I-2325J85D01*
G01X1513250Y391078D02*
Y390949D01*
G01X1514038Y392399D02*
G03X1513250Y391078I787J-1365D01*
G01X1515188Y394158D02*
G02X1514038Y392399I-2312J256D01*
G01X1515444Y394414D02*
X1515188Y394158D01*
G01X1516775Y394414D02*
X1515444D01*
G01Y387654D02*
X1516775D01*
G01X1515188Y387398D02*
X1515444Y387654D01*
G01X1514038Y385639D02*
G03X1515188Y387398I-1162J2015D01*
G01X1513250Y384318D02*
G02X1514038Y385639I1575J-44D01*
G01X1513250Y384189D02*
Y384318D01*
G01X1512088Y382259D02*
G03X1513250Y384189I-1163J2015D01*
G01X1511300Y380938D02*
G02X1512088Y382259I1575J-44D01*
G01X1511300Y380809D02*
Y380938D01*
G01X1510138Y378879D02*
G03X1511300Y380809I-1163J2015D01*
G01X1509350Y377558D02*
G02X1510138Y378879I1575J-44D01*
G01X1509350Y373398D02*
Y377558D01*
G01X1509355Y373393D02*
X1509350Y373398D01*
G01X1512558Y402870D02*
X1514447Y404759D01*
G01X1522956Y412031D02*
X1527362D01*
G01X1519138Y408213D02*
X1522956Y412031D01*
G01X1517181Y408213D02*
X1519138D01*
G01X1514742Y405774D02*
X1517181Y408213D01*
G01X1511926Y405774D02*
X1514742D01*
G01X1525891Y406139D02*
X1529281D01*
G01X1525786Y406034D02*
X1525891Y406139D01*
G01X1523364Y406034D02*
X1525786D01*
G01X1523275Y406123D02*
X1523364Y406034D01*
G01X1521069Y406123D02*
X1523275D01*
G01X1519705Y404759D02*
X1521069Y406123D01*
G01X1514447Y404759D02*
X1519705D01*
G01X1579921Y190415D02*
X1590138Y180198D01*
G01X1579921Y196887D02*
Y190415D01*
G01X1530726Y406123D02*
X1527383Y402780D01*
G01X1537780D02*
X1536656Y403904D01*
G01X1541963Y402780D02*
X1537780D01*
G01X1527734Y399674D02*
X1527235Y399921D01*
G01X1528775Y399529D02*
G02X1527734Y399674I-301J1645D01*
G01X1529262Y399809D02*
X1528775Y399529D01*
G01X1531358Y399926D02*
G03X1529262Y399809I-932J-2132D01*
G01X1531710Y400020D02*
X1531358Y399926D01*
G01X1532375Y401174D02*
X1531710Y400020D01*
G01X1529044Y398816D02*
G02X1527400Y399000I-568J2358D01*
G01X1529638Y399159D02*
X1529044Y398816D01*
G01X1531006Y399258D02*
G03X1529638Y399159I-582J-1464D01*
G01X1531006Y398802D02*
Y399258D01*
G01X1530425Y397794D02*
X1531006Y398802D01*
G01X1572440Y459911D02*
X1574510Y461981D01*
G01X1572440Y459210D02*
Y459911D01*
G01X1571867Y458637D02*
X1572440Y459210D01*
G01X1571492Y458637D02*
X1571867D01*
G01X1570588Y458431D02*
G02X1571492Y458637I787J-1365D01*
G01X1568262Y458431D02*
G03X1570588I1163J2015D01*
G01X1566688D02*
G02X1568262I787J-1365D01*
G01X1564362D02*
G03X1566688I1163J2015D01*
G01X1562788D02*
G02X1564362I787J-1365D01*
G01X1560462D02*
G03X1562788I1163J2015D01*
G01X1559300Y460361D02*
G03X1560462Y458431I2325J85D01*
G01X1559300Y460490D02*
Y460361D01*
G01X1558512Y461811D02*
G02X1559300Y460490I-787J-1365D01*
G01X1556938Y461811D02*
G02X1558512I787J-1365D01*
G01X1556166Y460674D02*
G02X1556938Y461811I1559J-228D01*
G01X1556037Y459794D02*
X1556166Y460674D01*
G01X1556037Y459085D02*
Y459794D01*
G01X1556166Y458956D02*
X1556037Y459085D01*
G01X1556155Y458945D02*
X1556166Y458956D01*
G01X1531035Y412105D02*
X1531330Y411810D01*
G01X1528764Y412105D02*
X1531035D01*
G01X1528750Y412119D02*
X1528764Y412105D01*
G01X1527450Y412119D02*
X1528750D01*
G01X1527362Y412031D02*
X1527450Y412119D01*
G01X1561006Y457066D02*
X1559675D01*
G01X1561288Y456575D02*
X1561006Y457066D01*
G01X1562207Y455169D02*
G02X1561288Y456575I929J1611D01*
G01X1562412Y455051D02*
X1562207Y455169D01*
G01X1563800Y454700D02*
G02X1562412Y455051I-76J2619D01*
G01X1564944Y455150D02*
G02X1563800Y454700I-62753J157852D01*
G01X1566312Y455051D02*
G03X1564944Y455150I-786J-1365D01*
G01X1568638Y455051D02*
G02X1566312I-1163J2015D01*
G01X1570212D02*
G03X1568638I-787J-1365D01*
G01X1578128Y444600D02*
X1579537Y443191D01*
G01X1573325Y444600D02*
X1578128D01*
G01X1572162Y444911D02*
G03X1573325Y444600I1162J2016D01*
G01X1570588Y444911D02*
G02X1572162I787J-1365D01*
G01X1567475Y443546D02*
G03X1570588Y444911I-4636J14805D01*
G01X1535738Y406123D02*
X1530726D01*
G01X1536656Y405205D02*
X1535738Y406123D01*
G01X1536656Y403904D02*
Y405205D01*
G01X1557344Y437566D02*
Y435470D01*
G01X1559294Y439516D02*
X1557344Y437566D01*
G01X1559294Y440816D02*
Y439516D01*
G01X1558106Y442004D02*
X1559294Y440816D01*
G01X1558106Y444544D02*
Y442004D01*
G01X1559294Y445732D02*
X1558106Y444544D01*
G01X1559294Y447576D02*
Y445732D01*
G01X1560298Y448580D02*
X1559294Y447576D01*
G01X1574520Y448580D02*
X1560298D01*
G01X1577255Y451315D02*
X1574520Y448580D01*
G01X1577255Y453726D02*
Y451315D01*
G01X1581719Y458190D02*
X1577255Y453726D01*
G01X1589240Y458190D02*
X1581719D01*
G01X1588210Y462610D02*
X1589770Y461050D01*
G01X1584200Y462610D02*
X1588210D01*
G01X1571201Y459386D02*
X1571600Y459785D01*
G01X1570212Y459081D02*
G02X1571201Y459386I1163J-2015D01*
G01X1568638Y459081D02*
G03X1570212I787J1365D01*
G01X1566312D02*
G02X1568638I1163J-2015D01*
G01X1564738D02*
G03X1566312I787J1365D01*
G01X1562412D02*
G02X1564738I1163J-2015D01*
G01X1560838D02*
G03X1562412I787J1365D01*
G01X1560050Y460402D02*
G03X1560838Y459081I1575J44D01*
G01X1560050Y460531D02*
Y460402D01*
G01X1558888Y462461D02*
G02X1560050Y460531I-1163J-2015D01*
G01X1556562Y462461D02*
G02X1558888I1163J-2015D01*
G01X1555412Y460702D02*
G02X1556562Y462461I2312J-256D01*
G01X1555156Y460446D02*
X1555412Y460702D01*
G01X1553825Y460446D02*
X1555156D01*
G01X1584070Y448328D02*
X1612367D01*
G01X1539778Y406365D02*
X1539843Y406300D01*
G01X1539525Y406365D02*
X1539778D01*
G01X1538606Y407284D02*
X1539525Y406365D01*
G01X1538606Y407537D02*
Y407284D01*
G01X1538200Y407943D02*
X1538606Y407537D01*
G01X1538200Y408685D02*
Y407943D01*
G01X1536583Y410302D02*
X1538200Y408685D01*
G01X1532060Y410302D02*
X1536583D01*
G01X1530304Y408546D02*
X1532060Y410302D01*
G01X1530304Y407162D02*
Y408546D01*
G01X1529281Y406139D02*
X1530304Y407162D01*
G01X1627842Y80935D02*
X1629297Y79480D01*
G01X1627842Y84125D02*
Y80935D01*
G01X1626450Y85517D02*
X1627842Y84125D01*
G01X1590138Y180198D02*
Y180104D01*
G01X1590224Y181176D02*
X1590890Y180510D01*
G01X1590224Y182908D02*
X1591642Y181490D01*
G01X1589770Y458720D02*
X1589240Y458190D01*
G01X1589770Y461050D02*
Y458720D01*
G01X1620551Y460150D02*
X1624700D01*
G01X1614901Y465800D02*
X1620551Y460150D01*
G01X1637750Y445477D02*
X1639750D01*
G01X1630446Y438173D02*
X1637750Y445477D01*
G01X1619126Y438173D02*
X1630446D01*
G01X1613760Y443539D02*
X1619126Y438173D01*
G01X1613760Y446935D02*
Y443539D01*
G01X1612367Y448328D02*
X1613760Y446935D01*
G01X1611636Y465800D02*
X1614901D01*
G01X1824578Y138222D02*
X1822198Y140602D01*
G01X1833766Y138222D02*
X1824578D01*
G01X1842891Y147347D02*
X1833766Y138222D01*
G01X1833372Y139172D02*
X1842116Y147916D01*
G01X1824748Y139172D02*
X1833372D01*
G01X1842891Y172197D02*
Y147347D01*
G01X1842116Y147916D02*
Y172766D01*
G01X1857714Y108197D02*
X1853317D01*
G01X1859297Y109780D02*
X1857714Y108197D01*
G01X1859297Y116240D02*
Y109780D01*
G01X1850507Y125030D02*
X1859297Y116240D01*
G01X1850507Y139702D02*
Y125030D01*
G01X1851117Y140312D02*
X1850507Y139702D01*
G01X1851117Y150592D02*
Y140312D01*
G01X1853089Y152564D02*
X1851117Y150592D01*
G01X1853089Y153186D02*
Y152564D01*
G01X1853088Y153187D02*
X1853089Y153186D01*
G01X1853088Y160527D02*
Y153187D01*
G01X1848425Y177731D02*
X1842891Y172197D01*
G01X1848425Y184645D02*
Y177731D01*
G01X1842613Y190457D02*
X1848425Y184645D01*
G01X1842613Y204213D02*
Y190457D01*
G01X1849700Y211300D02*
X1842613Y204213D01*
G01X1849700Y211595D02*
Y211300D01*
G01X1850876Y212771D02*
X1849700Y211595D01*
G01X1850876Y212946D02*
Y212771D01*
G01X1848648Y211997D02*
X1847699Y212946D01*
G01X1848648Y211592D02*
Y211997D01*
G01X1841663Y204607D02*
X1848648Y211592D01*
G01X1841663Y190063D02*
Y204607D01*
G01X1847475Y184251D02*
X1841663Y190063D01*
G01X1847475Y178125D02*
Y184251D01*
G01X1842116Y172766D02*
X1847475Y178125D01*
G01X1854549Y161988D02*
X1853088Y160527D01*
G01X1854549Y166649D02*
Y161988D01*
G01X1855000Y167100D02*
X1854549Y166649D01*
G01X1930185Y526400D02*
X1925692Y530893D01*
G01X1957251Y518949D02*
X1949800Y526400D01*
G01X1958351Y518949D02*
X1957251D01*
G01X1959300Y518000D02*
X1958351Y518949D01*
G01X1907500Y540600D02*
Y545600D01*
G01X1917207Y530893D02*
X1907500Y540600D01*
G01X1925692Y530893D02*
X1917207D01*
G01X1949800Y526400D02*
X1930185D01*
G54D13*
G01X-20790Y379556D02*
Y475750D01*
G01X-17954Y376720D02*
X-20790Y379556D01*
G01X-9420Y376720D02*
X-17954D01*
G01X-20038Y381289D02*
Y459674D01*
G01X-16699Y377950D02*
X-20038Y381289D01*
G01X14683Y377950D02*
X-16699D01*
G01X-21542Y378652D02*
Y476062D01*
G01X-18290Y375400D02*
X-21542Y378652D01*
G01X-12525Y375400D02*
X-18290D01*
G01X-20038Y459674D02*
X-7309Y472403D01*
G01X-18886Y456638D02*
X-9280Y466244D01*
G01X-18886Y438492D02*
Y456638D01*
G01X-14488Y434094D02*
X-18886Y438492D01*
G01X-20790Y475750D02*
X-19802Y476738D01*
G01X-18690Y477850D02*
X-12500D01*
G01X-19802Y476738D02*
X-18690Y477850D01*
G01X-21378Y479691D02*
X-19783Y481286D01*
G01X-21378Y476226D02*
Y479691D01*
G01X-21542Y476062D02*
X-21378Y476226D01*
G01X-19327Y480830D02*
X-19783Y481286D01*
G01X-16980Y480830D02*
X-19327D01*
G01X-14960Y478810D02*
X-16980Y480830D01*
G01X-18372Y558826D02*
X-11378Y565820D01*
G01X-18372Y549313D02*
Y558826D01*
G01X-8559Y539500D02*
X-18372Y549313D01*
G01X39200Y28398D02*
X54374Y13224D01*
G01X39200Y80700D02*
Y28398D01*
G01X40200Y28745D02*
X55460Y13485D01*
G01X40200Y81314D02*
Y28745D01*
G01X36262Y83638D02*
X39200Y80700D01*
G01X36262Y88309D02*
Y83638D01*
G01X34000Y90571D02*
X36262Y88309D01*
G01X34000Y93350D02*
Y90571D01*
G01X37214Y84300D02*
X40200Y81314D01*
G01X37214Y89586D02*
Y84300D01*
G01X35650Y91150D02*
X37214Y89586D01*
G01X8238Y340225D02*
X14077Y346064D01*
G01X8238Y309303D02*
Y340225D01*
G01X5995Y307060D02*
X8238Y309303D01*
G01X5995Y303158D02*
Y307060D01*
G01X6806Y302347D02*
X5995Y303158D01*
G01X6954Y341209D02*
X13035Y347290D01*
G01X6954Y309635D02*
Y341209D01*
G01X5092Y307773D02*
X6954Y309635D01*
G01X5092Y303633D02*
Y307773D01*
G01X3806Y302347D02*
X5092Y303633D01*
G01X-5810Y373110D02*
X-9420Y376720D01*
G01X-4725Y373110D02*
X-5810D01*
G01X36430Y400680D02*
Y408725D01*
G01X29060Y393310D02*
X36430Y400680D01*
G01X-273Y393310D02*
X29060D01*
G01X-4725Y388858D02*
X-273Y393310D01*
G01X45530Y373730D02*
Y404085D01*
G01X41626Y369826D02*
X45530Y373730D01*
G01X41626Y353436D02*
Y369826D01*
G01X34254Y346064D02*
X41626Y353436D01*
G01X14077Y346064D02*
X34254D01*
G01X44000Y367300D02*
X47834Y371134D01*
G01X44000Y354900D02*
Y367300D01*
G01X46548Y352352D02*
X44000Y354900D01*
G01X45642Y355000D02*
X47200Y353442D01*
G01X45642Y367312D02*
Y355000D01*
G01X48986Y370656D02*
X45642Y367312D01*
G01X37500Y395300D02*
Y407671D01*
G01X34400Y392200D02*
X37500Y395300D01*
G01X660Y392200D02*
X34400D01*
G01X-1660Y389880D02*
X660Y392200D01*
G01X-1660Y386341D02*
Y389880D01*
G01X-3101Y384900D02*
X-1660Y386341D01*
G01X-5927Y384900D02*
X-3101D01*
G01X-9843Y380984D02*
X-5927Y384900D01*
G01X17716Y380983D02*
X14683Y377950D01*
G01X17716Y380984D02*
Y380983D01*
G01X38700Y402146D02*
X51645Y415091D01*
G01X38700Y389682D02*
Y402146D01*
G01X34618Y385600D02*
X38700Y389682D01*
G01X5797Y385600D02*
X34618D01*
G01X1181Y380984D02*
X5797Y385600D01*
G01X42848Y368248D02*
X46682Y372082D01*
G01X42848Y354000D02*
Y368248D01*
G01X45796Y351052D02*
X42848Y354000D01*
G01X45796Y342677D02*
Y351052D01*
G01X46848Y341625D02*
X45796Y342677D01*
G01X44578Y374125D02*
Y404480D01*
G01X40674Y370221D02*
X44578Y374125D01*
G01X40674Y354060D02*
Y370221D01*
G01X33904Y347290D02*
X40674Y354060D01*
G01X13035Y347290D02*
X33904D01*
G01X39900Y401716D02*
X54662Y416478D01*
G01X39900Y389000D02*
Y401716D01*
G01X35300Y384400D02*
X39900Y389000D01*
G01X8100Y384400D02*
X35300D01*
G01X6693Y382993D02*
X8100Y384400D01*
G01X6693Y380984D02*
Y382993D01*
G01X-10236Y373111D02*
X-12525Y375400D01*
G01X-10236Y373110D02*
Y373111D01*
G01X30641Y426698D02*
X74430Y470487D01*
G01X30641Y414514D02*
Y426698D01*
G01X36430Y408725D02*
X30641Y414514D01*
G01X45530Y404085D02*
X55205Y413760D01*
G01X45637Y416734D02*
X46100Y416271D01*
G01X45637Y426417D02*
Y416734D01*
G01X72240Y453020D02*
X45637Y426417D01*
G01X37500Y407671D02*
X46100Y416271D01*
G01X44578Y404480D02*
X54810Y414712D01*
G01X46100Y413520D02*
X47676Y415096D01*
G01X21610Y476080D02*
X59120D01*
G01X20013Y477677D02*
X21610Y476080D01*
G01X8686Y477677D02*
X20013D01*
G01X4349Y473340D02*
X8686Y477677D01*
G01X-7990Y473340D02*
X4349D01*
G01X-12500Y477850D02*
X-7990Y473340D01*
G01X2887Y520882D02*
X6748Y517021D01*
G01X2887Y524390D02*
Y520882D01*
G01X8383Y529886D02*
X2887Y524390D01*
G01X31130Y473640D02*
X65848D01*
G01X29893Y472403D02*
X31130Y473640D01*
G01X-7309Y472403D02*
X29893D01*
G01X3354Y518773D02*
Y517143D01*
G01X1965Y520162D02*
X3354Y518773D01*
G01X1965Y524815D02*
Y520162D01*
G01X7988Y530838D02*
X1965Y524815D01*
G01X-8501Y526100D02*
X-4744Y529857D01*
G01X-9600Y526100D02*
X-8501D01*
G01X31570Y472270D02*
X67220D01*
G01X30551Y471251D02*
X31570Y472270D01*
G01X-6831Y471251D02*
X30551D01*
G01X-9280Y468802D02*
X-6831Y471251D01*
G01X-9280Y466244D02*
Y468802D01*
G01X-12149Y478810D02*
X-14960D01*
G01X-7606Y474267D02*
X-12149Y478810D01*
G01X3758Y474267D02*
X-7606D01*
G01X8318Y478827D02*
X3758Y474267D01*
G01X20355Y478827D02*
X8318D01*
G01X22175Y477007D02*
X20355Y478827D01*
G01X58736Y477007D02*
X22175D01*
G01X13961Y529886D02*
X8383D01*
G01X16612Y527235D02*
X13961Y529886D01*
G01X42894Y527235D02*
X16612D01*
G01X46485Y530826D02*
X42894Y527235D01*
G01X14073Y530838D02*
X7988D01*
G01X16766Y528145D02*
X14073Y530838D01*
G01X42457Y528145D02*
X16766D01*
G01X46090Y531778D02*
X42457Y528145D01*
G01X69541Y531778D02*
X46090D01*
G01X-265Y564164D02*
X50184D01*
G01X-1921Y565820D02*
X-265Y564164D01*
G01X-11378Y565820D02*
X-1921D01*
G01X-5670Y539500D02*
X-8559D01*
G01X-4744Y538574D02*
X-5670Y539500D01*
G01X-4744Y529857D02*
Y538574D01*
G01X104450Y-56200D02*
X100500Y-52250D01*
G01X145030Y-56200D02*
X104450D01*
G01X94864Y-18000D02*
X93500D01*
G01X98116Y-21252D02*
X94864Y-18000D01*
G01X406549Y-21252D02*
X98116D01*
G01X98940Y-20500D02*
X406237D01*
G01X94842Y-16402D02*
X98940Y-20500D01*
G01X92502Y-16402D02*
X94842D01*
G01X88404Y-20500D02*
X92502Y-16402D01*
G01X81024Y-20500D02*
X88404D01*
G01X79891Y-21633D02*
X81024Y-20500D01*
G01X68452Y-21633D02*
X79891D01*
G01X67564Y-20745D02*
X68452Y-21633D01*
G01X99564Y-18996D02*
X405047D01*
G01X95376Y-14808D02*
X99564Y-18996D01*
G01X91968Y-14808D02*
X95376D01*
G01X87780Y-18996D02*
X91968Y-14808D01*
G01X78062Y-18996D02*
X87780D01*
G01X71844Y-12778D02*
X78062Y-18996D01*
G01X66972Y-12778D02*
X71844D01*
G01X66061Y-13689D02*
X66972Y-12778D01*
G01X65550Y-19070D02*
X65164Y-19456D01*
G01X68606Y-19070D02*
X65550D01*
G01X70374Y-20838D02*
X68606Y-19070D01*
G01X79495Y-20838D02*
X70374D01*
G01X80585Y-19748D02*
X79495Y-20838D01*
G01X88092Y-19748D02*
X80585D01*
G01X92220Y-15620D02*
X88092Y-19748D01*
G01X95124Y-15620D02*
X92220D01*
G01X99252Y-19748D02*
X95124Y-15620D01*
G01X405359Y-19748D02*
X99252D01*
G01X97656Y19477D02*
X369059D01*
G01X97429Y19704D02*
X97656Y19477D01*
G01X79776Y19704D02*
X97429D01*
G01X71375Y11303D02*
X79776Y19704D01*
G01X64159Y11303D02*
X71375D01*
G01X100188Y-17492D02*
X403857D01*
G01X96000Y-13304D02*
X100188Y-17492D01*
G01X90178Y-13304D02*
X96000D01*
G01X87091Y-16391D02*
X90178Y-13304D01*
G01X65331Y-11218D02*
X63683Y-12866D01*
G01X71348Y-11218D02*
X65331D01*
G01X78374Y-18244D02*
X71348Y-11218D01*
G01X87468Y-18244D02*
X78374D01*
G01X91656Y-14056D02*
X87468Y-18244D01*
G01X95688Y-14056D02*
X91656D01*
G01X99876Y-18244D02*
X95688Y-14056D01*
G01X404735Y-18244D02*
X99876D01*
G01X107200Y-8967D02*
X113821Y-15588D01*
G01X107200Y-1400D02*
Y-8967D01*
G01X104907Y893D02*
X107200Y-1400D01*
G01X91165Y893D02*
X104907D01*
G01X81264Y-9008D02*
X91165Y893D01*
G01X64217Y-9008D02*
X81264D01*
G01X54374Y835D02*
X64217Y-9008D01*
G01X54374Y13224D02*
Y835D01*
G01X105302Y1845D02*
X108153Y-1006D01*
G01X90692Y1845D02*
X105302D01*
G01X80826Y-8021D02*
X90692Y1845D01*
G01X64953Y-8021D02*
X80826D01*
G01X55460Y1472D02*
X64953Y-8021D01*
G01X55460Y13485D02*
Y1472D01*
G01X107850Y211040D02*
X109810Y213000D01*
G01X107700Y211040D02*
X107850D01*
G01X105147Y211047D02*
X102507D01*
G01X108880Y214780D02*
X105147Y211047D01*
G01X79505Y213137D02*
Y267865D01*
G01X90831Y201811D02*
X79505Y213137D01*
G01X90831Y184982D02*
Y201811D01*
G01X107706Y267245D02*
Y290403D01*
G01X112705Y262246D02*
X107706Y267245D01*
G01X106710Y266832D02*
X111953Y261589D01*
G01X106710Y289990D02*
Y266832D01*
G01X61905Y273213D02*
X55018Y280100D01*
G01X74157Y273213D02*
X61905D01*
G01X79505Y267865D02*
X74157Y273213D01*
G01X106150Y305850D02*
X103500Y308500D01*
G01X106150Y291959D02*
Y305850D01*
G01X107706Y290403D02*
X106150Y291959D01*
G01X67400Y339529D02*
X65529Y341400D01*
G01X67400Y337168D02*
Y339529D01*
G01X68418Y336150D02*
X67400Y337168D01*
G01X102322Y294378D02*
X106710Y289990D01*
G01X102322Y295478D02*
Y294378D01*
G01X47600Y334748D02*
Y341937D01*
G01X50908Y331440D02*
X47600Y334748D01*
G01X54560Y331440D02*
X50908D01*
G01X57330Y328670D02*
X54560Y331440D01*
G01X57330Y323430D02*
Y328670D01*
G01X48677Y314777D02*
X57330Y323430D01*
G01X48677Y301777D02*
Y314777D01*
G01X48550Y301650D02*
X48677Y301777D01*
G01X70724Y320424D02*
X72100Y321800D01*
G01X64033Y320424D02*
X70724D01*
G01X58408Y326049D02*
X64033Y320424D01*
G01X58408Y331392D02*
Y326049D01*
G01X54220Y335580D02*
X58408Y331392D01*
G01X51670Y335580D02*
X54220D01*
G01X50800Y336450D02*
X51670Y335580D01*
G01X50800Y341400D02*
Y336450D01*
G01X107043Y326347D02*
X103200Y330190D01*
G01X107043Y292205D02*
Y326347D01*
G01X108511Y290737D02*
X107043Y292205D01*
G01X86296Y338304D02*
X87400Y337200D01*
G01X82366Y338304D02*
X86296D01*
G01X77021Y343649D02*
X82366Y338304D01*
G01X46848Y334436D02*
Y341625D01*
G01X50694Y330590D02*
X46848Y334436D01*
G01X54346Y330590D02*
X50694D01*
G01X56578Y328358D02*
X54346Y330590D01*
G01X56578Y323742D02*
Y328358D01*
G01X46752Y313916D02*
X56578Y323742D01*
G01X46752Y282419D02*
Y313916D01*
G01X48700Y280471D02*
X46752Y282419D01*
G01X48700Y280452D02*
Y280471D01*
G01X49052Y280100D02*
X48700Y280452D01*
G01X55018Y280100D02*
X49052D01*
G01X56300Y340629D02*
Y338500D01*
G01X54561Y342368D02*
X56300Y340629D01*
G01X73288Y393719D02*
Y427462D01*
G01X66984Y387415D02*
X73288Y393719D01*
G01X61556Y387415D02*
X66984D01*
G01X52988Y378847D02*
X61556Y387415D01*
G01X52988Y362201D02*
Y378847D01*
G01X55873Y359316D02*
X52988Y362201D01*
G01X55873Y349468D02*
Y359316D01*
G01X63941Y341400D02*
X55873Y349468D01*
G01X65529Y341400D02*
X63941D01*
G01X47834Y394695D02*
X70280Y417141D01*
G01X47834Y371134D02*
Y394695D01*
G01X46548Y342989D02*
Y352352D01*
G01X47600Y341937D02*
X46548Y342989D01*
G01X49974Y342226D02*
X50800Y341400D01*
G01X48375Y342226D02*
X49974D01*
G01X47300Y343301D02*
X48375Y342226D01*
G01X47300Y352664D02*
Y343301D01*
G01X47200Y352764D02*
X47300Y352664D01*
G01X47200Y353442D02*
Y352764D01*
G01X48986Y386779D02*
Y370656D01*
G01X62627Y400420D02*
X48986Y386779D01*
G01X68319Y400420D02*
X62627D01*
G01X71032Y403133D02*
X68319Y400420D01*
G01X63322Y343649D02*
X77021D01*
G01X57089Y349882D02*
X63322Y343649D01*
G01X57089Y359730D02*
Y349882D01*
G01X53900Y362919D02*
X57089Y359730D01*
G01X53900Y378129D02*
Y362919D01*
G01X62034Y386263D02*
X53900Y378129D01*
G01X67462Y386263D02*
X62034D01*
G01X74040Y392841D02*
X67462Y386263D01*
G01X74040Y426584D02*
Y392841D01*
G01X46682Y372082D02*
Y403411D01*
G01X91836Y396470D02*
Y429765D01*
G01X85609Y390243D02*
X91836Y396470D01*
G01X85609Y385234D02*
Y390243D01*
G01X48352Y354500D02*
X49100D01*
G01X46394Y356458D02*
X48352Y354500D01*
G01X46394Y366434D02*
Y356458D01*
G01X50138Y370178D02*
X46394Y366434D01*
G01X50138Y386867D02*
Y370178D01*
G01X62392Y399121D02*
X50138Y386867D01*
G01X68650Y399121D02*
X62392D01*
G01X71784Y402255D02*
X68650Y399121D01*
G01X71784Y429464D02*
Y402255D01*
G01X54561Y358998D02*
Y342368D01*
G01X51836Y361723D02*
X54561Y358998D01*
G01X51836Y379325D02*
Y361723D01*
G01X61078Y388567D02*
X51836Y379325D01*
G01X66506Y388567D02*
X61078D01*
G01X72536Y394597D02*
X66506Y388567D01*
G01X72536Y428340D02*
Y394597D01*
G01X84453Y449453D02*
Y480475D01*
G01X67092Y432092D02*
X84453Y449453D01*
G01X67092Y422992D02*
Y432092D01*
G01X57860Y413760D02*
X67092Y422992D01*
G01X55205Y413760D02*
X57860D01*
G01X103268Y450240D02*
X133894Y480866D01*
G01X96066Y450240D02*
X103268D01*
G01X73288Y427462D02*
X96066Y450240D01*
G01X86793Y447733D02*
Y480121D01*
G01X70280Y431220D02*
X86793Y447733D01*
G01X70280Y417141D02*
Y431220D01*
G01X71032Y430342D02*
Y403133D01*
G01X87545Y446855D02*
X71032Y430342D01*
G01X87545Y479809D02*
Y446855D01*
G01X72240Y456443D02*
Y453020D01*
G01X78270Y462473D02*
X72240Y456443D01*
G01X78270Y483796D02*
Y462473D01*
G01X81276Y458963D02*
Y498655D01*
G01X77252Y454939D02*
X81276Y458963D01*
G01X77252Y450898D02*
Y454939D01*
G01X54448Y428094D02*
X77252Y450898D01*
G01X54448Y419084D02*
Y428094D01*
G01X51645Y416281D02*
X54448Y419084D01*
G01X51645Y415091D02*
Y416281D01*
G01X96544Y449088D02*
X74040Y426584D01*
G01X103746Y449088D02*
X96544D01*
G01X134372Y479714D02*
X103746Y449088D01*
G01X86041Y448611D02*
Y480433D01*
G01X69344Y431914D02*
X86041Y448611D01*
G01X69344Y417835D02*
Y431914D01*
G01X64069Y412560D02*
X69344Y417835D01*
G01X55831Y412560D02*
X64069D01*
G01X46682Y403411D02*
X55831Y412560D01*
G01X83501Y449848D02*
Y480870D01*
G01X66140Y432487D02*
X83501Y449848D01*
G01X66140Y423387D02*
Y432487D01*
G01X57465Y414712D02*
X66140Y423387D01*
G01X54810Y414712D02*
X57465D01*
G01X98787Y436716D02*
X114756D01*
G01X91836Y429765D02*
X98787Y436716D01*
G01X79422Y461995D02*
Y484274D01*
G01X73470Y456043D02*
X79422Y461995D01*
G01X73470Y452035D02*
Y456043D01*
G01X46789Y425354D02*
X73470Y452035D01*
G01X46789Y417969D02*
Y425354D01*
G01X47676Y417082D02*
X46789Y417969D01*
G01X47676Y415096D02*
Y417082D01*
G01X95011Y452691D02*
X71784Y429464D01*
G01X102650Y452691D02*
X95011D01*
G01X133129Y483170D02*
X102650Y452691D01*
G01X82228Y458464D02*
Y498260D01*
G01X78397Y454633D02*
X82228Y458464D01*
G01X78397Y450696D02*
Y454633D01*
G01X55400Y427699D02*
X78397Y450696D01*
G01X55400Y417216D02*
Y427699D01*
G01X54662Y416478D02*
X55400Y417216D01*
G01X95588Y451392D02*
X72536Y428340D01*
G01X102790Y451392D02*
X95588D01*
G01X133416Y482018D02*
X102790Y451392D01*
G01X65450Y476620D02*
Y475610D01*
G01X64920Y477150D02*
X65450Y476620D01*
G01X60190Y477150D02*
X64920D01*
G01X59120Y476080D02*
X60190Y477150D01*
G01X86100Y503410D02*
Y505200D01*
G01X87390Y502120D02*
X86100Y503410D01*
G01X98697Y502120D02*
X87390D01*
G01X118948Y522371D02*
X98697Y502120D01*
G01X73599Y525015D02*
X86305Y537721D01*
G01X73599Y514466D02*
Y525015D01*
G01X65540Y506407D02*
X73599Y514466D01*
G01X65540Y488560D02*
Y506407D01*
G01X74430Y479670D02*
X65540Y488560D01*
G01X74430Y470487D02*
Y479670D01*
G01X97879Y489682D02*
X110718Y502521D01*
G01X93660Y489682D02*
X97879D01*
G01X84453Y480475D02*
X93660Y489682D01*
G01X94450Y487778D02*
X579982D01*
G01X86793Y480121D02*
X94450Y487778D01*
G01X94762Y487026D02*
X87545Y479809D01*
G01X580860Y487026D02*
X94762D01*
G01X70231Y491835D02*
X78270Y483796D01*
G01X70231Y505791D02*
Y491835D01*
G01X78452Y514012D02*
X70231Y505791D01*
G01X78452Y515700D02*
Y514012D01*
G01X88404Y525652D02*
X78452Y515700D01*
G01X93054Y525652D02*
X88404D01*
G01X93502Y526100D02*
X93054Y525652D01*
G01X97605Y526100D02*
X93502D01*
G01X104606Y533101D02*
X97605Y526100D01*
G01X72847Y525327D02*
X85552Y538032D01*
G01X72847Y515035D02*
Y525327D01*
G01X66236Y508424D02*
X72847Y515035D01*
G01X66217Y508424D02*
X66236D01*
G01X64788Y506995D02*
X66217Y508424D01*
G01X64788Y485712D02*
Y506995D01*
G01X69083Y481417D02*
X64788Y485712D01*
G01X69083Y476875D02*
Y481417D01*
G01X65848Y473640D02*
X69083Y476875D01*
G01X90196Y523700D02*
X88855Y522359D01*
G01X98532Y523700D02*
X90196D01*
G01X110404Y535572D02*
X98532Y523700D01*
G01X81276Y514780D02*
X88855Y522359D01*
G01X81276Y509247D02*
Y514780D01*
G01X83188Y507335D02*
X81276Y509247D01*
G01X83188Y500567D02*
Y507335D01*
G01X81276Y498655D02*
X83188Y500567D01*
G01X98423Y488530D02*
X110385Y500492D01*
G01X94138Y488530D02*
X98423D01*
G01X86041Y480433D02*
X94138Y488530D01*
G01X97484Y490634D02*
X110323Y503473D01*
G01X93265Y490634D02*
X97484D01*
G01X83501Y480870D02*
X93265Y490634D01*
G01X90598Y478100D02*
X89497Y479201D01*
G01X96647Y478100D02*
X90598D01*
G01X103069Y484522D02*
X96647Y478100D01*
G01X581050Y484522D02*
X103069D01*
G01X102674Y485474D02*
X580938D01*
G01X96252Y479052D02*
X102674Y485474D01*
G01X93672Y479052D02*
X96252D01*
G01X92326Y480398D02*
X93672Y479052D01*
G01X70260Y477880D02*
X71050Y478670D01*
G01X70260Y475310D02*
Y477880D01*
G01X67220Y472270D02*
X70260Y475310D01*
G01X98035Y524900D02*
X109252Y536117D01*
G01X88716Y524900D02*
X98035D01*
G01X79204Y515388D02*
X88716Y524900D01*
G01X79204Y513700D02*
Y515388D01*
G01X70983Y505479D02*
X79204Y513700D01*
G01X70983Y492713D02*
Y505479D01*
G01X79422Y484274D02*
X70983Y492713D01*
G01X92398Y522748D02*
X91650Y522000D01*
G01X98927Y522748D02*
X92398D01*
G01X111356Y535177D02*
X98927Y522748D01*
G01X90250Y520600D02*
X91650Y522000D01*
G01X88700Y520600D02*
X90250D01*
G01X82228Y514128D02*
X88700Y520600D01*
G01X82228Y509642D02*
Y514128D01*
G01X84140Y507730D02*
X82228Y509642D01*
G01X84140Y500172D02*
Y507730D01*
G01X82228Y498260D02*
X84140Y500172D01*
G01X59806Y478077D02*
X58736Y477007D01*
G01X67340Y478077D02*
X59806D01*
G01X67477Y477940D02*
X67340Y478077D01*
G01X86305Y537721D02*
Y590672D01*
G01X69936Y530826D02*
X46485D01*
G01X75010Y535900D02*
X69936Y530826D01*
G01X81400Y535900D02*
X75010D01*
G01X84400Y538900D02*
X81400Y535900D01*
G01X84400Y593094D02*
Y538900D01*
G01X104606Y538134D02*
Y533101D01*
G01X108100Y541628D02*
X104606Y538134D01*
G01X85552Y538032D02*
Y591000D01*
G01X74615Y536852D02*
X69541Y531778D01*
G01X81005Y536852D02*
X74615D01*
G01X83448Y539295D02*
X81005Y536852D01*
G01X83448Y593489D02*
Y539295D01*
G01X56000Y569980D02*
Y610000D01*
G01X50184Y564164D02*
X56000Y569980D01*
G01X92633Y597000D02*
X108546D01*
G01X86305Y590672D02*
X92633Y597000D01*
G01X102891Y616109D02*
X114719D01*
G01X98100Y620900D02*
X102891Y616109D01*
G01X91952Y620900D02*
X98100D01*
G01X90806Y599500D02*
X84400Y593094D01*
G01X105000Y599500D02*
X90806D01*
G01X114348Y608848D02*
X105000Y599500D01*
G01X105252Y597752D02*
X115500Y608000D01*
G01X90688Y597752D02*
X105252D01*
G01X85553Y592617D02*
X90688Y597752D01*
G01X85553Y591000D02*
Y592617D01*
G01X85552Y591000D02*
X85553D01*
G01X90411Y600452D02*
X83448Y593489D01*
G01X104605Y600452D02*
X90411D01*
G01X113396Y609243D02*
X104605Y600452D01*
G01X103239Y617261D02*
X114241D01*
G01X96750Y623750D02*
X103239Y617261D01*
G01X69750Y623750D02*
X96750D01*
G01X56000Y610000D02*
X69750Y623750D01*
G01X147382Y-53848D02*
X145030Y-56200D01*
G01X445509Y-53848D02*
X147382D01*
G01X148901Y-50496D02*
X445509D01*
G01X116696Y804D02*
X114000Y3500D01*
G01X619196Y804D02*
X116696D01*
G01X118196Y2024D02*
X114100Y6120D01*
G01X622106Y2024D02*
X118196D01*
G01X113821Y-15588D02*
X402411D01*
G01X114216Y-14636D02*
X402016D01*
G01X108152Y-8572D02*
X114216Y-14636D01*
G01X108152Y-1795D02*
Y-8572D01*
G01X108153Y-1794D02*
X108152Y-1795D01*
G01X108153Y-1006D02*
Y-1794D01*
G01X109810Y213000D02*
Y218286D01*
G01X108880Y218672D02*
Y214780D01*
G01X110740Y212620D02*
Y217900D01*
G01X124340Y199020D02*
X110740Y212620D01*
G01X124340Y197750D02*
Y199020D01*
G01X112705Y245611D02*
Y262246D01*
G01X110450Y243356D02*
X112705Y245611D01*
G01X110450Y234604D02*
Y243356D01*
G01X111400Y233654D02*
X110450Y234604D01*
G01X111400Y219876D02*
Y233654D01*
G01X109810Y218286D02*
X111400Y219876D01*
G01X110470Y220262D02*
X108880Y218672D01*
G01X110470Y233268D02*
Y220262D01*
G01X109590Y234148D02*
X110470Y233268D01*
G01X109590Y243812D02*
Y234148D01*
G01X111953Y246175D02*
X109590Y243812D01*
G01X111953Y261589D02*
Y246175D01*
G01X108511Y267579D02*
Y290737D01*
G01X113510Y262580D02*
X108511Y267579D01*
G01X113510Y245100D02*
Y262580D01*
G01X111280Y242870D02*
X113510Y245100D01*
G01X111280Y235090D02*
Y242870D01*
G01X112330Y234040D02*
X111280Y235090D01*
G01X112330Y219490D02*
Y234040D01*
G01X110740Y217900D02*
X112330Y219490D01*
G01X145939Y422239D02*
X148409D01*
G01X143700Y420000D02*
X145939Y422239D01*
G01X143700Y414500D02*
Y420000D01*
G01X145303Y412897D02*
X143700Y414500D01*
G01X149204Y412897D02*
X145303D01*
G01X150671Y414364D02*
X149204Y412897D01*
G01X150671Y414450D02*
Y414364D01*
G01X151594Y415373D02*
X150671Y414450D01*
G01X151680Y415373D02*
X151594D01*
G01X208221Y471914D02*
X151680Y415373D01*
G01X154025Y422731D02*
X207524Y476230D01*
G01X153034Y422731D02*
X154025D01*
G01X149564Y419261D02*
X153034Y422731D01*
G01X147961Y419261D02*
X149564D01*
G01X146700Y418000D02*
X147961Y419261D01*
G01X146700Y415400D02*
Y418000D01*
G01X147500Y414600D02*
X146700Y415400D01*
G01X148300Y414600D02*
X147500D01*
G01X150833Y417132D02*
X207351Y473650D01*
G01X149195Y417132D02*
X150833D01*
G01X148930Y417397D02*
X149195Y417132D01*
G01X148666Y417397D02*
X148930D01*
G01X114756Y436716D02*
X156240Y478200D01*
G01X138671Y522371D02*
X118948D01*
G01X144300Y528000D02*
X138671Y522371D01*
G01X110718Y502521D02*
X337605D01*
G01X133894Y480866D02*
X580586D01*
G01X580470Y479714D02*
X134372D01*
G01X112698Y501369D02*
X336659D01*
G01X112614Y501453D02*
X112698Y501369D01*
G01X111308Y501453D02*
X112614D01*
G01X110385Y500530D02*
X111308Y501453D01*
G01X110385Y500492D02*
Y500530D01*
G01X110323Y503473D02*
X338283D01*
G01X156240Y478200D02*
X581126D01*
G01X580762Y483170D02*
X133129D01*
G01X580674Y482018D02*
X133416D01*
G01X144300Y540207D02*
Y528000D01*
G01X145875Y541782D02*
X144300Y540207D01*
G01X368574Y541782D02*
X145875D01*
G01X108100Y588660D02*
Y541628D01*
G01X110404Y576951D02*
Y535572D01*
G01X113405Y579952D02*
X110404Y576951D01*
G01X367896Y579952D02*
X113405D01*
G01X109252Y536117D02*
Y588182D01*
G01X111356Y576556D02*
Y535177D01*
G01X113800Y579000D02*
X111356Y576556D01*
G01X367501Y579000D02*
X113800D01*
G01X113200Y601654D02*
X625860D01*
G01X108546Y597000D02*
X113200Y601654D01*
G01X117366Y618756D02*
X392133D01*
G01X114719Y616109D02*
X117366Y618756D01*
G01X114348Y612349D02*
Y608848D01*
G01X118651Y616652D02*
X114348Y612349D01*
G01X391000Y616652D02*
X118651D01*
G01X117096Y597656D02*
X108100Y588660D01*
G01X620443Y597656D02*
X117096D01*
G01X119500Y615500D02*
X390499D01*
G01X115500Y611500D02*
X119500Y615500D01*
G01X115500Y608000D02*
Y611500D01*
G01X113396Y612744D02*
Y609243D01*
G01X118256Y617604D02*
X113396Y612744D01*
G01X391395Y617604D02*
X118256D01*
G01X116488Y619508D02*
X393011D01*
G01X114241Y617261D02*
X116488Y619508D01*
G01X117574Y596504D02*
X619965D01*
G01X109252Y588182D02*
X117574Y596504D01*
G01X582121Y471914D02*
X208221D01*
G01X207524Y476230D02*
X581623D01*
G01X207351Y473650D02*
X581450D01*
G01X349941Y490185D02*
X475971D01*
G01X337605Y502521D02*
X349941Y490185D01*
G01X348995Y489033D02*
X579607D01*
G01X336659Y501369D02*
X348995Y489033D01*
G01X350419Y491337D02*
X475493D01*
G01X338283Y503473D02*
X350419Y491337D01*
G01X409425Y-18376D02*
X406549Y-21252D01*
G01X454988Y-18376D02*
X409425D01*
G01X409113Y-17624D02*
X650723D01*
G01X406237Y-20500D02*
X409113Y-17624D01*
G01X407923Y-16120D02*
X649533D01*
G01X405047Y-18996D02*
X407923Y-16120D01*
G01X408235Y-16872D02*
X405359Y-19748D01*
G01X649845Y-16872D02*
X408235D01*
G01X390545Y19077D02*
X623622D01*
G01X389918Y19704D02*
X390545Y19077D01*
G01X386456Y19704D02*
X389918D01*
G01X382043Y15291D02*
X386456Y19704D01*
G01X373245Y15291D02*
X382043D01*
G01X369059Y19477D02*
X373245Y15291D01*
G01X406733Y-14616D02*
X647777D01*
G01X403857Y-17492D02*
X406733Y-14616D01*
G01X407611Y-15368D02*
X404735Y-18244D01*
G01X649221Y-15368D02*
X407611D01*
G01X405287Y-12712D02*
X621344D01*
G01X402411Y-15588D02*
X405287Y-12712D01*
G01X404892Y-11760D02*
X620949D01*
G01X402016Y-14636D02*
X404892Y-11760D01*
G01X374892Y548100D02*
X368574Y541782D01*
G01X378682Y548100D02*
X374892D01*
G01X385137Y541645D02*
X378682Y548100D01*
G01X614555Y541645D02*
X385137D01*
G01X372748Y575100D02*
X367896Y579952D01*
G01X381254Y575100D02*
X372748D01*
G01X387106Y580952D02*
X381254Y575100D01*
G01X620727Y580952D02*
X387106D01*
G01X372353Y574148D02*
X367501Y579000D01*
G01X381649Y574148D02*
X372353D01*
G01X387501Y580000D02*
X381649Y574148D01*
G01X621122Y580000D02*
X387501D01*
G01X393133Y617756D02*
X642348D01*
G01X392133Y618756D02*
X393133Y617756D01*
G01X392000Y615652D02*
X391000Y616652D01*
G01X626122Y615652D02*
X392000D01*
G01X391499Y614500D02*
X619280D01*
G01X390499Y615500D02*
X391499Y614500D01*
G01X392395Y616604D02*
X391395Y617604D01*
G01X626397Y616604D02*
X392395D01*
G01X394011Y618508D02*
X645890D01*
G01X393011Y619508D02*
X394011Y618508D01*
G01X445509Y-50496D02*
G02Y-53848I0J-1676D01*
G01X457112Y-20500D02*
X454988Y-18376D01*
G01X648000Y-20500D02*
X457112D01*
G01X475102Y207268D02*
Y236276D01*
G01X485135Y197235D02*
X475102Y207268D01*
G01X468342Y209904D02*
Y240246D01*
G01X481766Y196480D02*
X468342Y209904D01*
G01X471722Y208478D02*
X483066Y197134D01*
G01X471722Y238298D02*
Y208478D01*
G01X477703Y237817D02*
X479437Y239551D01*
G01X476643Y237817D02*
X477703D01*
G01X475102Y236276D02*
X476643Y237817D01*
G01X477400Y245350D02*
X479346Y247296D01*
G01X475940Y245350D02*
X477400D01*
G01X473892Y243302D02*
X475940Y245350D01*
G01X472371Y243302D02*
X473892D01*
G01X470688Y241619D02*
X472371Y243302D01*
G01X469715Y241619D02*
X470688D01*
G01X468342Y240246D02*
X469715Y241619D01*
G01X472914Y239490D02*
X471722Y238298D01*
G01X473771Y239490D02*
X472914D01*
G01X475616Y241335D02*
X473771Y239490D01*
G01X477299Y241335D02*
X475616D01*
G01X479124Y243160D02*
X477299Y241335D01*
G01X475971Y490185D02*
X486690Y500904D01*
G01X475493Y491337D02*
X486212Y502056D01*
G01X421454Y610982D02*
Y612560D01*
G01X429630Y602806D02*
X421454Y610982D01*
G01X627079Y602806D02*
X429630D01*
G01X508012Y134228D02*
X485135Y157105D01*
G01X582840Y134228D02*
X508012D01*
G01X509539Y138511D02*
X489303Y158747D01*
G01X585089Y138511D02*
X509539D01*
G01X481766Y155230D02*
Y196480D01*
G01X505516Y131480D02*
X481766Y155230D01*
G01X581688Y131480D02*
X505516D01*
G01X508676Y135680D02*
X486543Y157813D01*
G01X583488Y135680D02*
X508676D01*
G01X509155Y137265D02*
X488151Y158269D01*
G01X583936Y137265D02*
X509155D01*
G01X507428Y132820D02*
X582049D01*
G01X483066Y157182D02*
X507428Y132820D01*
G01X485135Y157105D02*
Y197235D01*
G01X489303Y158747D02*
Y229282D01*
G01X478482Y205796D02*
Y234397D01*
G01X479401Y204877D02*
X478482Y205796D01*
G01X479423Y204877D02*
X479401D01*
G01X486543Y197757D02*
X479423Y204877D01*
G01X486543Y157813D02*
Y197757D01*
G01X488382Y209695D02*
Y231812D01*
G01X488151Y209464D02*
X488382Y209695D01*
G01X488151Y158269D02*
Y209464D01*
G01X483066Y197134D02*
Y157182D01*
G01X523400Y245165D02*
X521731Y243496D01*
G01X523400Y250300D02*
Y245165D01*
G01X532809Y235365D02*
X531434D01*
G01X532877Y235297D02*
X532809Y235365D01*
G01X533263Y235137D02*
X532877Y235297D01*
G01X534300Y234100D02*
X533263Y235137D01*
G01X536451Y233209D02*
X534300Y234100D01*
G01X537189Y232471D02*
X536451Y233209D01*
G01X539084Y231686D02*
X537189Y232471D01*
G01X540285Y230485D02*
X539084Y231686D01*
G01X510401Y257768D02*
Y260511D01*
G01X506642Y254009D02*
X510401Y257768D01*
G01X506642Y252029D02*
Y254009D01*
G01X506290Y251677D02*
X506642Y252029D01*
G01X504577Y251677D02*
X506290D01*
G01X502150Y249250D02*
X504577Y251677D01*
G01X500751Y249250D02*
X502150D01*
G01X498518Y247017D02*
X500751Y249250D01*
G01X497175Y247017D02*
X498518D01*
G01X495548Y245390D02*
X497175Y247017D01*
G01X490767Y245390D02*
X495548D01*
G01X488494Y243117D02*
X490767Y245390D01*
G01X485836Y243117D02*
X488494D01*
G01X484281Y241562D02*
X485836Y243117D01*
G01X482797Y241562D02*
X484281D01*
G01X480786Y239551D02*
X482797Y241562D01*
G01X479437Y239551D02*
X480786D01*
G01X539630Y235340D02*
X541250Y233720D01*
G01X538100Y235340D02*
X539630D01*
G01X535440Y238000D02*
X538100Y235340D01*
G01X534350Y238000D02*
X535440D01*
G01X533057Y239293D02*
X534350Y238000D01*
G01X521200Y253200D02*
X522600D01*
G01X520100Y252100D02*
X521200Y253200D01*
G01X520100Y244596D02*
Y252100D01*
G01X519000Y243496D02*
X520100Y244596D01*
G01X514972Y243496D02*
X519000D01*
G01X526681Y247777D02*
X525111Y249347D01*
G01X526681Y236996D02*
Y247777D01*
G01X525185Y235500D02*
X526681Y236996D01*
G01X524000Y235500D02*
X525185D01*
G01X522626Y234126D02*
X524000Y235500D01*
G01X520193Y234126D02*
X522626D01*
G01X519003Y235316D02*
X520193Y234126D01*
G01X517117Y235316D02*
X519003D01*
G01X515927Y234126D02*
X517117Y235316D01*
G01X514073Y234126D02*
X515927D01*
G01X512883Y235316D02*
X514073Y234126D01*
G01X510941Y235316D02*
X512883D01*
G01X509526Y234126D02*
X510716Y235316D01*
G01X507174Y234126D02*
X509526D01*
G01X505985Y235315D02*
X507174Y234126D01*
G01X502626D02*
X503815Y235315D01*
G01X500073Y234126D02*
X502626D01*
G01X499802Y234397D02*
X500073Y234126D01*
G01X495130Y233530D02*
X496500Y234900D01*
G01X493551Y233530D02*
X495130D01*
G01X489303Y229282D02*
X493551Y233530D01*
G01X493100Y273104D02*
X494692Y274696D01*
G01X493100Y263889D02*
Y273104D01*
G01X489668Y260457D02*
X493100Y263889D01*
G01X489668Y253882D02*
Y260457D01*
G01X486956Y251170D02*
X489668Y253882D01*
G01X485855Y251170D02*
X486956D01*
G01X483806Y249121D02*
X485855Y251170D01*
G01X482205Y249121D02*
X483806D01*
G01X480380Y247296D02*
X482205Y249121D01*
G01X479346Y247296D02*
X480380D01*
G01X520000Y271099D02*
X518352Y272747D01*
G01X520000Y259900D02*
Y271099D01*
G01X519500Y259400D02*
X520000Y259900D01*
G01X517900Y259400D02*
X519500D01*
G01X516000Y257500D02*
X517900Y259400D01*
G01X514981Y257500D02*
X516000D01*
G01X513393Y255912D02*
X514981Y257500D01*
G01X513393Y248927D02*
Y255912D01*
G01X511483Y247017D02*
X513393Y248927D01*
G01X510941Y247017D02*
X511483D01*
G01X509581Y245657D02*
X510941Y247017D01*
G01X507941Y245657D02*
X509581D01*
G01X505606Y243322D02*
X507941Y245657D01*
G01X504267Y243322D02*
X505606D01*
G01X502655Y241710D02*
X504267Y243322D01*
G01X500526Y241710D02*
X502655D01*
G01X499119Y243117D02*
X500526Y241710D01*
G01X497168Y243117D02*
X499119D01*
G01X495791Y241740D02*
X497168Y243117D01*
G01X489986Y241740D02*
X495791D01*
G01X487810Y239564D02*
X489986Y241740D01*
G01X486066Y239564D02*
X487810D01*
G01X484139Y237637D02*
X486066Y239564D01*
G01X482680Y237637D02*
X484139D01*
G01X480683Y235640D02*
X482680Y237637D01*
G01X479725Y235640D02*
X480683D01*
G01X478482Y234397D02*
X479725Y235640D01*
G01X524160Y271796D02*
X525111Y272747D01*
G01X524160Y270806D02*
Y271796D01*
G01X523477Y270123D02*
X524160Y270806D01*
G01X523477Y258277D02*
Y270123D01*
G01X522200Y257000D02*
X523477Y258277D01*
G01X520426Y257000D02*
X522200D01*
G01X518631Y255205D02*
X520426Y257000D01*
G01X518089Y255205D02*
X518631D01*
G01X516678Y253794D02*
X518089Y255205D01*
G01X516678Y246881D02*
Y253794D01*
G01X515107Y245310D02*
X516678Y246881D01*
G01X514407Y245310D02*
X515107D01*
G01X512825Y243728D02*
X514407Y245310D01*
G01X511000Y243728D02*
X512825D01*
G01X508871Y241599D02*
X511000Y243728D01*
G01X507695Y241599D02*
X508871D01*
G01X505606Y239510D02*
X507695Y241599D01*
G01X504126Y239510D02*
X505606D01*
G01X502642Y238026D02*
X504126Y239510D01*
G01X500438Y238026D02*
X502642D01*
G01X499247Y239217D02*
X500438Y238026D01*
G01X496837Y239217D02*
X499247D01*
G01X495305Y237685D02*
X496837Y239217D01*
G01X494255Y237685D02*
X495305D01*
G01X488382Y231812D02*
X494255Y237685D01*
G01X480543Y243160D02*
X479124D01*
G01X482713Y245330D02*
X480543Y243160D01*
G01X484072Y245330D02*
X482713D01*
G01X485978Y247236D02*
X484072Y245330D01*
G01X486922Y247236D02*
X485978D01*
G01X492445Y252759D02*
X486922Y247236D01*
G01X492445Y259070D02*
Y252759D01*
G01X494339Y260964D02*
X492445Y259070D01*
G01X494881Y260964D02*
X494339D01*
G01X498072Y264155D02*
X494881Y260964D01*
G01X498072Y264947D02*
Y264155D01*
G01X486690Y500904D02*
X590373D01*
G01X486212Y502056D02*
X589895D01*
G01X602568Y114500D02*
X582840Y134228D01*
G01X602188Y121412D02*
X585089Y138511D01*
G01X598329Y114839D02*
X581688Y131480D01*
G01X598329Y110471D02*
Y114839D01*
G01X600776Y108024D02*
X598329Y110471D01*
G01X609892Y108024D02*
X600776D01*
G01X603261Y115907D02*
X583488Y135680D01*
G01X603801Y117400D02*
X583936Y137265D01*
G01X599581Y115288D02*
X601777Y113092D01*
G01X599581Y115358D02*
Y115288D01*
G01X584419Y130520D02*
X599581Y115358D01*
G01X584349Y130520D02*
X584419D01*
G01X582049Y132820D02*
X584349Y130520D01*
G01X543519Y229145D02*
X540285Y230485D01*
G01X544491Y228173D02*
X543519Y229145D01*
G01X546123Y228173D02*
X544491D01*
G01X547421Y229471D02*
X546123Y228173D01*
G01X564703Y226200D02*
X561100D01*
G01X566367Y225511D02*
X564703Y226200D01*
G01X583787Y225511D02*
X566367D01*
G01X595776Y237500D02*
X583787Y225511D01*
G01X625200Y237500D02*
X595776D01*
G01X595900Y238700D02*
X622700D01*
G01X583519Y226319D02*
X595900Y238700D01*
G01X569181Y226319D02*
X583519D01*
G01X565900Y229600D02*
X569181Y226319D01*
G01X561200Y229600D02*
X565900D01*
G01X545718Y231982D02*
X547100Y230600D01*
G01X544488Y231982D02*
X545718D01*
G01X542750Y233720D02*
X544488Y231982D01*
G01X541250Y233720D02*
X542750D01*
G01X564997Y338671D02*
X563624D01*
G01X567915Y341589D02*
X564997Y338671D01*
G01X570766Y327307D02*
X588286Y393067D01*
G01X570596Y326728D02*
X570766Y327307D01*
G01X569248Y340580D02*
Y356624D01*
G01X564189Y335521D02*
X569248Y340580D01*
G01X569652Y327603D02*
X562163Y323177D01*
G01X587209Y393500D02*
X569652Y327603D01*
G01X564685Y339423D02*
X563624D01*
G01X567163Y341901D02*
X564685Y339423D01*
G01X570061Y340243D02*
X564589Y334771D01*
G01X570061Y356287D02*
Y340243D01*
G01X567915Y357177D02*
Y341589D01*
G01X574999Y364261D02*
X567915Y357177D01*
G01X574999Y444313D02*
Y364261D01*
G01X590851Y397612D02*
X605844Y448663D01*
G01X590743Y397513D02*
X590851Y397612D01*
G01X588286Y393067D02*
X590743Y397513D01*
G01X576332Y363708D02*
Y443760D01*
G01X569248Y356624D02*
X576332Y363708D01*
G01X589841Y398265D02*
X587209Y393500D01*
G01X604762Y449072D02*
X589841Y398265D01*
G01X567163Y357489D02*
Y341901D01*
G01X574247Y364573D02*
X567163Y357489D01*
G01X574247Y444625D02*
Y364573D01*
G01X572382Y365346D02*
Y445398D01*
G01X565298Y358262D02*
X572382Y365346D01*
G01X565298Y345016D02*
Y358262D01*
G01X563603Y343321D02*
X565298Y345016D01*
G01X566111Y344679D02*
X564003Y342571D01*
G01X566111Y357925D02*
Y344679D01*
G01X573195Y365009D02*
X566111Y357925D01*
G01X573195Y445061D02*
Y365009D01*
G01X577145Y363371D02*
X570061Y356287D01*
G01X577145Y443423D02*
Y363371D01*
G01X601906Y471220D02*
X574999Y444313D01*
G01X576332Y443760D02*
X603239Y470667D01*
G01X601154Y471532D02*
X574247Y444625D01*
G01X572382Y445398D02*
X599289Y472305D01*
G01X600102Y471968D02*
X573195Y445061D01*
G01X604052Y470330D02*
X577145Y443423D01*
G01X596781Y507312D02*
X618568D01*
G01X590373Y500904D02*
X596781Y507312D01*
G01X600984Y501264D02*
X635078D01*
G01X580586Y480866D02*
X600984Y501264D01*
G01X602139Y491932D02*
X582121Y471914D01*
G01X597980Y505776D02*
X620292D01*
G01X579982Y487778D02*
X597980Y505776D01*
G01X598858Y505024D02*
X580860Y487026D01*
G01X620604Y505024D02*
X598858D01*
G01X600961Y495568D02*
X613991D01*
G01X581623Y476230D02*
X600961Y495568D01*
G01X581450Y473650D02*
X601666Y493866D01*
G01X601154Y483559D02*
Y471532D01*
G01X605176Y487581D02*
X601154Y483559D01*
G01X580870Y480114D02*
X580470Y479714D01*
G01X580898Y480114D02*
X580870D01*
G01X601296Y500512D02*
X580898Y480114D01*
G01X634766Y500512D02*
X601296D01*
G01X597134Y506560D02*
X618880D01*
G01X579607Y489033D02*
X597134Y506560D01*
G01X596303Y508464D02*
X618090D01*
G01X589895Y502056D02*
X596303Y508464D01*
G01X600048Y503520D02*
X581050Y484522D01*
G01X636014Y503520D02*
X600048D01*
G01X599736Y504272D02*
X636326D01*
G01X580938Y485474D02*
X599736Y504272D01*
G01X599289Y485875D02*
X603494Y490080D01*
G01X599289Y472305D02*
Y485875D01*
G01X600102Y485624D02*
Y471968D01*
G01X603806Y489328D02*
X600102Y485624D01*
G01X599902Y496976D02*
X613407D01*
G01X581126Y478200D02*
X599902Y496976D01*
G01X600360Y502768D02*
X580762Y483170D01*
G01X635702Y502768D02*
X600360D01*
G01X600672Y502016D02*
X580674Y482018D01*
G01X635390Y502016D02*
X600672D01*
G01X648500Y-20000D02*
X648000Y-20500D01*
G01X650500Y-20000D02*
X648500D01*
G01X652000Y-18500D02*
X650500Y-20000D01*
G01X657500Y-18500D02*
X652000D01*
G01X658500Y-19500D02*
X657500Y-18500D01*
G01X662000Y-19500D02*
X658500D01*
G01X662700Y-18800D02*
X662000Y-19500D01*
G01X662700Y-17900D02*
Y-18800D01*
G01X663093Y6292D02*
X675267D01*
G01X659000Y2199D02*
X663093Y6292D01*
G01X659000Y-9347D02*
Y2199D01*
G01X650723Y-17624D02*
X659000Y-9347D01*
G01X623000Y-3000D02*
X619196Y804D01*
G01X662455Y12448D02*
X676052D01*
G01X654267Y4260D02*
X662455Y12448D01*
G01X654267Y-11386D02*
Y4260D01*
G01X649533Y-16120D02*
X654267Y-11386D01*
G01X655160Y-11557D02*
X649845Y-16872D01*
G01X655160Y4089D02*
Y-11557D01*
G01X662766Y11695D02*
X655160Y4089D01*
G01X675023Y11695D02*
X662766D01*
G01X646417Y38749D02*
X654016Y31150D01*
G01X630372Y25827D02*
Y34895D01*
G01X623622Y19077D02*
X630372Y25827D01*
G01X624770Y-640D02*
X622106Y2024D01*
G01X662279Y14400D02*
X671529D01*
G01X652142Y4263D02*
X662279Y14400D01*
G01X652142Y-10251D02*
Y4263D01*
G01X647777Y-14616D02*
X652142Y-10251D01*
G01X653294Y-11295D02*
X649221Y-15368D01*
G01X653294Y4351D02*
Y-11295D01*
G01X662143Y13200D02*
X653294Y4351D01*
G01X674400Y13200D02*
X662143D01*
G01X658253Y15648D02*
X671147D01*
G01X651156Y22745D02*
X658253Y15648D01*
G01X646989Y22745D02*
X651156D01*
G01X645405Y21161D02*
X646989Y22745D01*
G01X645405Y9972D02*
Y21161D01*
G01X637247Y1814D02*
X645405Y9972D01*
G01X635870Y1814D02*
X637247D01*
G01X621344Y-12712D02*
X635870Y1814D01*
G01X662500Y16600D02*
X670741D01*
G01X658100Y21000D02*
X662500Y16600D01*
G01X658100Y23400D02*
Y21000D01*
G01X656234Y25266D02*
X658100Y23400D01*
G01X648163Y25266D02*
X656234D01*
G01X644453Y21556D02*
X648163Y25266D01*
G01X644453Y10367D02*
Y21556D01*
G01X636852Y2766D02*
X644453Y10367D01*
G01X635475Y2766D02*
X636852D01*
G01X620949Y-11760D02*
X635475Y2766D01*
G01X634226Y38749D02*
X646417D01*
G01X630372Y34895D02*
X634226Y38749D01*
G01X629567Y83062D02*
Y99108D01*
G01X632613Y80016D02*
X629567Y83062D01*
G01X665157Y80016D02*
X632613D01*
G01X631073Y83496D02*
Y99951D01*
G01X633294Y81275D02*
X631073Y83496D01*
G01X664326Y81275D02*
X633294D01*
G01X630931Y77200D02*
X663237D01*
G01X626751Y81380D02*
X630931Y77200D01*
G01X626751Y94378D02*
Y81380D01*
G01X619352Y101777D02*
X626751Y94378D01*
G01X642184Y113128D02*
X873301D01*
G01X630744Y124568D02*
X642184Y113128D01*
G01X609482Y124568D02*
X630744D01*
G01X607179Y114500D02*
X602568D01*
G01X610741Y110938D02*
X607179Y114500D01*
G01X615745Y110938D02*
X610741D01*
G01X626040Y100643D02*
X615745Y110938D01*
G01X626040Y98281D02*
Y100643D01*
G01X624519Y121412D02*
X602188D01*
G01X647431Y98500D02*
X624519Y121412D01*
G01X710310Y98500D02*
X647431D01*
G01X617816Y100100D02*
X609892Y108024D01*
G01X618800Y100100D02*
X617816D01*
G01X607764Y115907D02*
X603261D01*
G01X611325Y112346D02*
X607764Y115907D01*
G01X616329Y112346D02*
X611325D01*
G01X629567Y99108D02*
X616329Y112346D01*
G01X640624Y112176D02*
X633800Y119000D01*
G01X873413Y112176D02*
X640624D01*
G01X608499Y117400D02*
X603801D01*
G01X611856Y114043D02*
X608499Y117400D01*
G01X616981Y114043D02*
X611856D01*
G01X631073Y99951D02*
X616981Y114043D01*
G01X617910Y101777D02*
X619352D01*
G01X606595Y113092D02*
X617910Y101777D01*
G01X601777Y113092D02*
X606595D01*
G01X633600Y245900D02*
X625200Y237500D01*
G01X647970Y245900D02*
X633600D01*
G01X651235Y249165D02*
X647970Y245900D01*
G01X622700Y238700D02*
X624500Y240500D01*
G01X624272Y270631D02*
X639621Y285980D01*
G01X624272Y259182D02*
Y270631D01*
G01X621165Y256075D02*
X624272Y259182D01*
G01X625500Y258066D02*
X620850Y253416D01*
G01X625500Y270229D02*
Y258066D01*
G01X641135Y285864D02*
X625500Y270229D01*
G01X639622Y285983D02*
Y290210D01*
G01X639621Y285980D02*
X639622Y285983D01*
G01X641135Y286962D02*
Y285864D01*
G01X643823Y289650D02*
X641135Y286962D01*
G01X611650Y461167D02*
Y474880D01*
G01X605844Y448663D02*
X611650Y461167D01*
G01X610498Y461423D02*
X604762Y449072D01*
G01X610498Y474402D02*
Y461423D01*
G01X628589Y463649D02*
X626521Y465717D01*
G01X601906Y482220D02*
Y471220D01*
G01X604820Y485134D02*
X601906Y482220D01*
G01X605277Y485134D02*
X604820D01*
G01X608163Y488020D02*
X605277Y485134D01*
G01X616008Y488020D02*
X608163D01*
G01X617038Y486990D02*
X616008Y488020D01*
G01X627003Y486990D02*
X617038D01*
G01X631028Y482965D02*
X627003Y486990D01*
G01X631028Y471252D02*
Y482965D01*
G01X629359Y469583D02*
X631028Y471252D01*
G01X611021Y476521D02*
X611250Y476750D01*
G01X611021Y475509D02*
Y476521D01*
G01X611650Y474880D02*
X611021Y475509D01*
G01X623600Y521700D02*
X618000Y527300D01*
G01X628057Y467638D02*
X634033D01*
G01X627283Y468412D02*
X628057Y467638D01*
G01X627283Y474360D02*
Y468412D01*
G01X630276Y477353D02*
X627283Y474360D01*
G01X630276Y482653D02*
Y477353D01*
G01X626691Y486238D02*
X630276Y482653D01*
G01X616726Y486238D02*
X626691D01*
G01X615696Y487268D02*
X616726Y486238D01*
G01X609025Y487268D02*
X615696D01*
G01X606938Y485181D02*
X609025Y487268D01*
G01X606938Y480299D02*
Y485181D01*
G01X603239Y476600D02*
X606938Y480299D01*
G01X603239Y470667D02*
Y476600D01*
G01X626500Y515244D02*
Y556230D01*
G01X618568Y507312D02*
X626500Y515244D01*
G01X657555Y496496D02*
X678749D01*
G01X654895Y493836D02*
X657555Y496496D01*
G01X654252Y493836D02*
X654895D01*
G01X651240Y490824D02*
X654252Y493836D01*
G01X645518Y490824D02*
X651240D01*
G01X635078Y501264D02*
X645518Y490824D01*
G01X615957Y491932D02*
X602139D01*
G01X618202Y494177D02*
X615957Y491932D01*
G01X627671Y494177D02*
X618202D01*
G01X635255Y486593D02*
X627671Y494177D01*
G01X635255Y482275D02*
Y486593D01*
G01X646170Y471360D02*
X635255Y482275D01*
G01X667160Y471360D02*
X646170D01*
G01X653714Y517732D02*
X689245D01*
G01X646880Y524566D02*
X653714Y517732D01*
G01X646880Y535357D02*
Y524566D01*
G01X628900Y514384D02*
Y553656D01*
G01X620292Y505776D02*
X628900Y514384D01*
G01X629653Y514073D02*
X620604Y505024D01*
G01X629653Y514695D02*
Y514073D01*
G01X629652Y514696D02*
X629653Y514695D01*
G01X629652Y553344D02*
Y514696D01*
G01X646218Y499718D02*
X646200Y499700D01*
G01X648619Y499718D02*
X646218D01*
G01X651157Y502256D02*
X648619Y499718D01*
G01X660092Y502256D02*
X651157D01*
G01X673183Y515347D02*
X660092Y502256D01*
G01X647284Y475160D02*
X665585D01*
G01X638868Y483576D02*
X647284Y475160D01*
G01X638868Y487796D02*
Y483576D01*
G01X630101Y496563D02*
X638868Y487796D01*
G01X630101Y496564D02*
Y496563D01*
G01X629105Y497560D02*
X630101Y496564D01*
G01X629104Y497560D02*
X629105D01*
G01X629083Y497581D02*
X629104Y497560D01*
G01X616004Y497581D02*
X629083D01*
G01X613991Y495568D02*
X616004Y497581D01*
G01X659706Y503500D02*
X672505Y516299D01*
G01X651212Y503500D02*
X659706D01*
G01X649287Y501575D02*
X651212Y503500D01*
G01X648025Y501575D02*
X649287D01*
G01X647989Y473458D02*
X666290D01*
G01X647988Y473457D02*
X647989Y473458D01*
G01X646580Y473457D02*
X647988D01*
G01X637166Y482871D02*
X646580Y473457D01*
G01X637166Y487091D02*
Y482871D01*
G01X628399Y495858D02*
X637166Y487091D01*
G01X628397Y495858D02*
X628399D01*
G01X628376Y495879D02*
X628397Y495858D01*
G01X617496Y495879D02*
X628376D01*
G01X617475Y495858D02*
X617496Y495879D01*
G01X617378Y495858D02*
X617475D01*
G01X615386Y493866D02*
X617378Y495858D01*
G01X601666Y493866D02*
X615386D01*
G01X609550Y475350D02*
X610498Y474402D01*
G01X609550Y477820D02*
Y475350D01*
G01X610970Y479240D02*
X609550Y477820D01*
G01X610970Y482030D02*
Y479240D01*
G01X609470Y483530D02*
X610970Y482030D01*
G01X609470Y484060D02*
Y483530D01*
G01X645206Y490072D02*
X634766Y500512D01*
G01X652118Y490072D02*
X645206D01*
G01X654730Y492684D02*
X652118Y490072D01*
G01X655373Y492684D02*
X654730D01*
G01X658033Y495344D02*
X655373Y492684D01*
G01X678260Y495344D02*
X658033D01*
G01X627700Y515380D02*
Y554086D01*
G01X618880Y506560D02*
X627700Y515380D01*
G01X625300Y515674D02*
Y556680D01*
G01X618090Y508464D02*
X625300Y515674D01*
G01X642678Y496856D02*
X636014Y503520D01*
G01X649017Y496856D02*
X642678D01*
G01X652113Y499952D02*
X649017Y496856D01*
G01X661048Y499952D02*
X652113D01*
G01X666926Y505830D02*
X661048Y499952D01*
G01X660570Y501104D02*
X666448Y506982D01*
G01X651635Y501104D02*
X660570D01*
G01X648539Y498008D02*
X651635Y501104D01*
G01X642590Y498008D02*
X648539D01*
G01X636326Y504272D02*
X642590Y498008D01*
G01X640522Y471989D02*
X641107D01*
G01X633403Y479108D02*
X640522Y471989D01*
G01X633403Y482718D02*
Y479108D01*
G01X627626Y488495D02*
X633403Y482718D01*
G01X618667Y488495D02*
X627626D01*
G01X617082Y490080D02*
X618667Y488495D01*
G01X603494Y490080D02*
X617082D01*
G01X616684Y489328D02*
X603806D01*
G01X618270Y487742D02*
X616684Y489328D01*
G01X625697Y487742D02*
X618270D01*
G01X625698Y487743D02*
X625697Y487742D01*
G01X627314Y487743D02*
X625698D01*
G01X632651Y482406D02*
X627314Y487743D01*
G01X632651Y473389D02*
Y482406D01*
G01X632771Y473269D02*
X632651Y473389D01*
G01X658837Y493936D02*
X677676D01*
G01X656177Y491276D02*
X658837Y493936D01*
G01X655314Y491276D02*
X656177D01*
G01X652702Y488664D02*
X655314Y491276D01*
G01X644622Y488664D02*
X652702D01*
G01X634297Y498989D02*
X644622Y488664D01*
G01X615420Y498989D02*
X634297D01*
G01X613407Y496976D02*
X615420Y498989D01*
G01X642766Y495704D02*
X635702Y502768D01*
G01X649495Y495704D02*
X642766D01*
G01X652591Y498800D02*
X649495Y495704D01*
G01X679705Y498800D02*
X652591D01*
G01X642854Y494552D02*
X635390Y502016D01*
G01X653338Y494552D02*
X642854D01*
G01X653774Y494988D02*
X653338Y494552D01*
G01X654417Y494988D02*
X653774D01*
G01X657077Y497648D02*
X654417Y494988D01*
G01X679227Y497648D02*
X657077D01*
G01X604052Y476349D02*
Y470330D01*
G01X607708Y480005D02*
X604052Y476349D01*
G01X607708Y484887D02*
Y480005D01*
G01X609337Y486516D02*
X607708Y484887D01*
G01X615008Y486516D02*
X609337D01*
G01X616024Y485500D02*
X615008Y486516D01*
G01X616400Y485500D02*
X616024D01*
G01X616415Y485485D02*
X616400Y485500D01*
G01X617037Y485485D02*
X616415D01*
G01X617038Y485484D02*
X617037Y485485D01*
G01X617660Y485484D02*
X617038D01*
G01X617662Y485486D02*
X617660Y485484D01*
G01X622445Y485486D02*
X617662D01*
G01X623481Y484450D02*
X622445Y485486D01*
G01X623481Y479045D02*
Y484450D01*
G01X626521Y476005D02*
X623481Y479045D01*
G01X626521Y465717D02*
Y476005D01*
G01X618000Y538200D02*
X614555Y541645D01*
G01X618000Y527300D02*
Y538200D01*
G01X660341Y586500D02*
X695634D01*
G01X647875Y598966D02*
X660341Y586500D01*
G01X656833Y564104D02*
X726613D01*
G01X654453Y561724D02*
X656833Y564104D01*
G01X631994Y561724D02*
X654453D01*
G01X626500Y556230D02*
X631994Y561724D01*
G01X648653Y537130D02*
X646880Y535357D01*
G01X648653Y554760D02*
Y537130D01*
G01X651809Y557916D02*
X648653Y554760D01*
G01X656033Y557916D02*
X651809D01*
G01X658413Y560296D02*
X656033Y557916D01*
G01X743103Y560296D02*
X658413D01*
G01X657789Y561800D02*
X745834D01*
G01X655409Y559420D02*
X657789Y561800D01*
G01X634664Y559420D02*
X655409D01*
G01X628900Y553656D02*
X634664Y559420D01*
G01X634976Y558668D02*
X629652Y553344D01*
G01X655721Y558668D02*
X634976D01*
G01X658101Y561048D02*
X655721Y558668D01*
G01X743415Y561048D02*
X658101D01*
G01X635525Y582574D02*
X620443Y597656D01*
G01X669290Y582574D02*
X635525D01*
G01X660653Y587252D02*
X647658Y600247D01*
G01X694756Y587252D02*
X660653D01*
G01X620728Y580953D02*
X620727Y580952D01*
G01X621516Y580953D02*
X620728D01*
G01X623117Y579352D02*
X621516Y580953D01*
G01X640705Y579352D02*
X623117D01*
G01X640706Y579353D02*
X640705Y579352D01*
G01X641494Y579353D02*
X640706D01*
G01X649047Y571800D02*
X641494Y579353D01*
G01X652747Y571800D02*
X649047D01*
G01X657187Y567360D02*
X652747Y571800D01*
G01X694213Y567360D02*
X657187D01*
G01X657311Y562952D02*
X727091D01*
G01X654931Y560572D02*
X657311Y562952D01*
G01X634186Y560572D02*
X654931D01*
G01X627700Y554086D02*
X634186Y560572D01*
G01X644256Y565256D02*
X726135D01*
G01X642000Y563000D02*
X644256Y565256D01*
G01X631620Y563000D02*
X642000D01*
G01X625300Y556680D02*
X631620Y563000D01*
G01X635047Y581422D02*
X668812D01*
G01X619965Y596504D02*
X635047Y581422D01*
G01X622722Y578400D02*
X621122Y580000D01*
G01X641100Y578400D02*
X622722D01*
G01X648652Y570848D02*
X641100Y578400D01*
G01X652352Y570848D02*
X648652D01*
G01X656792Y566408D02*
X652352Y570848D01*
G01X694608Y566408D02*
X656792D01*
G01X628548Y598966D02*
X647875D01*
G01X625860Y601654D02*
X628548Y598966D01*
G01X648604Y611500D02*
X655100D01*
G01X642348Y617756D02*
X648604Y611500D01*
G01X627705Y614069D02*
X626122Y615652D01*
G01X627705Y611973D02*
Y614069D01*
G01X660739Y591252D02*
X696515D01*
G01X650445Y601546D02*
X660739Y591252D01*
G01X632234Y601546D02*
X650445D01*
G01X619280Y614500D02*
X632234Y601546D01*
G01X629977Y613024D02*
X626397Y616604D01*
G01X629638Y600247D02*
X627079Y602806D01*
G01X647658Y600247D02*
X629638D01*
G01X662441Y592324D02*
X695957D01*
G01X656676Y598089D02*
X662441Y592324D01*
G01X656676Y612524D02*
Y598089D01*
G01X655100Y614100D02*
X656676Y612524D01*
G01X650298Y614100D02*
X655100D01*
G01X645890Y618508D02*
X650298Y614100D01*
G01X721300Y2938D02*
X726151Y-1913D01*
G01X721300Y4413D02*
Y2938D01*
G01X714664Y11049D02*
X721300Y4413D01*
G01X704694Y11049D02*
X714664D01*
G01X703345Y9700D02*
X704694Y11049D01*
G01X678675Y9700D02*
X703345D01*
G01X675267Y6292D02*
X678675Y9700D01*
G01X707300Y2100D02*
X704450Y4950D01*
G01X707300Y-5064D02*
Y2100D01*
G01X712948Y-10712D02*
X707300Y-5064D01*
G01X712948Y-13864D02*
Y-10712D01*
G01X720730Y-21646D02*
X712948Y-13864D01*
G01X1270062Y-21646D02*
X720730D01*
G01X723740Y3192D02*
X728055Y-1123D01*
G01X723740Y4544D02*
Y3192D01*
G01X715731Y12553D02*
X723740Y4544D01*
G01X704070Y12553D02*
X715731D01*
G01X702721Y11204D02*
X704070Y12553D01*
G01X677296Y11204D02*
X702721D01*
G01X676052Y12448D02*
X677296Y11204D01*
G01X676266Y10452D02*
X675023Y11695D01*
G01X703033Y10452D02*
X676266D01*
G01X704382Y11801D02*
X703033Y10452D01*
G01X715419Y11801D02*
X704382D01*
G01X722988Y4232D02*
X715419Y11801D01*
G01X722988Y2880D02*
Y4232D01*
G01X727303Y-1435D02*
X722988Y2880D01*
G01X718975Y-11964D02*
Y-4451D01*
G01X720529Y-13518D02*
X718975Y-11964D01*
G01X720529Y-16259D02*
Y-13518D01*
G01X723724Y-19454D02*
X720529Y-16259D01*
G01X1266556Y-19454D02*
X723724D01*
G01X711310Y6590D02*
X710800Y7100D01*
G01X711310Y1910D02*
Y6590D01*
G01X712988Y232D02*
X711310Y1910D01*
G01X720592Y232D02*
X712988D01*
G01X722898Y-2074D02*
X720592Y232D01*
G01X722898Y-13075D02*
Y-2074D01*
G01X722051Y-13922D02*
X722898Y-13075D01*
G01X722051Y-15587D02*
Y-13922D01*
G01X724384Y-17920D02*
X722051Y-15587D01*
G01X735605Y-17920D02*
X724384D01*
G01X721042Y-20894D02*
X1267756D01*
G01X713700Y-13552D02*
X721042Y-20894D01*
G01X713700Y-10400D02*
Y-13552D01*
G01X708100Y-4800D02*
X713700Y-10400D01*
G01X708100Y3529D02*
Y-4800D01*
G01X705029Y6600D02*
X708100Y3529D01*
G01X702600Y6600D02*
X705029D01*
G01X701100Y8100D02*
X702600Y6600D01*
G01X716355Y14057D02*
X725644Y4768D01*
G01X702977Y14057D02*
X716355D01*
G01X702644Y13724D02*
X702977Y14057D01*
G01X685147Y13724D02*
X702644D01*
G01X683319Y15552D02*
X685147Y13724D01*
G01X672681Y15552D02*
X683319D01*
G01X671529Y14400D02*
X672681Y15552D01*
G01X676000Y14800D02*
X674400Y13200D01*
G01X682000Y14800D02*
X676000D01*
G01X684485Y12315D02*
X682000Y14800D01*
G01X702361Y12315D02*
X684485D01*
G01X703351Y13305D02*
X702361Y12315D01*
G01X716043Y13305D02*
X703351D01*
G01X724492Y4856D02*
X716043Y13305D01*
G01X724492Y3504D02*
Y4856D01*
G01X728807Y-811D02*
X724492Y3504D01*
G01X722240Y12589D02*
X726796Y8033D01*
G01X722240Y15450D02*
Y12589D01*
G01X721190Y16500D02*
X722240Y15450D01*
G01X694201Y16500D02*
X721190D01*
G01X693625Y17076D02*
X694201Y16500D01*
G01X685463Y17076D02*
X693625D01*
G01X681687Y20852D02*
X685463Y17076D01*
G01X676351Y20852D02*
X681687D01*
G01X671147Y15648D02*
X676351Y20852D01*
G01X724056Y17530D02*
X727748Y13838D01*
G01X694770Y17530D02*
X724056D01*
G01X694272Y18028D02*
X694770Y17530D01*
G01X685858Y18028D02*
X694272D01*
G01X681745Y22141D02*
X685858Y18028D01*
G01X676293Y22141D02*
X681745D01*
G01X674652Y20500D02*
X676293Y22141D01*
G01X674641Y20500D02*
X674652D01*
G01X670741Y16600D02*
X674641Y20500D01*
G01X716716Y81996D02*
X728132D01*
G01X715318Y83394D02*
X716716Y81996D01*
G01X715318Y83692D02*
Y83394D01*
G01X714610Y84400D02*
X715318Y83692D01*
G01X712600Y84400D02*
X714610D01*
G01X708045Y88955D02*
X712600Y84400D01*
G01X707329Y88955D02*
X708045D01*
G01X713058Y81150D02*
X709560Y84648D01*
G01X715932Y81150D02*
X713058D01*
G01X716238Y80844D02*
X715932Y81150D01*
G01X724249Y80844D02*
X716238D01*
G01X727701Y77392D02*
X724249Y80844D01*
G01X697096Y82504D02*
X694600Y85000D01*
G01X702673Y82504D02*
X697096D01*
G01X712025Y73152D02*
X702673Y82504D01*
G01X723509Y73152D02*
X712025D01*
G01X727021Y69640D02*
X723509Y73152D01*
G01X699676Y83924D02*
X698300Y85300D01*
G01X703024Y83924D02*
X699676D01*
G01X712544Y74404D02*
X703024Y83924D01*
G01X724028Y74404D02*
X712544D01*
G01X728273Y70159D02*
X724028Y74404D01*
G01X722812Y90940D02*
X732291D01*
G01X720572Y88700D02*
X722812Y90940D01*
G01X716268Y87515D02*
Y88683D01*
G01X719483Y84300D02*
X716268Y87515D01*
G01X736929Y84300D02*
X719483D01*
G01X718996Y89814D02*
X710310Y98500D01*
G01X718996Y88047D02*
Y89814D01*
G01X720439Y86604D02*
X718996Y88047D01*
G01X735745Y86604D02*
X720439D01*
G01X703845Y86504D02*
Y88830D01*
G01X713541Y76808D02*
X703845Y86504D01*
G01X725025Y76808D02*
X713541D01*
G01X671695Y86554D02*
X665157Y80016D01*
G01X681296Y86554D02*
X671695D01*
G01X688868Y78982D02*
X681296Y86554D01*
G01X695489Y78982D02*
X688868D01*
G01X696547Y77924D02*
X695489Y78982D01*
G01X703661Y77924D02*
X696547D01*
G01X711381Y70204D02*
X703661Y77924D01*
G01X715007Y70204D02*
X711381D01*
G01X719039Y66172D02*
X715007Y70204D01*
G01X719039Y64440D02*
Y66172D01*
G01X725095Y58384D02*
X719039Y64440D01*
G01X670664Y87613D02*
X664326Y81275D01*
G01X671448Y87613D02*
X670664D01*
G01X671731Y87896D02*
X671448Y87613D01*
G01X682490Y87896D02*
X671731D01*
G01X689134Y81252D02*
X682490Y87896D01*
G01X702154Y81252D02*
X689134D01*
G01X711506Y71900D02*
X702154Y81252D01*
G01X715347Y71900D02*
X711506D01*
G01X720290Y66957D02*
X715347Y71900D01*
G01X720290Y64924D02*
Y66957D01*
G01X725424Y59790D02*
X720290Y64924D01*
G01X705972Y86007D02*
Y86660D01*
G01X714019Y77960D02*
X705972Y86007D01*
G01X725503Y77960D02*
X714019D01*
G01X703219Y85500D02*
X701500D01*
G01X713063Y75656D02*
X703219Y85500D01*
G01X724547Y75656D02*
X713063D01*
G01X729525Y70678D02*
X724547Y75656D01*
G01X717793Y83148D02*
X716894Y84047D01*
G01X728610Y83148D02*
X717793D01*
G01X714745Y90259D02*
X713115Y88629D01*
G01X716921Y90259D02*
X714745D01*
G01X717844Y89336D02*
X716921Y90259D01*
G01X717844Y87569D02*
Y89336D01*
G01X719961Y85452D02*
X717844Y87569D01*
G01X737407Y85452D02*
X719961D01*
G01X724225Y55712D02*
X726749D01*
G01X716535Y63402D02*
X724225Y55712D01*
G01X716535Y65134D02*
Y63402D01*
G01X713969Y67700D02*
X716535Y65134D01*
G01X710342Y67700D02*
X713969D01*
G01X702672Y75370D02*
X710342Y67700D01*
G01X694448Y75370D02*
X702672D01*
G01X693340Y76478D02*
X694448Y75370D01*
G01X687940Y76478D02*
X693340D01*
G01X684872Y73410D02*
X687940Y76478D01*
G01X667027Y73410D02*
X684872D01*
G01X663237Y77200D02*
X667027Y73410D01*
G01X671325Y115884D02*
X670503D01*
G01X672865Y114344D02*
X671325Y115884D01*
G01X740073Y114344D02*
X672865D01*
G01X675241Y288147D02*
X688924D01*
G01X674469Y287375D02*
X675241Y288147D01*
G01X724360Y509700D02*
X732120D01*
G01X721570Y506910D02*
X724360Y509700D01*
G01X717069Y506910D02*
X721570D01*
G01X716279Y507700D02*
X717069Y506910D01*
G01X715400Y507700D02*
X716279D01*
G01X713200Y505500D02*
X715400Y507700D01*
G01X714649Y493436D02*
X733650D01*
G01X708732Y487519D02*
X714649Y493436D01*
G01X687726Y487519D02*
X708732D01*
G01X678749Y496496D02*
X687726Y487519D01*
G01X680300Y484500D02*
X667160Y471360D01*
G01X680300Y485700D02*
Y484500D01*
G01X713067Y514859D02*
X715009Y512917D01*
G01X692118Y514859D02*
X713067D01*
G01X689245Y517732D02*
X692118Y514859D01*
G01X721414Y508986D02*
X730580Y518152D01*
G01X688653Y515347D02*
X673183D01*
G01X694453Y509547D02*
X688653Y515347D01*
G01X695636Y509547D02*
X694453D01*
G01X695637Y509548D02*
X695636Y509547D01*
G01X720852Y509548D02*
X695637D01*
G01X721414Y508986D02*
X720852Y509548D01*
G01X675080Y484655D02*
Y485570D01*
G01X665585Y475160D02*
X675080Y484655D01*
G01X719727Y510500D02*
X720565Y511338D01*
G01X695242Y510500D02*
X719727D01*
G01X695241Y510499D02*
X695242Y510500D01*
G01X694848Y510499D02*
X695241D01*
G01X689048Y516299D02*
X694848Y510499D01*
G01X672505Y516299D02*
X689048D01*
G01X721741Y510660D02*
X730185Y519104D01*
G01X721243Y510660D02*
X721741D01*
G01X720565Y511338D02*
X721243Y510660D01*
G01X711802Y495352D02*
X752442D01*
G01X707450Y491000D02*
X711802Y495352D01*
G01X701750Y491000D02*
X707450D01*
G01X696000Y496750D02*
X701750Y491000D01*
G01X696000Y496800D02*
Y496750D01*
G01X677800Y484968D02*
Y485600D01*
G01X666290Y473458D02*
X677800Y484968D01*
G01X686837Y486767D02*
X678260Y495344D01*
G01X709621Y486767D02*
X686837D01*
G01X715538Y492684D02*
X709621Y486767D01*
G01X732880Y492684D02*
X715538D01*
G01X724755Y508748D02*
X732515D01*
G01X724659Y508652D02*
X724755Y508748D01*
G01X724376Y508652D02*
X724659D01*
G01X721882Y506158D02*
X724376Y508652D01*
G01X718691Y506158D02*
X721882D01*
G01X718491Y505958D02*
X718691Y506158D01*
G01X716208Y505958D02*
X718491D01*
G01X715900Y505650D02*
X716208Y505958D01*
G01X685470Y505830D02*
X666926D01*
G01X688500Y502800D02*
X685470Y505830D01*
G01X688500Y498034D02*
Y502800D01*
G01X688202Y497736D02*
X688500Y498034D01*
G01X718700Y497400D02*
X733994D01*
G01X714321Y501779D02*
X718700Y497400D01*
G01X711079Y501779D02*
X714321D01*
G01X708700Y499400D02*
X711079Y501779D01*
G01X689600Y499600D02*
X691000Y498200D01*
G01X689600Y503200D02*
Y499600D01*
G01X685818Y506982D02*
X689600Y503200D01*
G01X666448Y506982D02*
X685818D01*
G01X724771Y507700D02*
X733010D01*
G01X722277Y505206D02*
X724771Y507700D01*
G01X719086Y505206D02*
X722277D01*
G01X717840Y503960D02*
X719086Y505206D01*
G01X717269Y503960D02*
X717840D01*
G01X716626Y503317D02*
X717269Y503960D01*
G01X698597Y503317D02*
X716626D01*
G01X691322Y496042D02*
X698597Y503317D01*
G01X686753Y496042D02*
X691322D01*
G01X679049Y503746D02*
X686753Y496042D01*
G01X716122Y491276D02*
X732254D01*
G01X710205Y485359D02*
X716122Y491276D01*
G01X686253Y485359D02*
X710205D01*
G01X677676Y493936D02*
X686253Y485359D01*
G01X688972Y489533D02*
X679705Y498800D01*
G01X690733Y489533D02*
X688972D01*
G01X691700Y490500D02*
X690733Y489533D01*
G01X691700Y495000D02*
Y490500D01*
G01X695725Y499025D02*
X691700Y495000D01*
G01X698925Y499025D02*
X695725D01*
G01X700126Y497824D02*
X698925Y499025D01*
G01X710100Y497824D02*
X700126D01*
G01X711420Y496504D02*
X710100Y497824D01*
G01X752956Y496504D02*
X711420D01*
G01X688494Y488381D02*
X679227Y497648D01*
G01X707964Y488381D02*
X688494D01*
G01X713783Y494200D02*
X707964Y488381D01*
G01X733988Y494200D02*
X713783D01*
G01X695634Y586500D02*
X702702Y593568D01*
G01X680535Y571329D02*
X669290Y582574D01*
G01X693415Y571329D02*
X680535D01*
G01X701250Y579164D02*
X693415Y571329D01*
G01X710258Y579164D02*
X701250D01*
G01X715442Y584348D02*
X710258Y579164D01*
G01X727567Y584348D02*
X715442D01*
G01X702224Y594720D02*
X694756Y587252D01*
G01X697505Y570652D02*
X694213Y567360D01*
G01X701252Y570652D02*
X697505D01*
G01X702000Y571400D02*
X701252Y570652D01*
G01X702600Y570800D02*
X702000Y571400D01*
G01X705953Y570800D02*
X702600D01*
G01X710253Y575100D02*
X705953Y570800D01*
G01X728265Y575100D02*
X710253D01*
G01X715920Y583196D02*
X728045D01*
G01X710736Y578012D02*
X715920Y583196D01*
G01X701728Y578012D02*
X710736D01*
G01X693892Y570176D02*
X701728Y578012D01*
G01X680058Y570176D02*
X693892D01*
G01X668812Y581422D02*
X680058Y570176D01*
G01X697900Y569700D02*
X694608Y566408D01*
G01X701200Y569700D02*
X697900D01*
G01X702100Y568800D02*
X701200Y569700D01*
G01X703100Y569800D02*
X702100Y568800D01*
G01X706300Y569800D02*
X703100D01*
G01X710648Y574148D02*
X706300Y569800D01*
G01X728660Y574148D02*
X710648D01*
G01X715573Y598744D02*
X725829Y609000D01*
G01X715573Y596714D02*
Y598744D01*
G01X712427Y593568D02*
X715573Y596714D01*
G01X702702Y593568D02*
X712427D01*
G01X717421Y615824D02*
X733119D01*
G01X708952Y607355D02*
X717421Y615824D01*
G01X708952Y603689D02*
Y607355D01*
G01X696515Y591252D02*
X708952Y603689D01*
G01X711949Y594720D02*
X702224D01*
G01X713971Y596742D02*
X711949Y594720D01*
G01X713971Y600856D02*
Y596742D01*
G01X717734Y604619D02*
X713971Y600856D01*
G01X717734Y609234D02*
Y604619D01*
G01X723500Y615000D02*
X717734Y609234D01*
G01X733992Y615000D02*
X723500D01*
G01X717516Y616983D02*
X732983D01*
G01X707800Y607267D02*
X717516Y616983D01*
G01X707800Y604167D02*
Y607267D01*
G01X695957Y592324D02*
X707800Y604167D01*
G01X764164Y2432D02*
X1023524D01*
G01X761332Y5264D02*
X764164Y2432D01*
G01X740049Y5264D02*
X761332D01*
G01X739297Y6016D02*
X740049Y5264D01*
G01X739291Y6016D02*
X739297D01*
G01X729600Y15707D02*
X739291Y6016D01*
G01X729600Y17991D02*
Y15707D01*
G01X735661Y-15984D02*
X1265673D01*
G01X726549Y-6872D02*
X735661Y-15984D01*
G01X726549Y-6779D02*
Y-6872D01*
G01X726151Y-6381D02*
X726549Y-6779D01*
G01X726151Y-1913D02*
Y-6381D01*
G01X736062Y-14257D02*
X1265031D01*
G01X728055Y-6250D02*
X736062Y-14257D01*
G01X728055Y-1123D02*
Y-6250D01*
G01X727303Y-5938D02*
Y-1435D01*
G01X727302Y-5939D02*
X727303Y-5938D01*
G01X727302Y-6561D02*
Y-5939D01*
G01X735973Y-15232D02*
X727302Y-6561D01*
G01X1265361Y-15232D02*
X735973D01*
G01X766174Y3184D02*
X1019969D01*
G01X763342Y6016D02*
X766174Y3184D01*
G01X740361Y6016D02*
X763342D01*
G01X732424Y13953D02*
X740361Y6016D01*
G01X732424Y16159D02*
Y13953D01*
G01X734256Y17991D02*
X732424Y16159D01*
G01X736133Y-17392D02*
X735605Y-17920D01*
G01X1266257Y-17392D02*
X736133D01*
G01X768373Y26323D02*
X760368Y34328D01*
G01X1018397Y26323D02*
X768373D01*
G01X736502Y-12569D02*
X1019261D01*
G01X730191Y-6258D02*
X736502Y-12569D01*
G01X730191Y-565D02*
Y-6258D01*
G01X725644Y3982D02*
X730191Y-565D01*
G01X725644Y4768D02*
Y3982D01*
G01X728807Y-5938D02*
Y-811D01*
G01X736190Y-13321D02*
X728807Y-5938D01*
G01X1019573Y-13321D02*
X736190D01*
G01X762380Y528D02*
X1021269D01*
G01X762373Y535D02*
X762380Y528D01*
G01X760332Y535D02*
X762373D01*
G01X758211Y2656D02*
X760332Y535D01*
G01X735151Y2656D02*
X758211D01*
G01X732484Y-11D02*
X735151Y2656D01*
G01X731267Y-11D02*
X732484D01*
G01X726796Y4460D02*
X731267Y-11D01*
G01X726796Y8033D02*
Y4460D01*
G01X762775Y1480D02*
X1022879D01*
G01X760223Y4032D02*
X762775Y1480D01*
G01X739260Y4032D02*
X760223D01*
G01X729454Y13838D02*
X739260Y4032D01*
G01X727748Y13838D02*
X729454D01*
G01X767647Y23507D02*
X1019123D01*
G01X759330Y31824D02*
X767647Y23507D01*
G01X753819Y31824D02*
X759330D01*
G01X746700Y38943D02*
X753819Y31824D01*
G01X770037Y56550D02*
X1015879D01*
G01X755394Y71193D02*
X770037Y56550D01*
G01X755394Y73406D02*
Y71193D01*
G01X753200Y75600D02*
X755394Y73406D01*
G01X748799Y75600D02*
X753200D01*
G01X748798Y75599D02*
X748799Y75600D01*
G01X747844Y75599D02*
X748798D01*
G01X747039Y76404D02*
X747844Y75599D01*
G01X737005Y76404D02*
X747039D01*
G01X734642Y78767D02*
X737005Y76404D01*
G01X733686Y78767D02*
X734642D01*
G01X733685Y78768D02*
X733686Y78767D01*
G01X731360Y78768D02*
X733685D01*
G01X728132Y81996D02*
X731360Y78768D01*
G01X734387Y77392D02*
X727701D01*
G01X737667Y74112D02*
X734387Y77392D01*
G01X737667Y67032D02*
Y74112D01*
G01X741547Y63152D02*
X737667Y67032D01*
G01X747039Y63152D02*
X741547D01*
G01X747072Y63185D02*
X747039Y63152D01*
G01X753564Y63185D02*
X747072D01*
G01X761434Y55315D02*
X753564Y63185D01*
G01X761434Y54805D02*
Y55315D01*
G01X761435Y54804D02*
X761434Y54805D01*
G01X761435Y53850D02*
Y54804D01*
G01X761434Y53849D02*
X761435Y53850D01*
G01X761434Y52345D02*
Y53849D01*
G01X768713Y45066D02*
X761434Y52345D01*
G01X1021298Y45066D02*
X768713D01*
G01X727021Y62341D02*
Y69640D01*
G01X736042Y53320D02*
X727021Y62341D01*
G01X736042Y53158D02*
Y53320D01*
G01X736043Y53157D02*
X736042Y53158D01*
G01X736043Y52308D02*
Y53157D01*
G01X736042Y52307D02*
X736043Y52308D01*
G01X736042Y49449D02*
Y52307D01*
G01X741411Y44080D02*
X736042Y49449D01*
G01X759320Y44080D02*
X741411D01*
G01X764367Y39033D02*
X759320Y44080D01*
G01X1024540Y39033D02*
X764367D01*
G01X765714Y92974D02*
X769781Y97041D01*
G01X758850Y92974D02*
X765714D01*
G01X753464Y98360D02*
X758850Y92974D01*
G01X734611Y92692D02*
X740279Y98360D01*
G01X734611Y92196D02*
Y92692D01*
G01X732565Y90150D02*
X734611Y92196D01*
G01X731780Y90150D02*
X732565D01*
G01X730038Y88408D02*
X731780Y90150D01*
G01X764904Y79666D02*
X763350Y81220D01*
G01X948117Y79666D02*
X764904D01*
G01X728273Y62860D02*
Y70159D01*
G01X732689Y58444D02*
X728273Y62860D01*
G01X748056Y58444D02*
X732689D01*
G01X766042Y40458D02*
X748056Y58444D01*
G01X766237Y40458D02*
X766042D01*
G01X766410Y40285D02*
X766237Y40458D01*
G01X1023932Y40285D02*
X766410D01*
G01X735241Y90062D02*
Y88329D01*
G01X736515Y91336D02*
X735241Y90062D01*
G01X736515Y91902D02*
Y91336D01*
G01X741069Y96456D02*
X736515Y91902D01*
G01X758460Y90670D02*
X752674Y96456D01*
G01X758779Y90670D02*
X758460D01*
G01X761930Y87519D02*
X758779Y90670D01*
G01X768910Y87519D02*
X761930D01*
G01X771240Y85189D02*
X768910Y87519D01*
G01X771240Y84473D02*
Y85189D01*
G01X772591Y83122D02*
X771240Y84473D01*
G01X939359Y83122D02*
X772591D01*
G01X733859Y93004D02*
X739967Y99112D01*
G01X733859Y92508D02*
Y93004D01*
G01X732291Y90940D02*
X733859Y92508D01*
G01X741369Y79860D02*
X736929Y84300D01*
G01X748473Y79860D02*
X741369D01*
G01X749233Y79100D02*
X748473Y79860D01*
G01X754670Y79100D02*
X749233D01*
G01X758850Y74920D02*
X754670Y79100D01*
G01X758850Y72627D02*
Y74920D01*
G01X771471Y60006D02*
X758850Y72627D01*
G01X1014445Y60006D02*
X771471D01*
G01X737667Y88526D02*
X735745Y86604D01*
G01X737667Y91424D02*
Y88526D01*
G01X741547Y95304D02*
X737667Y91424D01*
G01X757594Y84749D02*
X747039Y95304D01*
G01X757594Y80094D02*
Y84749D01*
G01X761154Y76534D02*
X757594Y80094D01*
G01X761154Y73820D02*
Y76534D01*
G01X767398Y67576D02*
X761154Y73820D01*
G01X770534Y67576D02*
X767398D01*
G01X771457Y66653D02*
X770534Y67576D01*
G01X771457Y64325D02*
Y66653D01*
G01X773472Y62310D02*
X771457Y64325D01*
G01X1009184Y62310D02*
X773472D01*
G01X770993Y58854D02*
X1014923D01*
G01X757698Y72149D02*
X770993Y58854D01*
G01X757698Y74442D02*
Y72149D01*
G01X754192Y77948D02*
X757698Y74442D01*
G01X748755Y77948D02*
X754192D01*
G01X747995Y78708D02*
X748755Y77948D01*
G01X737961Y78708D02*
X747995D01*
G01X735539Y81130D02*
X737961Y78708D01*
G01X734230Y81130D02*
X735539D01*
G01X732734Y82626D02*
X734230Y81130D01*
G01X729402Y72431D02*
X725025Y76808D01*
G01X733868Y72431D02*
X729402D01*
G01X735363Y70936D02*
X733868Y72431D01*
G01X735363Y66076D02*
Y70936D01*
G01X736512Y64927D02*
X735363Y66076D01*
G01X736512Y64003D02*
Y64927D01*
G01X739667Y60848D02*
X736512Y64003D01*
G01X752131Y60848D02*
X739667D01*
G01X758851Y54128D02*
X752131Y60848D01*
G01X758851Y51245D02*
Y54128D01*
G01X767334Y42762D02*
X758851Y51245D01*
G01X1022428Y42762D02*
X767334D01*
G01X766192Y91822D02*
X770259Y95889D01*
G01X758938Y91822D02*
X766192D01*
G01X753152Y97608D02*
X758938Y91822D01*
G01X735363Y92380D02*
X740591Y97608D01*
G01X735363Y91814D02*
Y92380D01*
G01X732599Y89050D02*
X735363Y91814D01*
G01X732599Y88408D02*
Y89050D01*
G01X727619Y58384D02*
X725095D01*
G01X733343Y52660D02*
X727619Y58384D01*
G01X733343Y48710D02*
Y52660D01*
G01X740606Y41447D02*
X733343Y48710D01*
G01X747905Y41447D02*
X740606D01*
G01X755024Y34328D02*
X747905Y41447D01*
G01X760368Y34328D02*
X755024D01*
G01X731910Y96410D02*
Y92790D01*
G01X727801Y59790D02*
X725424D01*
G01X734790Y52801D02*
X727801Y59790D01*
G01X734790Y48898D02*
Y52801D01*
G01X740860Y42828D02*
X734790Y48898D01*
G01X758672Y42828D02*
X740860D01*
G01X763719Y37781D02*
X758672Y42828D01*
G01X1029793Y37781D02*
X763719D01*
G01X766824Y84367D02*
Y85943D01*
G01X769221Y81970D02*
X766824Y84367D01*
G01X943728Y81970D02*
X769221D01*
G01X761774Y82944D02*
X763930Y85100D01*
G01X761774Y77697D02*
Y82944D01*
G01X762747Y76724D02*
X761774Y77697D01*
G01X768474Y76724D02*
X762747D01*
G01X769900Y78150D02*
X768474Y76724D01*
G01X951250Y78150D02*
X769900D01*
G01X729880Y73583D02*
X725503Y77960D01*
G01X734346Y73583D02*
X729880D01*
G01X736515Y71414D02*
X734346Y73583D01*
G01X736515Y66554D02*
Y71414D01*
G01X737664Y65405D02*
X736515Y66554D01*
G01X737664Y64481D02*
Y65405D01*
G01X740145Y62000D02*
X737664Y64481D01*
G01X752609Y62000D02*
X740145D01*
G01X760282Y54327D02*
X752609Y62000D01*
G01X760282Y51867D02*
Y54327D01*
G01X768235Y43914D02*
X760282Y51867D01*
G01X1021950Y43914D02*
X768235D01*
G01X729525Y63379D02*
Y70678D01*
G01X733208Y59696D02*
X729525Y63379D01*
G01X748575Y59696D02*
X733208D01*
G01X766561Y41710D02*
X748575Y59696D01*
G01X766756Y41710D02*
X766561D01*
G01X766856Y41610D02*
X766756Y41710D01*
G01X1023280Y41610D02*
X766856D01*
G01X731838Y79920D02*
X728610Y83148D01*
G01X734163Y79920D02*
X731838D01*
G01X734164Y79921D02*
X734163Y79920D01*
G01X735118Y79921D02*
X734164D01*
G01X737483Y77556D02*
X735118Y79921D01*
G01X747517Y77556D02*
X737483D01*
G01X748321Y76752D02*
X747517Y77556D01*
G01X753678Y76752D02*
X748321D01*
G01X756546Y73884D02*
X753678Y76752D01*
G01X756546Y71671D02*
Y73884D01*
G01X770515Y57702D02*
X756546Y71671D01*
G01X1015401Y57702D02*
X770515D01*
G01X741847Y81012D02*
X737407Y85452D01*
G01X748951Y81012D02*
X741847D01*
G01X749711Y80252D02*
X748951Y81012D01*
G01X755148Y80252D02*
X749711D01*
G01X760002Y75398D02*
X755148Y80252D01*
G01X760002Y73105D02*
Y75398D01*
G01X771949Y61158D02*
X760002Y73105D01*
G01X1013967Y61158D02*
X771949D01*
G01X739568Y38943D02*
X746700D01*
G01X730839Y47672D02*
X739568Y38943D01*
G01X730839Y51613D02*
Y47672D01*
G01X730680Y51772D02*
X730839Y51613D01*
G01X730680Y51781D02*
Y51772D01*
G01X726749Y55712D02*
X730680Y51781D01*
G01X741700Y104829D02*
Y102000D01*
G01X746051Y109180D02*
X741700Y104829D01*
G01X875024Y109180D02*
X746051D01*
G01X740109Y114380D02*
X740073Y114344D01*
G01X872782Y114380D02*
X740109D01*
G01X769781Y97041D02*
X959351D01*
G01X740279Y98360D02*
X753464D01*
G01X756376Y104476D02*
X752900Y101000D01*
G01X773596Y104476D02*
X756376D01*
G01X776516Y101556D02*
X773596Y104476D01*
G01X956506Y101556D02*
X776516D01*
G01X752674Y96456D02*
X741069D01*
G01X777776Y102708D02*
X956008D01*
G01X774757Y105727D02*
X777776Y102708D01*
G01X748427Y105727D02*
X774757D01*
G01X746600Y103900D02*
X748427Y105727D01*
G01X759181Y98224D02*
X958904D01*
G01X758336Y97379D02*
X759181Y98224D01*
G01X755599Y97379D02*
X758336D01*
G01X753866Y99112D02*
X755599Y97379D01*
G01X739967Y99112D02*
X753866D01*
G01X747039Y95304D02*
X741547D01*
G01X770259Y95889D02*
X959899D01*
G01X740591Y97608D02*
X753152D01*
G01X738835Y103335D02*
X731910Y96410D01*
G01X738835Y107665D02*
Y103335D01*
G01X742454Y111284D02*
X738835Y107665D01*
G01X874151Y111284D02*
X742454D01*
G01X744200Y104376D02*
Y102800D01*
G01X747456Y107632D02*
X744200Y104376D01*
G01X876200Y107632D02*
X747456D01*
G01X734971Y95230D02*
X733740D01*
G01X739763Y100022D02*
X734971Y95230D01*
G01X739763Y104927D02*
Y100022D01*
G01X744967Y110131D02*
X739763Y104927D01*
G01X874628Y110131D02*
X744967D01*
G01X958380Y99400D02*
X756800D01*
G01X758751Y102000D02*
X756800D01*
G01X760347Y100404D02*
X758751Y102000D01*
G01X958104Y100404D02*
X760347D01*
G01X747115Y523428D02*
X753023Y529336D01*
G01X741568Y523428D02*
X747115D01*
G01X734000Y515860D02*
X741568Y523428D01*
G01X734000Y511580D02*
Y515860D01*
G01X732120Y509700D02*
X734000Y511580D01*
G01X737626Y489460D02*
X875596D01*
G01X733650Y493436D02*
X737626Y489460D01*
G01X746637Y524580D02*
X751871Y529814D01*
G01X741002Y524580D02*
X746637D01*
G01X734574Y518152D02*
X741002Y524580D01*
G01X730580Y518152D02*
X734574D01*
G01X746242Y525532D02*
X750919Y530209D01*
G01X740607Y525532D02*
X746242D01*
G01X734179Y519104D02*
X740607Y525532D01*
G01X730185Y519104D02*
X734179D01*
G01X754558Y493236D02*
X875364D01*
G01X752442Y495352D02*
X754558Y493236D01*
G01X736856Y488708D02*
X732880Y492684D01*
G01X871842Y488708D02*
X736856D01*
G01X747227Y522476D02*
X753775Y529024D01*
G01X741963Y522476D02*
X747227D01*
G01X735204Y515717D02*
X741963Y522476D01*
G01X735204Y511437D02*
Y515717D01*
G01X732515Y508748D02*
X735204Y511437D01*
G01X755672Y495140D02*
X877370D01*
G01X753556Y497256D02*
X755672Y495140D01*
G01X734138Y497256D02*
X753556D01*
G01X733994Y497400D02*
X734138Y497256D01*
G01X747598Y521500D02*
X754727Y528629D01*
G01X742342Y521500D02*
X747598D01*
G01X737500Y516658D02*
X742342Y521500D01*
G01X737500Y512190D02*
Y516658D01*
G01X733010Y507700D02*
X737500Y512190D01*
G01X736230Y487300D02*
X871258D01*
G01X732254Y491276D02*
X736230Y487300D01*
G01X755072Y494388D02*
X752956Y496504D01*
G01X876412Y494388D02*
X755072D01*
G01X737976Y490212D02*
X733988Y494200D01*
G01X875908Y490212D02*
X737976D01*
G01X764689Y541339D02*
X1020071D01*
G01X753023Y529673D02*
X764689Y541339D01*
G01X753023Y529336D02*
Y529673D01*
G01X760516Y579759D02*
X1019971D01*
G01X759356Y578599D02*
X760516Y579759D01*
G01X741108Y578599D02*
X759356D01*
G01X726613Y564104D02*
X741108Y578599D01*
G01X744132Y559267D02*
X743103Y560296D01*
G01X746760Y559267D02*
X744132D01*
G01X760479Y545548D02*
X746760Y559267D01*
G01X1019277Y545548D02*
X760479D01*
G01X761489Y577455D02*
X1018895D01*
G01X745834Y561800D02*
X761489Y577455D01*
G01X744444Y560019D02*
X743415Y561048D01*
G01X756743Y560019D02*
X744444D01*
G01X759225Y557537D02*
X756743Y560019D01*
G01X915431Y557537D02*
X759225D01*
G01X755185Y543444D02*
X1020480D01*
G01X751871Y540130D02*
X755185Y543444D01*
G01X751871Y529814D02*
Y540130D01*
G01X740819Y597600D02*
X727567Y584348D01*
G01X754790Y544396D02*
X1020085D01*
G01X750919Y540525D02*
X754790Y544396D01*
G01X750919Y530209D02*
Y540525D01*
G01X735317Y582152D02*
X728265Y575100D01*
G01X758019Y582152D02*
X735317D01*
G01X759082Y583215D02*
X758019Y582152D01*
G01X1020288Y583215D02*
X759082D01*
G01X760994Y578607D02*
X1019392D01*
G01X759834Y577447D02*
X760994Y578607D01*
G01X741586Y577447D02*
X759834D01*
G01X727091Y562952D02*
X741586Y577447D01*
G01X764821Y540124D02*
X1019460D01*
G01X764335Y539638D02*
X764821Y540124D01*
G01X764052Y539638D02*
X764335D01*
G01X753775Y529361D02*
X764052Y539638D01*
G01X753775Y529024D02*
Y529361D01*
G01X760038Y580911D02*
X1020486D01*
G01X758878Y579751D02*
X760038Y580911D01*
G01X740630Y579751D02*
X758878D01*
G01X726135Y565256D02*
X740630Y579751D01*
G01X764447Y538686D02*
X1019198D01*
G01X754727Y528966D02*
X764447Y538686D01*
G01X754727Y528629D02*
Y528966D01*
G01X728045Y583196D02*
X741154Y596305D01*
G01X735712Y581200D02*
X728660Y574148D01*
G01X758697Y581200D02*
X735712D01*
G01X759560Y582063D02*
X758697Y581200D01*
G01X1020766Y582063D02*
X759560D01*
G01X742176Y616298D02*
X1038702D01*
G01X734878Y609000D02*
X742176Y616298D01*
G01X725829Y609000D02*
X734878D01*
G01X1292482Y597600D02*
X740819D01*
G01X739010Y621715D02*
X1040785D01*
G01X733119Y615824D02*
X739010Y621715D01*
G01X739555Y620563D02*
X733992Y615000D01*
G01X1040437Y620563D02*
X739555D01*
G01X729616Y612307D02*
Y610863D01*
G01X730309Y613000D02*
X729616Y612307D01*
G01X735408Y613000D02*
X730309D01*
G01X740610Y618202D02*
X735408Y613000D01*
G01X1039798Y618202D02*
X740610D01*
G01X740215Y619154D02*
X1039403D01*
G01X735013Y613952D02*
X740215Y619154D01*
G01X729938Y613952D02*
X735013D01*
G01X726857Y610871D02*
X729938Y613952D01*
G01X738867Y622867D02*
X1041133D01*
G01X732983Y616983D02*
X738867Y622867D01*
G01X741154Y596305D02*
X1291945D01*
G01X735038Y611000D02*
X732500D01*
G01X741088Y617050D02*
X735038Y611000D01*
G01X1039450Y617050D02*
X741088D01*
G01X739307Y598850D02*
X1292862D01*
G01X846818Y209725D02*
X914178D01*
G01X844996Y207903D02*
X846818Y209725D01*
G01X812968Y207903D02*
X844996D01*
G01X810457Y205392D02*
X812968Y207903D01*
G01X805557Y205392D02*
X810457D01*
G01X803134Y202969D02*
X805557Y205392D01*
G01X845498Y212043D02*
X913178D01*
G01X843046Y209591D02*
X845498Y212043D01*
G01X812053Y209591D02*
X843046D01*
G01X809357Y206895D02*
X812053Y209591D01*
G01X798119Y206895D02*
X809357D01*
G01X792514Y201290D02*
X798119Y206895D01*
G01X847192Y208824D02*
X914340D01*
G01X845370Y207002D02*
X847192Y208824D01*
G01X813324Y207002D02*
X845370D01*
G01X809851Y203529D02*
X813324Y207002D01*
G01X808165Y203529D02*
X809851D01*
G01X845865Y211157D02*
X913355D01*
G01X843413Y208705D02*
X845865Y211157D01*
G01X812512Y208705D02*
X843413D01*
G01X809951Y206144D02*
X812512Y208705D01*
G01X801954Y206144D02*
X809951D01*
G01X797717Y201907D02*
X801954Y206144D01*
G01X847935Y207404D02*
X917158D01*
G01X846684Y206153D02*
X847935Y207404D01*
G01X816001Y206153D02*
X846684D01*
G01X814849Y205001D02*
X816001Y206153D01*
G01X842895Y201044D02*
X848322Y206471D01*
G01X820146Y201044D02*
X842895D01*
G01X818960Y202230D02*
X820146Y201044D01*
G01X881686Y115842D02*
X875024Y109180D01*
G01X951496Y115842D02*
X881686D01*
G01X879824Y119651D02*
X952994D01*
G01X873301Y113128D02*
X879824Y119651D01*
G01X879379Y120977D02*
X872782Y114380D01*
G01X953464Y120977D02*
X879379D01*
G01X880613Y117746D02*
X874151Y111284D01*
G01X952286Y117746D02*
X880613D01*
G01X880136Y118899D02*
X873413Y112176D01*
G01X952682Y118899D02*
X880136D01*
G01X883258Y114690D02*
X876200Y107632D01*
G01X951018Y114690D02*
X883258D01*
G01X881091Y116594D02*
X874628Y110131D01*
G01X951808Y116594D02*
X881091D01*
G01X848322Y206471D02*
X916718D01*
G01X881334Y483722D02*
X960508D01*
G01X875596Y489460D02*
X881334Y483722D01*
G01X882974Y485626D02*
X959718D01*
G01X875364Y493236D02*
X882974Y485626D01*
G01X877580Y482970D02*
X871842Y488708D01*
G01X961753Y482970D02*
X877580D01*
G01X883810Y488700D02*
X958790D01*
G01X877370Y495140D02*
X883810Y488700D01*
G01X878164Y481562D02*
X962337D01*
G01X878163Y481561D02*
X878164Y481562D01*
G01X876997Y481561D02*
X878163D01*
G01X871258Y487300D02*
X876997Y481561D01*
G01X883290Y487510D02*
X876412Y494388D01*
G01X959220Y487510D02*
X883290D01*
G01X881646Y484474D02*
X875908Y490212D01*
G01X960196Y484474D02*
X881646D01*
G01X955800Y87349D02*
X948117Y79666D01*
G01X955800Y87649D02*
Y87349D01*
G01X957121Y88970D02*
X955800Y87649D01*
G01X958430Y88970D02*
X957121D01*
G01X959012Y88388D02*
X958430Y88970D01*
G01X961282Y88388D02*
X959012D01*
G01X962400Y89506D02*
X961282Y88388D01*
G01X962400Y93310D02*
Y89506D01*
G01X963422Y94332D02*
X962400Y93310D01*
G01X968016Y94332D02*
X963422D01*
G01X969169Y95485D02*
X968016Y94332D01*
G01X941200Y84963D02*
X939359Y83122D01*
G01X941200Y86600D02*
Y84963D01*
G01X949337Y94737D02*
X941200Y86600D01*
G01X950750Y88992D02*
X943728Y81970D01*
G01X950750Y89507D02*
Y88992D01*
G01X953233Y91990D02*
X950750Y89507D01*
G01X955060Y91990D02*
X953233D01*
G01X956550Y90500D02*
X955060Y91990D01*
G01X957960Y90500D02*
X956550D01*
G01X962944Y95484D02*
X957960Y90500D01*
G01X959390Y86290D02*
X951250Y78150D01*
G01X961860Y86290D02*
X959390D01*
G01X962334Y85816D02*
X961860Y86290D01*
G01X964629Y85816D02*
X962334D01*
G01X965720Y86907D02*
X964629Y85816D01*
G01X965720Y90591D02*
Y86907D01*
G01X968309Y93180D02*
X965720Y90591D01*
G01X968494Y93180D02*
X968309D01*
G01X969647Y94333D02*
X968494Y93180D01*
G01X1024314Y94333D02*
X969647D01*
G01X954594Y112744D02*
X951496Y115842D01*
G01X1023731Y112744D02*
X954594D01*
G01X956093Y116552D02*
X1021707D01*
G01X952994Y119651D02*
X956093Y116552D01*
G01X956637Y117804D02*
X953464Y120977D01*
G01X1021188Y117804D02*
X956637D01*
G01X967257Y100093D02*
X1021924D01*
G01X966104Y98940D02*
X967257Y100093D01*
G01X961250Y98940D02*
X966104D01*
G01X959351Y97041D02*
X961250Y98940D01*
G01X964202Y109252D02*
X956506Y101556D01*
G01X1025129Y109252D02*
X964202D01*
G01X1023836Y95485D02*
X969169D01*
G01X960427Y94737D02*
X949337D01*
G01X962326Y96636D02*
X960427Y94737D01*
G01X967060Y96636D02*
X962326D01*
G01X968213Y97789D02*
X967060Y96636D01*
G01X1022880Y97789D02*
X968213D01*
G01X963704Y110404D02*
X1024651D01*
G01X956008Y102708D02*
X963704Y110404D01*
G01X966109Y101245D02*
X1021436D01*
G01X964956Y100092D02*
X966109Y101245D01*
G01X960772Y100092D02*
X964956D01*
G01X958904Y98224D02*
X960772Y100092D01*
G01X967735Y98941D02*
X1022402D01*
G01X966582Y97788D02*
X967735Y98941D01*
G01X961798Y97788D02*
X966582D01*
G01X959899Y95889D02*
X961798Y97788D01*
G01X955384Y114648D02*
X952286Y117746D01*
G01X1022941Y114648D02*
X955384D01*
G01X955781Y115800D02*
X952682Y118899D01*
G01X1022563Y115800D02*
X955781D01*
G01X954116Y111592D02*
X951018Y114690D01*
G01X1024209Y111592D02*
X954116D01*
G01X954906Y113496D02*
X951808Y116594D01*
G01X1023419Y113496D02*
X954906D01*
G01X967538Y95484D02*
X962944D01*
G01X968691Y96637D02*
X967538Y95484D01*
G01X1023358Y96637D02*
X968691D01*
G01X960224Y101244D02*
X958380Y99400D01*
G01X964478Y101244D02*
X960224D01*
G01X970434Y107200D02*
X964478Y101244D01*
G01X1025771Y107200D02*
X970434D01*
G01X959696Y101996D02*
X958104Y100404D01*
G01X963460Y101996D02*
X959696D01*
G01X969563Y108099D02*
X963460Y101996D01*
G01X1025606Y108099D02*
X969563D01*
G01X927655Y217286D02*
G03X928971Y218073I-48J1574D01*
G01X927526Y217286D02*
X927655D01*
G01X925591Y216123D02*
G02X927526Y217286I2016J-1163D01*
G01X924255Y215335D02*
G03X925591Y216123I-28J1574D01*
G01X919788Y215335D02*
X924255D01*
G01X914178Y209725D02*
X919788Y215335D01*
G01X913178Y212043D02*
X920370Y219235D01*
G01X929623Y217696D02*
G02X930939Y218483I1364J-787D01*
G01X927702Y216534D02*
G03X929623Y217696I-95J2326D01*
G01X927579Y216534D02*
X927702D01*
G01X926243Y215746D02*
G02X927579Y216534I1364J-786D01*
G01X924308Y214583D02*
G03X926243Y215746I-81J2326D01*
G01X920099Y214583D02*
X924308D01*
G01X914340Y208824D02*
X920099Y214583D01*
G01X913355Y211157D02*
X920681Y218483D01*
G01X934415Y217286D02*
G03X935731Y218073I-48J1574D01*
G01X934286Y217286D02*
X934415D01*
G01X932351Y216123D02*
G02X934286Y217286I2016J-1163D01*
G01X931015Y215335D02*
G03X932351Y216123I-28J1574D01*
G01X930892Y215335D02*
X931015D01*
G01X928971Y214173D02*
G02X930892Y215335I2016J-1164D01*
G01X927655Y213386D02*
G03X928971Y214173I-48J1574D01*
G01X927526Y213386D02*
X927655D01*
G01X925591Y212223D02*
G02X927526Y213386I2016J-1163D01*
G01X924255Y211435D02*
G03X925591Y212223I-28J1574D01*
G01X924132Y211435D02*
X924255D01*
G01X922211Y210273D02*
G02X924132Y211435I2016J-1164D01*
G01X920895Y209486D02*
G03X922211Y210273I-48J1574D01*
G01X920803Y209486D02*
X920895D01*
G01X918831Y208322D02*
G02X920803Y209486I2016J-1163D01*
G01X918581Y207995D02*
G03X918831Y208322I-1116J1112D01*
G01X917158Y207404D02*
G03X918581Y207995I-3J2015D01*
G01X936383Y217696D02*
G02X937699Y218483I1364J-787D01*
G01X934462Y216534D02*
G03X936383Y217696I-95J2326D01*
G01X934339Y216534D02*
X934462D01*
G01X933003Y215746D02*
G02X934339Y216534I1364J-786D01*
G01X931068Y214583D02*
G03X933003Y215746I-81J2326D01*
G01X930939Y214583D02*
X931068D01*
G01X929623Y213796D02*
G02X930939Y214583I1364J-787D01*
G01X927702Y212634D02*
G03X929623Y213796I-95J2326D01*
G01X927579Y212634D02*
X927702D01*
G01X926243Y211846D02*
G02X927579Y212634I1364J-786D01*
G01X924308Y210683D02*
G03X926243Y211846I-81J2326D01*
G01X924179Y210683D02*
X924308D01*
G01X922863Y209896D02*
G02X924179Y210683I1364J-787D01*
G01X920912Y208733D02*
G03X922863Y209896I-65J2327D01*
G01X920799Y208733D02*
X920912D01*
G01X919483Y207946D02*
G02X920799Y208733I1364J-787D01*
G01X919113Y207463D02*
G03X919483Y207946I-1647J1645D01*
G01X916718Y206471D02*
G03X919113Y207463I0J3387D01*
G01X971574Y242635D02*
G03X972910Y243423I-28J1574D01*
G01X971451Y242635D02*
X971574D01*
G01X969530Y241473D02*
G02X971451Y242635I2016J-1164D01*
G01X968214Y240686D02*
G03X969530Y241473I-48J1574D01*
G01X968085Y240686D02*
X968214D01*
G01X966150Y239523D02*
G02X968085Y240686I2016J-1163D01*
G01X964814Y238735D02*
G03X966150Y239523I-28J1574D01*
G01X964691Y238735D02*
X964814D01*
G01X962770Y237573D02*
G02X964691Y238735I2016J-1164D01*
G01X961454Y236786D02*
G03X962770Y237573I-48J1574D01*
G01X961325Y236786D02*
X961454D01*
G01X959390Y235623D02*
G02X961325Y236786I2016J-1163D01*
G01X958054Y234835D02*
G03X959390Y235623I-28J1574D01*
G01X957931Y234835D02*
X958054D01*
G01X956010Y233673D02*
G02X957931Y234835I2016J-1164D01*
G01X956001Y233658D02*
X956010Y233673D01*
G01X954647Y232886D02*
G03X956001Y233658I0J1573D01*
G01X954603Y232886D02*
X954647D01*
G01X952631Y231722D02*
G02X954603Y232886I2016J-1163D01*
G01X951341Y230936D02*
G03X952631Y231722I-74J1573D01*
G01X951186Y230936D02*
X951341D01*
G01X949251Y229773D02*
G02X951186Y230936I2016J-1163D01*
G01X947949Y228986D02*
G03X949251Y229773I-62J1573D01*
G01X947806Y228986D02*
X947949D01*
G01X945871Y227823D02*
G02X947806Y228986I2016J-1163D01*
G01X944555Y227036D02*
G03X945871Y227823I-48J1574D01*
G01X944442Y227036D02*
X944555D01*
G01X942491Y225873D02*
G02X944442Y227036I2016J-1164D01*
G01X941175Y225086D02*
G03X942491Y225873I-48J1574D01*
G01X941046Y225086D02*
X941175D01*
G01X939111Y223923D02*
G02X941046Y225086I2016J-1163D01*
G01X937775Y223135D02*
G03X939111Y223923I-28J1574D01*
G01X937652Y223135D02*
X937775D01*
G01X935731Y221973D02*
G02X937652Y223135I2016J-1164D01*
G01X934415Y221186D02*
G03X935731Y221973I-48J1574D01*
G01X934286Y221186D02*
X934415D01*
G01X932351Y220023D02*
G02X934286Y221186I2016J-1163D01*
G01X931015Y219235D02*
G03X932351Y220023I-28J1574D01*
G01X930892Y219235D02*
X931015D01*
G01X928971Y218073D02*
G02X930892Y219235I2016J-1164D01*
G01X971574Y246535D02*
G03X972910Y247323I-28J1574D01*
G01X971451Y246535D02*
X971574D01*
G01X969530Y245373D02*
G02X971451Y246535I2016J-1164D01*
G01X968214Y244586D02*
G03X969530Y245373I-48J1574D01*
G01X968085Y244586D02*
X968214D01*
G01X966150Y243423D02*
G02X968085Y244586I2016J-1163D01*
G01X964814Y242635D02*
G03X966150Y243423I-28J1574D01*
G01X964691Y242635D02*
X964814D01*
G01X962770Y241473D02*
G02X964691Y242635I2016J-1164D01*
G01X961454Y240686D02*
G03X962770Y241473I-48J1574D01*
G01X961325Y240686D02*
X961454D01*
G01X959390Y239523D02*
G02X961325Y240686I2016J-1163D01*
G01X958054Y238735D02*
G03X959390Y239523I-28J1574D01*
G01X957931Y238735D02*
X958054D01*
G01X956010Y237573D02*
G02X957931Y238735I2016J-1164D01*
G01X956001Y237558D02*
X956010Y237573D01*
G01X954647Y236786D02*
G03X956001Y237558I0J1573D01*
G01X954566Y236786D02*
X954647D01*
G01X952631Y235623D02*
G02X954566Y236786I2016J-1163D01*
G01X951295Y234835D02*
G03X952631Y235623I-28J1574D01*
G01X951172Y234835D02*
X951295D01*
G01X949251Y233673D02*
G02X951172Y234835I2016J-1164D01*
G01X947935Y232886D02*
G03X949251Y233673I-48J1574D01*
G01X947843Y232886D02*
X947935D01*
G01X945871Y231722D02*
G02X947843Y232886I2016J-1163D01*
G01X944581Y230936D02*
G03X945871Y231722I-74J1573D01*
G01X944426Y230936D02*
X944581D01*
G01X942491Y229773D02*
G02X944426Y230936I2016J-1163D01*
G01X941189Y228986D02*
G03X942491Y229773I-62J1573D01*
G01X941046Y228986D02*
X941189D01*
G01X939111Y227823D02*
G02X941046Y228986I2016J-1163D01*
G01X937795Y227036D02*
G03X939111Y227823I-48J1574D01*
G01X937682Y227036D02*
X937795D01*
G01X935731Y225873D02*
G02X937682Y227036I2016J-1164D01*
G01X934415Y225086D02*
G03X935731Y225873I-48J1574D01*
G01X934286Y225086D02*
X934415D01*
G01X932351Y223923D02*
G02X934286Y225086I2016J-1163D01*
G01X931015Y223135D02*
G03X932351Y223923I-28J1574D01*
G01X930892Y223135D02*
X931015D01*
G01X928971Y221973D02*
G02X930892Y223135I2016J-1164D01*
G01X927655Y221186D02*
G03X928971Y221973I-48J1574D01*
G01X927526Y221186D02*
X927655D01*
G01X925591Y220023D02*
G02X927526Y221186I2016J-1163D01*
G01X924255Y219235D02*
G03X925591Y220023I-28J1574D01*
G01X920370Y219235D02*
X924255D01*
G01X971627Y241883D02*
G03X973562Y243046I-81J2326D01*
G01X971498Y241883D02*
X971627D01*
G01X970182Y241096D02*
G02X971498Y241883I1364J-787D01*
G01X968261Y239934D02*
G03X970182Y241096I-95J2326D01*
G01X968138Y239934D02*
X968261D01*
G01X966802Y239146D02*
G02X968138Y239934I1364J-786D01*
G01X964867Y237983D02*
G03X966802Y239146I-81J2326D01*
G01X964738Y237983D02*
X964867D01*
G01X963422Y237196D02*
G02X964738Y237983I1364J-787D01*
G01X961501Y236034D02*
G03X963422Y237196I-95J2326D01*
G01X961378Y236034D02*
X961501D01*
G01X960042Y235246D02*
G02X961378Y236034I1364J-786D01*
G01X958107Y234083D02*
G03X960042Y235246I-81J2326D01*
G01X958026Y234083D02*
X958107D01*
G01X956672Y233311D02*
G02X958026Y234083I1354J-801D01*
G01X956663Y233296D02*
X956672Y233311D01*
G01X954712Y232133D02*
G03X956663Y233296I-65J2327D01*
G01X954599Y232133D02*
X954712D01*
G01X953283Y231346D02*
G02X954599Y232133I1364J-787D01*
G01X951348Y230183D02*
G03X953283Y231346I-81J2326D01*
G01X951205Y230183D02*
X951348D01*
G01X949903Y229396D02*
G02X951205Y230183I1364J-786D01*
G01X947968Y228233D02*
G03X949903Y229396I-81J2326D01*
G01X947813Y228233D02*
X947968D01*
G01X946523Y227447D02*
G02X947813Y228233I1364J-787D01*
G01X944551Y226283D02*
G03X946523Y227447I-44J2327D01*
G01X944459Y226283D02*
X944551D01*
G01X943143Y225496D02*
G02X944459Y226283I1364J-787D01*
G01X941222Y224334D02*
G03X943143Y225496I-95J2326D01*
G01X941099Y224334D02*
X941222D01*
G01X939763Y223546D02*
G02X941099Y224334I1364J-786D01*
G01X937828Y222383D02*
G03X939763Y223546I-81J2326D01*
G01X937699Y222383D02*
X937828D01*
G01X936383Y221596D02*
G02X937699Y222383I1364J-787D01*
G01X934462Y220434D02*
G03X936383Y221596I-95J2326D01*
G01X934339Y220434D02*
X934462D01*
G01X933003Y219646D02*
G02X934339Y220434I1364J-786D01*
G01X931068Y218483D02*
G03X933003Y219646I-81J2326D01*
G01X930939Y218483D02*
X931068D01*
G01X971627Y245783D02*
G03X973562Y246946I-81J2326D01*
G01X971498Y245783D02*
X971627D01*
G01X970182Y244996D02*
G02X971498Y245783I1364J-787D01*
G01X968261Y243834D02*
G03X970182Y244996I-95J2326D01*
G01X968138Y243834D02*
X968261D01*
G01X966802Y243046D02*
G02X968138Y243834I1364J-786D01*
G01X964867Y241883D02*
G03X966802Y243046I-81J2326D01*
G01X964738Y241883D02*
X964867D01*
G01X963422Y241096D02*
G02X964738Y241883I1364J-787D01*
G01X961501Y239934D02*
G03X963422Y241096I-95J2326D01*
G01X961378Y239934D02*
X961501D01*
G01X960042Y239146D02*
G02X961378Y239934I1364J-786D01*
G01X958107Y237983D02*
G03X960042Y239146I-81J2326D01*
G01X958026Y237983D02*
X958107D01*
G01X956672Y237211D02*
G02X958026Y237983I1354J-801D01*
G01X956663Y237196D02*
X956672Y237211D01*
G01X954742Y236034D02*
G03X956663Y237196I-95J2326D01*
G01X954619Y236034D02*
X954742D01*
G01X953283Y235246D02*
G02X954619Y236034I1364J-786D01*
G01X951348Y234083D02*
G03X953283Y235246I-81J2326D01*
G01X951219Y234083D02*
X951348D01*
G01X949903Y233296D02*
G02X951219Y234083I1364J-787D01*
G01X947952Y232133D02*
G03X949903Y233296I-65J2327D01*
G01X947839Y232133D02*
X947952D01*
G01X946523Y231346D02*
G02X947839Y232133I1364J-787D01*
G01X944588Y230183D02*
G03X946523Y231346I-81J2326D01*
G01X944445Y230183D02*
X944588D01*
G01X943143Y229396D02*
G02X944445Y230183I1364J-786D01*
G01X941208Y228233D02*
G03X943143Y229396I-81J2326D01*
G01X941053Y228233D02*
X941208D01*
G01X939763Y227447D02*
G02X941053Y228233I1364J-787D01*
G01X937791Y226283D02*
G03X939763Y227447I-44J2327D01*
G01X937699Y226283D02*
X937791D01*
G01X936383Y225496D02*
G02X937699Y226283I1364J-787D01*
G01X934462Y224334D02*
G03X936383Y225496I-95J2326D01*
G01X934339Y224334D02*
X934462D01*
G01X933003Y223546D02*
G02X934339Y224334I1364J-786D01*
G01X931068Y222383D02*
G03X933003Y223546I-81J2326D01*
G01X930939Y222383D02*
X931068D01*
G01X929623Y221596D02*
G02X930939Y222383I1364J-787D01*
G01X927702Y220434D02*
G03X929623Y221596I-95J2326D01*
G01X927579Y220434D02*
X927702D01*
G01X926243Y219646D02*
G02X927579Y220434I1364J-786D01*
G01X924308Y218483D02*
G03X926243Y219646I-81J2326D01*
G01X920681Y218483D02*
X924308D01*
G01X971574Y238735D02*
G03X972910Y239523I-28J1574D01*
G01X971451Y238735D02*
X971574D01*
G01X969530Y237573D02*
G02X971451Y238735I2016J-1164D01*
G01X968214Y236786D02*
G03X969530Y237573I-48J1574D01*
G01X968085Y236786D02*
X968214D01*
G01X966150Y235623D02*
G02X968085Y236786I2016J-1163D01*
G01X964814Y234835D02*
G03X966150Y235623I-28J1574D01*
G01X964691Y234835D02*
X964814D01*
G01X962770Y233673D02*
G02X964691Y234835I2016J-1164D01*
G01X961454Y232886D02*
G03X962770Y233673I-48J1574D01*
G01X961362Y232886D02*
X961454D01*
G01X959390Y231722D02*
G02X961362Y232886I2016J-1163D01*
G01X958100Y230936D02*
G03X959390Y231722I-74J1573D01*
G01X957945Y230936D02*
X958100D01*
G01X956010Y229773D02*
G02X957945Y230936I2016J-1163D01*
G01X954682Y228986D02*
G03X956010Y229773I-35J1573D01*
G01X954566Y228986D02*
X954682D01*
G01X952631Y227823D02*
G02X954566Y228986I2016J-1163D01*
G01X951315Y227036D02*
G03X952631Y227823I-48J1574D01*
G01X951202Y227036D02*
X951315D01*
G01X949251Y225873D02*
G02X951202Y227036I2016J-1164D01*
G01X947935Y225086D02*
G03X949251Y225873I-48J1574D01*
G01X947806Y225086D02*
X947935D01*
G01X945871Y223923D02*
G02X947806Y225086I2016J-1163D01*
G01X944535Y223135D02*
G03X945871Y223923I-28J1574D01*
G01X944412Y223135D02*
X944535D01*
G01X942491Y221973D02*
G02X944412Y223135I2016J-1164D01*
G01X941175Y221186D02*
G03X942491Y221973I-48J1574D01*
G01X941046Y221186D02*
X941175D01*
G01X939111Y220023D02*
G02X941046Y221186I2016J-1163D01*
G01X937775Y219235D02*
G03X939111Y220023I-28J1574D01*
G01X937652Y219235D02*
X937775D01*
G01X935731Y218073D02*
G02X937652Y219235I2016J-1164D01*
G01X971627Y237983D02*
G03X973562Y239146I-81J2326D01*
G01X971498Y237983D02*
X971627D01*
G01X970182Y237196D02*
G02X971498Y237983I1364J-787D01*
G01X968261Y236034D02*
G03X970182Y237196I-95J2326D01*
G01X968138Y236034D02*
X968261D01*
G01X966802Y235246D02*
G02X968138Y236034I1364J-786D01*
G01X964867Y234083D02*
G03X966802Y235246I-81J2326D01*
G01X964738Y234083D02*
X964867D01*
G01X963422Y233296D02*
G02X964738Y234083I1364J-787D01*
G01X961471Y232133D02*
G03X963422Y233296I-65J2327D01*
G01X961358Y232133D02*
X961471D01*
G01X960042Y231346D02*
G02X961358Y232133I1364J-787D01*
G01X958107Y230183D02*
G03X960042Y231346I-81J2326D01*
G01X957991Y230183D02*
X958107D01*
G01X956663Y229396D02*
G02X957991Y230183I1363J-786D01*
G01X954728Y228233D02*
G03X956663Y229396I-81J2326D01*
G01X954573Y228233D02*
X954728D01*
G01X953283Y227447D02*
G02X954573Y228233I1364J-787D01*
G01X951311Y226283D02*
G03X953283Y227447I-44J2327D01*
G01X951219Y226283D02*
X951311D01*
G01X949903Y225496D02*
G02X951219Y226283I1364J-787D01*
G01X947982Y224334D02*
G03X949903Y225496I-95J2326D01*
G01X947859Y224334D02*
X947982D01*
G01X946523Y223546D02*
G02X947859Y224334I1364J-786D01*
G01X944588Y222383D02*
G03X946523Y223546I-81J2326D01*
G01X944459Y222383D02*
X944588D01*
G01X943143Y221596D02*
G02X944459Y222383I1364J-787D01*
G01X941222Y220434D02*
G03X943143Y221596I-95J2326D01*
G01X941099Y220434D02*
X941222D01*
G01X939763Y219646D02*
G02X941099Y220434I1364J-786D01*
G01X937828Y218483D02*
G03X939763Y219646I-81J2326D01*
G01X937699Y218483D02*
X937828D01*
G01X963325Y486539D02*
X1037407D01*
G01X960508Y483722D02*
X963325Y486539D01*
G01X962592Y488500D02*
X1039026D01*
G01X959718Y485626D02*
X962592Y488500D01*
G01X964170Y485387D02*
X961753Y482970D01*
G01X1036929Y485387D02*
X964170D01*
G01X960535Y490445D02*
X1040485D01*
G01X958790Y488700D02*
X960535Y490445D01*
G01X964754Y483979D02*
X1036345D01*
G01X962337Y481562D02*
X964754Y483979D01*
G01X961362Y489652D02*
X959220Y487510D01*
G01X1039628Y489652D02*
X961362D01*
G01X963070Y487348D02*
X960196Y484474D01*
G01X1038548Y487348D02*
X963070D01*
G01X919500Y553468D02*
X915431Y557537D01*
G01X919500Y552703D02*
Y553468D01*
G01X925881Y546322D02*
X919500Y552703D01*
G01X1018421Y546322D02*
X925881D01*
G01X1032545Y5181D02*
X1271819D01*
G01X1027464Y100D02*
X1032545Y5181D01*
G01X1025856Y100D02*
X1027464D01*
G01X1023524Y2432D02*
X1025856Y100D01*
G01X1031702Y9184D02*
X1034953Y5933D01*
G01X1025969Y9184D02*
X1031702D01*
G01X1019969Y3184D02*
X1025969Y9184D01*
G01X1028653Y36579D02*
X1018397Y26323D01*
G01X1028639Y-5970D02*
Y-6615D01*
G01X1035582Y973D02*
X1028639Y-5970D01*
G01X1019261Y-12569D02*
X1033955Y2125D01*
G01X1019720Y-13174D02*
X1019573Y-13321D01*
G01X1265051Y-13174D02*
X1019720D01*
G01X1027734Y-2466D02*
X1033477Y3277D01*
G01X1024263Y-2466D02*
X1027734D01*
G01X1021269Y528D02*
X1024263Y-2466D01*
G01X1033039Y4229D02*
X1272214D01*
G01X1027910Y-900D02*
X1033039Y4229D01*
G01X1025259Y-900D02*
X1027910D01*
G01X1022879Y1480D02*
X1025259Y-900D01*
G01X1019123Y23507D02*
X1029691Y34075D01*
G01X1022784Y63455D02*
X1036637Y77308D01*
G01X1022784Y63385D02*
Y63455D01*
G01X1019165Y59766D02*
X1022784Y63385D01*
G01X1019095Y59766D02*
X1019165D01*
G01X1015879Y56550D02*
X1019095Y59766D01*
G01X1024801Y48569D02*
X1021298Y45066D01*
G01X1024801Y56996D02*
Y48569D01*
G01X1029429Y61624D02*
X1024801Y56996D01*
G01X1031153Y61624D02*
X1029429D01*
G01X1032635Y63106D02*
X1031153Y61624D01*
G01X1042021Y63106D02*
X1032635D01*
G01X1030057Y44550D02*
X1024540Y39033D01*
G01X1032838Y44550D02*
X1030057D01*
G01X1034090Y43298D02*
X1032838Y44550D01*
G01X1031661Y48014D02*
X1023932Y40285D01*
G01X1031661Y53239D02*
Y48014D01*
G01X1036097Y57675D02*
X1031661Y53239D01*
G01X1017661Y63222D02*
X1014445Y60006D01*
G01X1017731Y63222D02*
X1017661D01*
G01X1019328Y64819D02*
X1017731Y63222D01*
G01X1019328Y64889D02*
Y64819D01*
G01X1031645Y77206D02*
X1019328Y64889D01*
G01X1031645Y96774D02*
Y77206D01*
G01X1020586Y73712D02*
X1009184Y62310D01*
G01X1020586Y77709D02*
Y73712D01*
G01X1022872Y79995D02*
X1020586Y77709D01*
G01X1026891Y79995D02*
X1022872D01*
G01X1029341Y82445D02*
X1026891Y79995D01*
G01X1029341Y97730D02*
Y82445D01*
G01X1020480Y64411D02*
X1035788Y79719D01*
G01X1020480Y64341D02*
Y64411D01*
G01X1018209Y62070D02*
X1020480Y64341D01*
G01X1018139Y62070D02*
X1018209D01*
G01X1014923Y58854D02*
X1018139Y62070D01*
G01X1027554Y47888D02*
X1022428Y42762D01*
G01X1027554Y56026D02*
Y47888D01*
G01X1030848Y59320D02*
X1027554Y56026D01*
G01X1032109Y59320D02*
X1030848D01*
G01X1033591Y60802D02*
X1032109Y59320D01*
G01X1030421Y36579D02*
X1028653D01*
G01X1035108Y41266D02*
X1030421Y36579D01*
G01X1034058Y42046D02*
X1029793Y37781D01*
G01X1034007Y104026D02*
X1024314Y94333D01*
G01X1026402Y48366D02*
X1021950Y43914D01*
G01X1026402Y56670D02*
Y48366D01*
G01X1030204Y60472D02*
X1026402Y56670D01*
G01X1031631Y60472D02*
X1030204D01*
G01X1033113Y61954D02*
X1031631Y60472D01*
G01X1041543Y61954D02*
X1033113D01*
G01X1029276Y47606D02*
X1023280Y41610D01*
G01X1029276Y52782D02*
Y47606D01*
G01X1035525Y59031D02*
X1029276Y52782D01*
G01X1018617Y60918D02*
X1015401Y57702D01*
G01X1018687Y60918D02*
X1018617D01*
G01X1021632Y63863D02*
X1018687Y60918D01*
G01X1021632Y63933D02*
Y63863D01*
G01X1036159Y78460D02*
X1021632Y63933D01*
G01X1017183Y64374D02*
X1013967Y61158D01*
G01X1017253Y64374D02*
X1017183D01*
G01X1018176Y65297D02*
X1017253Y64374D01*
G01X1018176Y65367D02*
Y65297D01*
G01X1030493Y77684D02*
X1018176Y65367D01*
G01X1030493Y97252D02*
Y77684D01*
G01X1031459Y34075D02*
X1035988Y38604D01*
G01X1029691Y34075D02*
X1031459D01*
G01X1028437Y117450D02*
X1023731Y112744D01*
G01X1034295Y117450D02*
X1028437D01*
G01X1033059Y121713D02*
X1039461Y128115D01*
G01X1026868Y121713D02*
X1033059D01*
G01X1021707Y116552D02*
X1026868Y121713D01*
G01X1026349Y122965D02*
X1021188Y117804D01*
G01X1032540Y122965D02*
X1026349D01*
G01X1038942Y129367D02*
X1032540Y122965D01*
G01X1031617Y109786D02*
X1036933D01*
G01X1021924Y100093D02*
X1031617Y109786D01*
G01X1029871Y113994D02*
X1025129Y109252D01*
G01X1035729Y113994D02*
X1029871D01*
G01X1033529Y105178D02*
X1023836Y95485D01*
G01X1032573Y107482D02*
X1022880Y97789D01*
G01X1037889Y107482D02*
X1032573D01*
G01X1029393Y115146D02*
X1035251D01*
G01X1024651Y110404D02*
X1029393Y115146D01*
G01X1031139Y110938D02*
X1036455D01*
G01X1021453Y101252D02*
X1031139Y110938D01*
G01X1021436Y101245D02*
X1021453Y101252D01*
G01X1035441Y100570D02*
X1031645Y96774D01*
G01X1034485Y102874D02*
X1029341Y97730D01*
G01X1032095Y108634D02*
X1037411D01*
G01X1022402Y98941D02*
X1032095Y108634D01*
G01X1028025Y119732D02*
X1022941Y114648D01*
G01X1034379Y119732D02*
X1028025D01*
G01X1027527Y120764D02*
X1022563Y115800D01*
G01X1033638Y120764D02*
X1027527D01*
G01X1028915Y116298D02*
X1024209Y111592D01*
G01X1034773Y116298D02*
X1028915D01*
G01X1028125Y118202D02*
X1023419Y113496D01*
G01X1033983Y118202D02*
X1028125D01*
G01X1033051Y106330D02*
X1023358Y96637D01*
G01X1038367Y106330D02*
X1033051D01*
G01X1030661Y112090D02*
X1025771Y107200D01*
G01X1036519Y112090D02*
X1030661D01*
G01X1030349Y112842D02*
X1025606Y108099D01*
G01X1036207Y112842D02*
X1030349D01*
G01X1034963Y101722D02*
X1030493Y97252D01*
G01X999738Y259145D02*
X998586Y259809D01*
G01X999821Y258834D02*
X999738Y259145D01*
G01X998586Y258235D02*
G03X999821Y258834I-1J1574D01*
G01X998491Y258235D02*
X998586D01*
G01X996570Y257073D02*
G02X998491Y258235I2016J-1164D01*
G01X995254Y256286D02*
G03X996570Y257073I-48J1574D01*
G01X995125Y256286D02*
X995254D01*
G01X993190Y255123D02*
G02X995125Y256286I2016J-1163D01*
G01X991854Y254335D02*
G03X993190Y255123I-28J1574D01*
G01X991731Y254335D02*
X991854D01*
G01X989810Y253173D02*
G02X991731Y254335I2016J-1164D01*
G01X988494Y252386D02*
G03X989810Y253173I-48J1574D01*
G01X988365Y252386D02*
X988494D01*
G01X986430Y251223D02*
G02X988365Y252386I2016J-1163D01*
G01X985094Y250435D02*
G03X986430Y251223I-28J1574D01*
G01X984971Y250435D02*
X985094D01*
G01X983050Y249273D02*
G02X984971Y250435I2016J-1164D01*
G01X981734Y248486D02*
G03X983050Y249273I-48J1574D01*
G01X981605Y248486D02*
X981734D01*
G01X979670Y247323D02*
G02X981605Y248486I2016J-1163D01*
G01X978334Y246535D02*
G03X979670Y247323I-28J1574D01*
G01X978211Y246535D02*
X978334D01*
G01X976290Y245373D02*
G02X978211Y246535I2016J-1164D01*
G01X974974Y244586D02*
G03X976290Y245373I-48J1574D01*
G01X974845Y244586D02*
X974974D01*
G01X972910Y243423D02*
G02X974845Y244586I2016J-1163D01*
G01X995206Y260430D02*
Y261760D01*
G01X994950Y260174D02*
X995206Y260430D01*
G01X993190Y259023D02*
G02X994950Y260174I2016J-1162D01*
G01X991854Y258235D02*
G03X993190Y259023I-28J1574D01*
G01X991731Y258235D02*
X991854D01*
G01X989810Y257073D02*
G02X991731Y258235I2016J-1164D01*
G01X988494Y256286D02*
G03X989810Y257073I-48J1574D01*
G01X988365Y256286D02*
X988494D01*
G01X986430Y255123D02*
G02X988365Y256286I2016J-1163D01*
G01X985094Y254335D02*
G03X986430Y255123I-28J1574D01*
G01X984971Y254335D02*
X985094D01*
G01X983050Y253173D02*
G02X984971Y254335I2016J-1164D01*
G01X981734Y252386D02*
G03X983050Y253173I-48J1574D01*
G01X981605Y252386D02*
X981734D01*
G01X979670Y251223D02*
G02X981605Y252386I2016J-1163D01*
G01X978334Y250435D02*
G03X979670Y251223I-28J1574D01*
G01X978211Y250435D02*
X978334D01*
G01X976290Y249273D02*
G02X978211Y250435I2016J-1164D01*
G01X974974Y248486D02*
G03X976290Y249273I-48J1574D01*
G01X974845Y248486D02*
X974974D01*
G01X972910Y247323D02*
G02X974845Y248486I2016J-1163D01*
G01X1000813Y258524D02*
X1001965Y257860D01*
G01X1000461Y258429D02*
X1000813Y258524D01*
G01X998667Y257483D02*
G03X1000461Y258429I-80J2326D01*
G01X998538Y257483D02*
X998667D01*
G01X997222Y256696D02*
G02X998538Y257483I1364J-787D01*
G01X995301Y255534D02*
G03X997222Y256696I-95J2326D01*
G01X995178Y255534D02*
X995301D01*
G01X993842Y254746D02*
G02X995178Y255534I1364J-786D01*
G01X991907Y253583D02*
G03X993842Y254746I-81J2326D01*
G01X991778Y253583D02*
X991907D01*
G01X990462Y252796D02*
G02X991778Y253583I1364J-787D01*
G01X988541Y251634D02*
G03X990462Y252796I-95J2326D01*
G01X988418Y251634D02*
X988541D01*
G01X987082Y250846D02*
G02X988418Y251634I1364J-786D01*
G01X985147Y249683D02*
G03X987082Y250846I-81J2326D01*
G01X985018Y249683D02*
X985147D01*
G01X983702Y248896D02*
G02X985018Y249683I1364J-787D01*
G01X981781Y247734D02*
G03X983702Y248896I-95J2326D01*
G01X981658Y247734D02*
X981781D01*
G01X980322Y246946D02*
G02X981658Y247734I1364J-786D01*
G01X978387Y245783D02*
G03X980322Y246946I-81J2326D01*
G01X978258Y245783D02*
X978387D01*
G01X976942Y244996D02*
G02X978258Y245783I1364J-787D01*
G01X975021Y243834D02*
G03X976942Y244996I-95J2326D01*
G01X974898Y243834D02*
X975021D01*
G01X973562Y243046D02*
G02X974898Y243834I1364J-786D01*
G01X995206Y259190D02*
Y257860D01*
G01X994979Y259417D02*
X995206Y259190D01*
G01X993842Y258646D02*
G02X994979Y259417I1363J-787D01*
G01X991907Y257483D02*
G03X993842Y258646I-81J2326D01*
G01X991778Y257483D02*
X991907D01*
G01X990462Y256696D02*
G02X991778Y257483I1364J-787D01*
G01X988541Y255534D02*
G03X990462Y256696I-95J2326D01*
G01X988418Y255534D02*
X988541D01*
G01X987082Y254746D02*
G02X988418Y255534I1364J-786D01*
G01X985147Y253583D02*
G03X987082Y254746I-81J2326D01*
G01X985018Y253583D02*
X985147D01*
G01X983702Y252796D02*
G02X985018Y253583I1364J-787D01*
G01X981781Y251634D02*
G03X983702Y252796I-95J2326D01*
G01X981658Y251634D02*
X981781D01*
G01X980322Y250846D02*
G02X981658Y251634I1364J-786D01*
G01X978387Y249683D02*
G03X980322Y250846I-81J2326D01*
G01X978258Y249683D02*
X978387D01*
G01X976942Y248896D02*
G02X978258Y249683I1364J-787D01*
G01X975021Y247734D02*
G03X976942Y248896I-95J2326D01*
G01X974898Y247734D02*
X975021D01*
G01X973562Y246946D02*
G02X974898Y247734I1364J-786D01*
G01X998586Y254579D02*
Y255909D01*
G01X998330Y254323D02*
X998586Y254579D01*
G01X996570Y253173D02*
G02X998330Y254323I2016J-1164D01*
G01X995254Y252386D02*
G03X996570Y253173I-48J1574D01*
G01X995125Y252386D02*
X995254D01*
G01X993190Y251223D02*
G02X995125Y252386I2016J-1163D01*
G01X991854Y250435D02*
G03X993190Y251223I-28J1574D01*
G01X991731Y250435D02*
X991854D01*
G01X989810Y249273D02*
G02X991731Y250435I2016J-1164D01*
G01X988494Y248486D02*
G03X989810Y249273I-48J1574D01*
G01X988365Y248486D02*
X988494D01*
G01X986430Y247323D02*
G02X988365Y248486I2016J-1163D01*
G01X985094Y246535D02*
G03X986430Y247323I-28J1574D01*
G01X984971Y246535D02*
X985094D01*
G01X983050Y245373D02*
G02X984971Y246535I2016J-1164D01*
G01X981734Y244586D02*
G03X983050Y245373I-48J1574D01*
G01X981605Y244586D02*
X981734D01*
G01X979670Y243423D02*
G02X981605Y244586I2016J-1163D01*
G01X978334Y242635D02*
G03X979670Y243423I-28J1574D01*
G01X978211Y242635D02*
X978334D01*
G01X976290Y241473D02*
G02X978211Y242635I2016J-1164D01*
G01X974974Y240686D02*
G03X976290Y241473I-48J1574D01*
G01X974845Y240686D02*
X974974D01*
G01X972910Y239523D02*
G02X974845Y240686I2016J-1163D01*
G01X998586Y253339D02*
Y252009D01*
G01X998358Y253567D02*
X998586Y253339D01*
G01X997222Y252796D02*
G02X998358Y253567I1364J-787D01*
G01X995301Y251634D02*
G03X997222Y252796I-95J2326D01*
G01X995178Y251634D02*
X995301D01*
G01X993842Y250846D02*
G02X995178Y251634I1364J-786D01*
G01X991907Y249683D02*
G03X993842Y250846I-81J2326D01*
G01X991778Y249683D02*
X991907D01*
G01X990462Y248896D02*
G02X991778Y249683I1364J-787D01*
G01X988541Y247734D02*
G03X990462Y248896I-95J2326D01*
G01X988418Y247734D02*
X988541D01*
G01X987082Y246946D02*
G02X988418Y247734I1364J-786D01*
G01X985147Y245783D02*
G03X987082Y246946I-81J2326D01*
G01X985018Y245783D02*
X985147D01*
G01X983702Y244996D02*
G02X985018Y245783I1364J-787D01*
G01X981781Y243834D02*
G03X983702Y244996I-95J2326D01*
G01X981658Y243834D02*
X981781D01*
G01X980322Y243046D02*
G02X981658Y243834I1364J-786D01*
G01X978387Y241883D02*
G03X980322Y243046I-81J2326D01*
G01X978258Y241883D02*
X978387D01*
G01X976942Y241096D02*
G02X978258Y241883I1364J-787D01*
G01X975021Y239934D02*
G03X976942Y241096I-95J2326D01*
G01X974898Y239934D02*
X975021D01*
G01X973562Y239146D02*
G02X974898Y239934I1364J-786D01*
G01X1032961Y541896D02*
X1266864D01*
G01X1027503Y536438D02*
X1032961Y541896D01*
G01X1024972Y536438D02*
X1027503D01*
G01X1020071Y541339D02*
X1024972Y536438D01*
G01X1030841Y574699D02*
X1035616Y579474D01*
G01X1025031Y574699D02*
X1030841D01*
G01X1019971Y579759D02*
X1025031Y574699D01*
G01X1024311Y550582D02*
X1019277Y545548D01*
G01X1028618Y550582D02*
X1024311D01*
G01X1034048Y545152D02*
X1028618Y550582D01*
G01X1032198Y564152D02*
X1036043D01*
G01X1018895Y577455D02*
X1032198Y564152D01*
G01X1031975Y559876D02*
X1018421Y546322D01*
G01X1130612Y559876D02*
X1031975D01*
G01X1032816Y543048D02*
X1267952D01*
G01X1027386Y548478D02*
X1032816Y543048D01*
G01X1025515Y548478D02*
X1027386D01*
G01X1022561Y545524D02*
X1025515Y548478D01*
G01X1022560Y545524D02*
X1022561D01*
G01X1020480Y543444D02*
X1022560Y545524D01*
G01X1033211Y544000D02*
X1268400D01*
G01X1027781Y549430D02*
X1033211Y544000D01*
G01X1025120Y549430D02*
X1027781D01*
G01X1022166Y546476D02*
X1025120Y549430D01*
G01X1022165Y546476D02*
X1022166D01*
G01X1020085Y544396D02*
X1022165Y546476D01*
G01X1021670Y584597D02*
X1020288Y583215D01*
G01X1031603Y584597D02*
X1021670D01*
G01X1033270Y582930D02*
X1031603Y584597D01*
G01X1264765Y582930D02*
X1033270D01*
G01X1031319Y573547D02*
X1036094Y578322D01*
G01X1024452Y573547D02*
X1031319D01*
G01X1019392Y578607D02*
X1024452Y573547D01*
G01X1027980Y535285D02*
X1033776Y541081D01*
G01X1024299Y535285D02*
X1027980D01*
G01X1019460Y540124D02*
X1024299Y535285D01*
G01X1030302Y575852D02*
X1035076Y580626D01*
G01X1025545Y575852D02*
X1030302D01*
G01X1020486Y580911D02*
X1025545Y575852D01*
G01X1028375Y534333D02*
X1034171Y540129D01*
G01X1023551Y534333D02*
X1028375D01*
G01X1019198Y538686D02*
X1023551Y534333D01*
G01X1022148Y583445D02*
X1020766Y582063D01*
G01X1030735Y583445D02*
X1022148D01*
G01X1032402Y581778D02*
X1030735Y583445D01*
G01X1265344Y581778D02*
X1032402D01*
G01X1034953Y5933D02*
X1271507D01*
G01X1274103Y973D02*
X1035582D01*
G01X1033955Y2125D02*
X1273087D01*
G01X1033477Y3277D02*
X1272609D01*
G01X1048273Y61269D02*
X1264586D01*
G01X1047615Y61927D02*
X1048273Y61269D01*
G01X1044830Y61927D02*
X1047615D01*
G01X1042164Y64593D02*
X1044830Y61927D01*
G01X1042164Y73768D02*
Y64593D01*
G01X1038624Y77308D02*
X1042164Y73768D01*
G01X1036637Y77308D02*
X1038624D01*
G01X1044352Y60775D02*
X1042021Y63106D01*
G01X1047127Y60775D02*
X1044352D01*
G01X1047785Y60117D02*
X1047127Y60775D01*
G01X1267566Y60117D02*
X1047785D01*
G01X1042534Y43298D02*
X1034090D01*
G01X1043243Y42589D02*
X1042534Y43298D01*
G01X1269678Y42589D02*
X1043243D01*
G01X1039357Y57675D02*
X1036097D01*
G01X1042312Y54720D02*
X1039357Y57675D01*
G01X1042312Y45775D02*
Y54720D01*
G01X1044246Y43841D02*
X1042312Y45775D01*
G01X1269064Y43841D02*
X1044246D01*
G01X1049229Y63573D02*
X1261914D01*
G01X1048571Y64231D02*
X1049229Y63573D01*
G01X1046984Y64231D02*
X1048571D01*
G01X1046061Y65154D02*
X1046984Y64231D01*
G01X1046061Y66460D02*
Y65154D01*
G01X1047865Y68264D02*
X1046061Y66460D01*
G01X1047865Y71285D02*
Y68264D01*
G01X1045301Y73849D02*
X1047865Y71285D01*
G01X1045301Y75277D02*
Y73849D01*
G01X1040859Y79719D02*
X1045301Y75277D01*
G01X1035788Y79719D02*
X1040859D01*
G01X1041065Y60802D02*
X1033591D01*
G01X1043579Y58288D02*
X1041065Y60802D01*
G01X1046280Y58288D02*
X1043579D01*
G01X1047122Y57446D02*
X1046280Y58288D01*
G01X1265133Y57446D02*
X1047122D01*
G01X1041731Y41266D02*
X1035108D01*
G01X1042495Y40502D02*
X1041731Y41266D01*
G01X1271355Y40502D02*
X1042495D01*
G01X1042015Y42046D02*
X1034058D01*
G01X1042724Y41337D02*
X1042015Y42046D01*
G01X1270261Y41337D02*
X1042724D01*
G01X1043874Y59623D02*
X1041543Y61954D01*
G01X1046649Y59623D02*
X1043874D01*
G01X1047307Y58965D02*
X1046649Y59623D01*
G01X1266497Y58965D02*
X1047307D01*
G01X1039787Y59031D02*
X1035525D01*
G01X1041854Y56964D02*
X1039787Y59031D01*
G01X1044406Y56964D02*
X1041854D01*
G01X1045938Y55432D02*
X1044406Y56964D01*
G01X1045938Y45791D02*
Y55432D01*
G01X1046541Y45188D02*
X1045938Y45791D01*
G01X1268638Y45188D02*
X1046541D01*
G01X1040255Y78460D02*
X1036159D01*
G01X1043962Y74753D02*
X1040255Y78460D01*
G01X1043962Y73290D02*
Y74753D01*
G01X1046215Y71037D02*
X1043962Y73290D01*
G01X1046215Y68448D02*
Y71037D01*
G01X1044909Y67142D02*
X1046215Y68448D01*
G01X1044909Y64676D02*
Y67142D01*
G01X1046506Y63079D02*
X1044909Y64676D01*
G01X1048093Y63079D02*
X1046506D01*
G01X1048751Y62421D02*
X1048093Y63079D01*
G01X1264108Y62421D02*
X1048751D01*
G01X1050386Y37997D02*
X1272456D01*
G01X1049907Y37518D02*
X1050386Y37997D01*
G01X1040614Y37518D02*
X1049907D01*
G01X1039528Y38604D02*
X1040614Y37518D01*
G01X1035988Y38604D02*
X1039528D01*
G01X1041588Y124743D02*
X1034295Y117450D01*
G01X1195587Y124743D02*
X1041588D01*
G01X1039461Y128115D02*
X1193018D01*
G01X1192499Y129367D02*
X1038942D01*
G01X1045891Y118744D02*
X1201524D01*
G01X1036933Y109786D02*
X1045891Y118744D01*
G01X1044222Y122487D02*
X1035729Y113994D01*
G01X1198221Y122487D02*
X1044222D01*
G01X1038375Y105178D02*
X1033529D01*
G01X1048133Y114936D02*
X1038375Y105178D01*
G01X1084046Y114936D02*
X1048133D01*
G01X1099007Y99975D02*
X1084046Y114936D01*
G01X1047247Y116840D02*
X1037889Y107482D01*
G01X1085402Y116840D02*
X1047247D01*
G01X1099504Y102738D02*
X1085402Y116840D01*
G01X1043344Y123239D02*
X1197343D01*
G01X1035251Y115146D02*
X1043344Y123239D01*
G01X1045135Y119618D02*
X1200768D01*
G01X1036455Y110938D02*
X1045135Y119618D01*
G01X1036463Y100570D02*
X1035441D01*
G01X1036464Y100569D02*
X1036463Y100570D01*
G01X1040286Y100569D02*
X1036464D01*
G01X1049619Y109902D02*
X1040286Y100569D01*
G01X1082560Y109902D02*
X1049619D01*
G01X1097095Y95367D02*
X1082560Y109902D01*
G01X1037419Y102874D02*
X1034485D01*
G01X1037420Y102873D02*
X1037419Y102874D01*
G01X1039330Y102873D02*
X1037420D01*
G01X1049089Y112632D02*
X1039330Y102873D01*
G01X1083090Y112632D02*
X1049089D01*
G01X1098051Y97671D02*
X1083090Y112632D01*
G01X1046769Y117992D02*
X1202402D01*
G01X1037411Y108634D02*
X1046769Y117992D01*
G01X1041065Y126418D02*
X1034379Y119732D01*
G01X1194568Y126418D02*
X1041065D01*
G01X1040237Y127363D02*
X1033638Y120764D01*
G01X1193872Y127363D02*
X1040237D01*
G01X1042466Y123991D02*
X1034773Y116298D01*
G01X1196465Y123991D02*
X1042466D01*
G01X1041276Y125495D02*
X1033983Y118202D01*
G01X1195275Y125495D02*
X1041276D01*
G01X1047725Y115688D02*
X1038367Y106330D01*
G01X1084924Y115688D02*
X1047725D01*
G01X1099026Y101586D02*
X1084924Y115688D01*
G01X1045084Y120655D02*
X1036519Y112090D01*
G01X1199083Y120655D02*
X1045084D01*
G01X1037897Y104026D02*
X1034007D01*
G01X1037898Y104025D02*
X1037897Y104026D01*
G01X1038852Y104025D02*
X1037898D01*
G01X1048611Y113784D02*
X1038852Y104025D01*
G01X1083568Y113784D02*
X1048611D01*
G01X1098529Y98823D02*
X1083568Y113784D01*
G01X1044969Y121604D02*
X1036207Y112842D01*
G01X1198968Y121604D02*
X1044969D01*
G01X1036941Y101722D02*
X1034963D01*
G01X1036942Y101721D02*
X1036941Y101722D01*
G01X1039808Y101721D02*
X1036942D01*
G01X1049567Y111480D02*
X1039808Y101721D01*
G01X1082612Y111480D02*
X1049567D01*
G01X1097573Y96519D02*
X1082612Y111480D01*
G01X1041046Y482900D02*
X1207510D01*
G01X1037407Y486539D02*
X1041046Y482900D01*
G01X1042662Y484864D02*
X1206111D01*
G01X1039026Y488500D02*
X1042662Y484864D01*
G01X1040222Y482094D02*
X1036929Y485387D01*
G01X1208334Y482094D02*
X1040222D01*
G01X1043980Y486950D02*
X1204915D01*
G01X1040485Y490445D02*
X1043980Y486950D01*
G01X1039664Y480660D02*
X1208892D01*
G01X1036345Y483979D02*
X1039664Y480660D01*
G01X1043177Y486103D02*
X1039628Y489652D01*
G01X1205720Y486103D02*
X1043177D01*
G01X1042220Y483676D02*
X1038548Y487348D01*
G01X1206576Y483676D02*
X1042220D01*
G01X1035616Y579474D02*
X1266300D01*
G01X1274664Y545152D02*
X1034048D01*
G01X1044354Y576907D02*
X1267907D01*
G01X1042500Y575053D02*
X1044354Y576907D01*
G01X1042500Y565501D02*
Y575053D01*
G01X1041128Y564129D02*
X1042500Y565501D01*
G01X1036066Y564129D02*
X1041128D01*
G01X1036043Y564152D02*
X1036066Y564129D01*
G01X1036094Y578322D02*
X1266778D01*
G01X1033776Y541081D02*
X1264917D01*
G01X1035076Y580626D02*
X1265822D01*
G01X1034171Y540129D02*
X1264522D01*
G01X1040299Y614701D02*
X1282919D01*
G01X1038702Y616298D02*
X1040299Y614701D01*
G01X1041948Y620552D02*
X1101040D01*
G01X1040785Y621715D02*
X1041948Y620552D01*
G01X1041600Y619400D02*
X1040437Y620563D01*
G01X1101518Y619400D02*
X1041600D01*
G01X1040995Y617005D02*
X1039798Y618202D01*
G01X1102435Y617005D02*
X1040995D01*
G01X1041390Y617957D02*
X1102040D01*
G01X1040192Y619155D02*
X1041390Y617957D01*
G01X1039404Y619155D02*
X1040192D01*
G01X1039403Y619154D02*
X1039404Y619155D01*
G01X1042500Y621500D02*
X1100358D01*
G01X1041133Y622867D02*
X1042500Y621500D01*
G01X1040647Y615853D02*
X1039450Y617050D01*
G01X1102913Y615853D02*
X1040647D01*
G01X1206953Y99975D02*
X1099007D01*
G01X1205920Y102738D02*
X1099504D01*
G01X1207909Y95367D02*
X1097095D01*
G01X1210568Y97671D02*
X1098051D01*
G01X1206398Y101586D02*
X1099026D01*
G01X1207431Y98823D02*
X1098529D01*
G01X1211046Y96519D02*
X1097573D01*
G01X1142651Y268545D02*
X1144300Y266896D01*
G01X1142651Y281327D02*
Y268545D01*
G01X1108125Y276799D02*
X1116152Y284826D01*
G01X1148104Y274696D02*
X1144300D01*
G01X1150100Y272700D02*
X1148104Y274696D01*
G01X1151900Y272700D02*
X1150100D01*
G01X1153900Y270700D02*
X1151900Y272700D01*
G01X1155300Y270700D02*
X1153900D01*
G01X1157300Y268700D02*
X1155300Y270700D01*
G01X1141614Y282364D02*
X1142651Y281327D01*
G01X1140211Y282364D02*
X1141614D01*
G01X1138373Y284202D02*
X1140211Y282364D01*
G01X1137170Y284202D02*
X1138373D01*
G01X1135231Y286141D02*
X1137170Y284202D01*
G01X1133256Y286141D02*
X1135231D01*
G01X1131431Y287966D02*
X1133256Y286141D01*
G01X1130129Y287966D02*
X1131431D01*
G01X1128304Y286141D02*
X1130129Y287966D01*
G01X1126611Y286141D02*
X1128304D01*
G01X1125296Y284826D02*
X1126611Y286141D01*
G01X1116152Y284826D02*
X1125296D01*
G01X1147680Y281337D02*
Y280547D01*
G01X1144951Y284066D02*
X1147680Y281337D01*
G01X1144334Y284066D02*
X1144951D01*
G01X1142300Y286100D02*
X1144334Y284066D01*
G01X1140057Y286100D02*
X1142300D01*
G01X1138191Y287966D02*
X1140057Y286100D01*
G01X1136762Y287966D02*
X1138191D01*
G01X1134051Y290677D02*
X1136762Y287966D01*
G01X1133509Y290677D02*
X1134051D01*
G01X1131560Y292626D02*
X1133509Y290677D01*
G01X1130129Y292626D02*
X1131560D01*
G01X1128178Y294577D02*
X1130129Y292626D01*
G01X1125623Y294577D02*
X1128178D01*
G01X1122100Y298100D02*
X1125623Y294577D01*
G01X1122100Y317238D02*
Y298100D01*
G01X1120172Y319166D02*
X1122100Y317238D01*
G01X1115748Y319166D02*
X1120172D01*
G01X1114839Y320075D02*
X1115748Y319166D01*
G01X1136900Y553588D02*
X1130612Y559876D01*
G01X1136900Y552823D02*
Y553588D01*
G01X1143423Y546300D02*
X1136900Y552823D01*
G01X1274700Y546300D02*
X1143423D01*
G01X1103132Y622644D02*
X1299356D01*
G01X1101040Y620552D02*
X1103132Y622644D01*
G01X1103610Y621492D02*
X1101518Y619400D01*
G01X1298011Y621492D02*
X1103610D01*
G01X1104370Y618940D02*
X1102435Y617005D01*
G01X1296010Y618940D02*
X1104370D01*
G01X1103975Y619892D02*
X1296405D01*
G01X1102040Y617957D02*
X1103975Y619892D01*
G01X1102254Y623396D02*
X1301104D01*
G01X1100358Y621500D02*
X1102254Y623396D01*
G01X1103942Y616882D02*
X1102913Y615853D01*
G01X1291599Y616882D02*
X1103942D01*
G01X1236944Y166100D02*
X1195587Y124743D01*
G01X1193018Y128115D02*
X1242413Y177510D01*
G01X1233902Y170770D02*
X1192499Y129367D01*
G01X1201524Y118744D02*
X1235025Y152245D01*
G01X1234334Y158600D02*
X1198221Y122487D01*
G01X1234618Y127640D02*
X1206953Y99975D01*
G01X1231505Y128323D02*
X1205920Y102738D01*
G01X1197343Y123239D02*
X1236004Y161900D01*
G01X1200768Y119618D02*
X1234435Y153285D01*
G01X1207910Y95366D02*
X1207909Y95367D01*
G01X1211523Y95366D02*
X1207910D01*
G01X1243999Y127842D02*
X1211523Y95366D01*
G01X1241695Y128798D02*
X1210568Y97671D01*
G01X1202402Y117992D02*
X1234994Y150584D01*
G01X1238120Y169970D02*
X1194568Y126418D01*
G01X1238549Y172040D02*
X1193872Y127363D01*
G01X1235950Y163476D02*
X1196465Y123991D01*
G01X1237480Y167700D02*
X1195275Y125495D01*
G01X1233079Y128267D02*
X1206398Y101586D01*
G01X1235020Y156592D02*
X1199083Y120655D01*
G01X1236359Y127751D02*
X1207431Y98823D01*
G01X1235028Y157664D02*
X1198968Y121604D01*
G01X1242847Y128320D02*
X1211046Y96519D01*
G01X1217298Y206773D02*
X1244797Y179274D01*
G01X1217298Y215520D02*
Y206773D01*
G01X1218308Y216530D02*
X1217298Y215520D01*
G01X1220524Y216530D02*
X1218308D01*
G01X1214008Y218100D02*
X1218000D01*
G01X1211592Y220516D02*
X1214008Y218100D01*
G01X1210259Y220516D02*
X1211592D01*
G01X1207741Y223034D02*
X1210259Y220516D01*
G01X1200900Y231900D02*
X1201858D01*
G01X1199300Y233500D02*
X1200900Y231900D01*
G01X1197500Y233500D02*
X1199300D01*
G01X1195500Y235500D02*
X1197500Y233500D01*
G01X1194600Y235500D02*
X1195500D01*
G01X1192400Y237700D02*
X1194600Y235500D01*
G01X1190900Y237700D02*
X1192400D01*
G01X1189200Y239400D02*
X1190900Y237700D01*
G01X1187100Y239400D02*
X1189200D01*
G01X1185300Y237600D02*
X1187100Y239400D01*
G01X1184100Y237600D02*
X1185300D01*
G01X1182150Y239550D02*
X1184100Y237600D01*
G01X1180550Y239550D02*
X1182150D01*
G01X1178800Y237800D02*
X1180550Y239550D01*
G01X1177400Y237800D02*
X1178800D01*
G01X1175800Y239400D02*
X1177400Y237800D01*
G01X1174100Y239400D02*
X1175800D01*
G01X1172200Y241300D02*
X1174100Y239400D01*
G01X1170900Y241300D02*
X1172200D01*
G01X1168800Y243400D02*
X1170900Y241300D01*
G01X1167200Y243400D02*
X1168800D01*
G01X1166300Y244300D02*
X1167200Y243400D01*
G01X1166300Y264296D02*
Y244300D01*
G01X1163700Y266896D02*
X1166300Y264296D01*
G01X1157820Y266896D02*
X1163700D01*
G01X1174719Y248555D02*
Y249347D01*
G01X1177448Y245826D02*
X1174719Y248555D01*
G01X1179539Y245826D02*
X1177448D01*
G01X1180730Y247017D02*
X1179539Y245826D01*
G01X1182639Y247017D02*
X1180730D01*
G01X1183830Y245826D02*
X1182639Y247017D01*
G01X1186365Y245826D02*
X1183830D01*
G01X1187556Y247017D02*
X1186365Y245826D01*
G01X1190920Y247017D02*
X1187556D01*
G01X1194237Y243700D02*
X1190920Y247017D01*
G01X1195357Y243700D02*
X1194237D01*
G01X1197147Y241910D02*
X1195357Y243700D01*
G01X1198452Y241910D02*
X1197147D01*
G01X1200504Y239858D02*
X1198452Y241910D01*
G01X1202183Y239858D02*
X1200504D01*
G01X1203358Y238683D02*
X1202183Y239858D01*
G01X1209809Y222030D02*
X1209439Y222400D01*
G01X1220531Y222030D02*
X1209809D01*
G01X1158200Y268700D02*
X1157300D01*
G01X1160300Y270800D02*
X1158200Y268700D01*
G01X1161800Y270800D02*
X1160300D01*
G01X1165600Y267000D02*
X1161800Y270800D01*
G01X1168400Y267000D02*
X1165600D01*
G01X1169600Y265800D02*
X1168400Y267000D01*
G01X1169600Y246700D02*
Y265800D01*
G01X1171000Y245300D02*
X1169600Y246700D01*
G01X1172100Y245300D02*
X1171000D01*
G01X1173900Y243500D02*
X1172100Y245300D01*
G01X1175200Y243500D02*
X1173900D01*
G01X1177100Y241600D02*
X1175200Y243500D01*
G01X1178700Y241600D02*
X1177100D01*
G01X1180400Y243300D02*
X1178700Y241600D01*
G01X1182000Y243300D02*
X1180400D01*
G01X1183800Y241500D02*
X1182000Y243300D01*
G01X1185400Y241500D02*
X1183800D01*
G01X1187200Y243300D02*
X1185400Y241500D01*
G01X1188900Y243300D02*
X1187200D01*
G01X1190800Y241400D02*
X1188900Y243300D01*
G01X1192400Y241400D02*
X1190800D01*
G01X1194200Y239600D02*
X1192400Y241400D01*
G01X1195900Y239600D02*
X1194200D01*
G01X1197800Y237700D02*
X1195900Y239600D01*
G01X1198835Y237700D02*
X1197800D01*
G01X1207510Y482900D02*
X1221916Y497306D01*
G01X1206111Y484864D02*
X1220457Y499210D01*
G01X1222794Y496554D02*
X1208334Y482094D01*
G01X1204915Y486950D02*
X1219350Y501385D01*
G01X1208892Y480660D02*
X1223232Y495000D01*
G01X1220250Y500633D02*
X1205720Y486103D01*
G01X1220958Y498058D02*
X1206576Y483676D01*
G01X1275548Y16793D02*
X1283073Y24318D01*
G01X1275548Y8910D02*
Y16793D01*
G01X1271819Y5181D02*
X1275548Y8910D01*
G01X1269961Y-9675D02*
X1283643Y4007D01*
G01X1269961Y-11696D02*
Y-9675D01*
G01X1265673Y-15984D02*
X1269961Y-11696D01*
G01X1274208Y-17500D02*
X1270062Y-21646D01*
G01X1286900Y-17500D02*
X1274208D01*
G01X1273088Y-3281D02*
X1281880Y5511D01*
G01X1270003Y-3281D02*
X1273088D01*
G01X1268117Y-5167D02*
X1270003Y-3281D01*
G01X1268117Y-11173D02*
Y-5167D01*
G01X1265032Y-14258D02*
X1268117Y-11173D01*
G01X1265031Y-14257D02*
X1265032Y-14258D01*
G01X1269209Y-11384D02*
X1265361Y-15232D01*
G01X1269209Y-9363D02*
Y-11384D01*
G01X1283331Y4759D02*
X1269209Y-9363D01*
G01X1274796Y17105D02*
X1282761Y25070D01*
G01X1274796Y9222D02*
Y17105D01*
G01X1271507Y5933D02*
X1274796Y9222D01*
G01X1273818Y-12192D02*
X1266556Y-19454D01*
G01X1273818Y-9988D02*
Y-12192D01*
G01X1275444Y-8362D02*
X1273818Y-9988D01*
G01X1278500Y-8362D02*
X1275444D01*
G01X1282880Y-12742D02*
X1278500Y-8362D01*
G01X1271369Y-12280D02*
X1266257Y-17392D01*
G01X1271369Y-10259D02*
Y-12280D01*
G01X1284103Y2475D02*
X1271369Y-10259D01*
G01X1276346Y-12304D02*
Y-10250D01*
G01X1267756Y-20894D02*
X1276346Y-12304D01*
G01X1279846Y6716D02*
X1274103Y973D01*
G01X1279846Y15062D02*
Y6716D01*
G01X1284894Y20110D02*
X1279846Y15062D01*
G01X1278646Y15492D02*
X1284416Y21262D01*
G01X1278646Y7684D02*
Y15492D01*
G01X1273087Y2125D02*
X1278646Y7684D01*
G01X1267153Y-11072D02*
X1265051Y-13174D01*
G01X1267153Y-4617D02*
Y-11072D01*
G01X1269365Y-2405D02*
X1267153Y-4617D01*
G01X1272504Y-2405D02*
X1269365D01*
G01X1281172Y6263D02*
X1272504Y-2405D01*
G01X1277452Y16003D02*
X1283863Y22414D01*
G01X1277452Y8120D02*
Y16003D01*
G01X1272609Y3277D02*
X1277452Y8120D01*
G01X1276500Y16398D02*
X1283468Y23366D01*
G01X1276500Y8515D02*
Y16398D01*
G01X1272214Y4229D02*
X1276500Y8515D01*
G01X1271376Y68059D02*
Y94504D01*
G01X1264586Y61269D02*
X1271376Y68059D01*
G01X1272721Y65272D02*
X1267566Y60117D01*
G01X1272721Y95929D02*
Y65272D01*
G01X1274230Y47141D02*
X1269678Y42589D01*
G01X1274230Y57878D02*
Y47141D01*
G01X1276781Y60429D02*
X1274230Y57878D01*
G01X1276781Y91663D02*
Y60429D01*
G01X1290159Y105041D02*
X1276781Y91663D01*
G01X1272853Y47630D02*
X1269064Y43841D01*
G01X1272853Y50776D02*
Y47630D01*
G01X1272852Y50777D02*
X1272853Y50776D01*
G01X1272852Y58883D02*
Y50777D01*
G01X1275363Y61394D02*
X1272852Y58883D01*
G01X1275363Y92103D02*
Y61394D01*
G01X1288907Y105647D02*
X1275363Y92103D01*
G01X1263389Y65048D02*
Y109813D01*
G01X1261914Y63573D02*
X1263389Y65048D01*
G01X1266115Y56464D02*
X1265133Y57446D01*
G01X1268321Y56464D02*
X1266115D01*
G01X1269804Y54981D02*
X1268321Y56464D01*
G01X1269804Y53382D02*
Y54981D01*
G01X1267959Y51537D02*
X1269804Y53382D01*
G01X1267959Y47245D02*
Y51537D01*
G01X1276797Y45944D02*
X1271355Y40502D01*
G01X1276797Y53380D02*
Y45944D01*
G01X1286036Y62619D02*
X1276797Y53380D01*
G01X1275483Y46559D02*
X1270261Y41337D01*
G01X1275483Y49747D02*
Y46559D01*
G01X1275482Y49748D02*
X1275483Y49747D01*
G01X1275482Y57359D02*
Y49748D01*
G01X1278033Y59910D02*
X1275482Y57359D01*
G01X1278033Y91144D02*
Y59910D01*
G01X1291700Y104811D02*
X1278033Y91144D01*
G01X1267422Y58040D02*
X1266497Y58965D01*
G01X1268111Y58040D02*
X1267422D01*
G01X1271600Y48150D02*
X1268638Y45188D01*
G01X1271600Y59402D02*
Y48150D01*
G01X1274057Y61859D02*
X1271600Y59402D01*
G01X1274057Y93161D02*
Y61859D01*
G01X1284300Y103404D02*
X1274057Y93161D01*
G01X1270184Y68497D02*
X1264108Y62421D01*
G01X1270184Y86612D02*
Y68497D01*
G01X1266733Y90063D02*
X1270184Y86612D01*
G01X1266733Y97348D02*
Y90063D01*
G01X1279301Y52330D02*
X1287086Y60115D01*
G01X1279301Y44842D02*
Y52330D01*
G01X1272456Y37997D02*
X1279301Y44842D01*
G01X1266924Y110088D02*
X1282842Y126006D01*
G01X1266924Y98956D02*
Y110088D01*
G01X1271376Y94504D02*
X1266924Y98956D01*
G01X1270350Y98300D02*
X1272721Y95929D01*
G01X1264941Y152245D02*
X1266646Y150540D01*
G01X1235025Y152245D02*
X1264941D01*
G01X1278793Y145780D02*
X1278000D01*
G01X1280227Y147214D02*
X1278793Y145780D01*
G01X1277605Y155811D02*
X1280227Y153189D01*
G01X1277605Y171533D02*
Y155811D01*
G01X1276302Y153744D02*
Y170612D01*
G01X1268236Y145678D02*
X1276302Y153744D01*
G01X1268236Y141938D02*
Y145678D01*
G01X1234618Y130147D02*
Y127640D01*
G01X1251347Y146876D02*
X1234618Y130147D01*
G01X1257724Y146876D02*
X1251347D01*
G01X1259950Y144650D02*
X1257724Y146876D01*
G01X1231505Y130294D02*
Y128323D01*
G01X1250219Y149008D02*
X1231505Y130294D01*
G01X1262570Y149008D02*
X1250219D01*
G01X1264146Y150584D02*
X1262570Y149008D01*
G01X1263185Y153285D02*
X1264700Y154800D01*
G01X1234435Y153285D02*
X1263185D01*
G01X1243999Y131530D02*
Y127842D01*
G01X1248314Y135845D02*
X1243999Y131530D01*
G01X1272286Y135845D02*
X1248314D01*
G01X1281379Y144938D02*
X1272286Y135845D01*
G01X1241695Y132487D02*
Y128798D01*
G01X1247686Y138478D02*
X1241695Y132487D01*
G01X1257099Y138478D02*
X1247686D01*
G01X1272976Y154355D02*
X1257099Y138478D01*
G01X1272976Y166103D02*
Y154355D01*
G01X1278987Y140811D02*
X1282531Y144355D01*
G01X1278987Y133418D02*
Y140811D01*
G01X1273453Y127884D02*
X1278987Y133418D01*
G01X1273453Y119877D02*
Y127884D01*
G01X1263389Y109813D02*
X1273453Y119877D01*
G01X1234994Y150584D02*
X1261546D01*
G01X1233079Y130238D02*
Y128267D01*
G01X1250697Y147856D02*
X1233079Y130238D01*
G01X1258444Y147856D02*
X1250697D01*
G01X1259099Y147201D02*
X1258444Y147856D01*
G01X1262569Y147201D02*
X1259099D01*
G01X1261800Y154973D02*
X1260181Y156592D01*
G01X1236359Y129659D02*
Y127751D01*
G01X1252000Y145300D02*
X1236359Y129659D01*
G01X1265772Y98309D02*
X1266733Y97348D01*
G01X1265772Y110566D02*
Y98309D01*
G01X1274605Y119399D02*
X1265772Y110566D01*
G01X1274605Y127406D02*
Y119399D01*
G01X1280139Y132940D02*
X1274605Y127406D01*
G01X1280139Y140228D02*
Y132940D01*
G01X1283683Y143772D02*
X1280139Y140228D01*
G01X1268302Y154398D02*
X1265036Y157664D01*
G01X1269810Y154398D02*
X1268302D01*
G01X1242847Y132009D02*
Y128320D01*
G01X1248164Y137326D02*
X1242847Y132009D01*
G01X1257577Y137326D02*
X1248164D01*
G01X1274128Y153877D02*
X1257577Y137326D01*
G01X1274128Y166581D02*
Y153877D01*
G01X1256950Y166100D02*
X1236944D01*
G01X1259200Y168350D02*
X1256950Y166100D01*
G01X1272305Y215465D02*
Y239943D01*
G01X1279058Y208712D02*
X1272305Y215465D01*
G01X1279058Y199101D02*
Y208712D01*
G01X1273505Y193548D02*
X1279058Y199101D01*
G01X1273505Y187231D02*
Y193548D01*
G01X1283062Y177674D02*
X1273505Y187231D01*
G01X1245540Y177510D02*
X1246655Y176395D01*
G01X1242413Y177510D02*
X1245540D01*
G01X1277454Y188606D02*
X1285664Y180396D01*
G01X1277454Y191433D02*
Y188606D01*
G01X1282514Y196493D02*
X1277454Y191433D01*
G01X1276859Y217442D02*
X1282974Y211327D01*
G01X1276859Y226247D02*
Y217442D01*
G01X1233902Y173337D02*
Y170770D01*
G01X1264600Y158600D02*
X1234334D01*
G01X1267800Y161800D02*
X1264600Y158600D01*
G01X1263786Y185352D02*
X1277605Y171533D01*
G01X1253412Y185352D02*
X1263786D01*
G01X1234952Y203812D02*
X1253412Y185352D01*
G01X1234952Y221592D02*
Y203812D01*
G01X1233294Y203482D02*
Y221892D01*
G01X1252757Y184019D02*
X1233294Y203482D01*
G01X1262895Y184019D02*
X1252757D01*
G01X1276302Y170612D02*
X1262895Y184019D01*
G01X1276128Y188072D02*
X1285133Y179067D01*
G01X1276128Y191904D02*
Y188072D01*
G01X1281722Y197498D02*
X1276128Y191904D01*
G01X1275607Y216923D02*
X1281722Y210808D01*
G01X1275607Y233249D02*
Y216923D01*
G01X1236004Y161900D02*
X1240309D01*
G01X1279606Y166675D02*
X1281379Y164902D01*
G01X1279606Y176240D02*
Y166675D01*
G01X1269799Y186047D02*
X1279606Y176240D01*
G01X1269799Y194732D02*
Y186047D01*
G01X1275602Y200535D02*
X1269799Y194732D01*
G01X1275602Y207278D02*
Y200535D01*
G01X1268362Y214518D02*
X1275602Y207278D01*
G01X1268362Y243784D02*
Y214518D01*
G01X1259805Y179274D02*
X1272976Y166103D01*
G01X1244797Y179274D02*
X1259805D01*
G01X1220702Y216708D02*
X1220524Y216530D01*
G01X1221587Y217593D02*
Y220974D01*
G01X1220702Y216708D02*
X1221587Y217593D01*
G01X1269577Y214933D02*
Y242589D01*
G01X1276754Y207756D02*
X1269577Y214933D01*
G01X1276754Y200057D02*
Y207756D01*
G01X1270951Y194254D02*
X1276754Y200057D01*
G01X1270951Y186525D02*
Y194254D01*
G01X1280758Y176718D02*
X1270951Y186525D01*
G01X1248270Y169970D02*
X1238120D01*
G01X1251052Y172752D02*
X1248270Y169970D01*
G01X1259998Y172752D02*
X1251052D01*
G01X1263300Y169450D02*
X1259998Y172752D01*
G01X1241381Y172040D02*
X1238549D01*
G01X1269824Y163476D02*
X1235950D01*
G01X1271400Y161900D02*
X1269824Y163476D01*
G01X1251452Y167700D02*
X1237480D01*
G01X1253678Y169926D02*
X1251452Y167700D01*
G01X1260574Y169926D02*
X1253678D01*
G01X1262626Y167874D02*
X1260574Y169926D01*
G01X1265124Y167874D02*
X1262626D01*
G01X1267050Y169800D02*
X1265124Y167874D01*
G01X1260181Y156592D02*
X1235020D01*
G01X1274862Y187538D02*
X1284708Y177692D01*
G01X1274862Y192654D02*
Y187538D01*
G01X1280370Y198162D02*
X1274862Y192654D01*
G01X1274002Y216498D02*
X1280370Y210130D01*
G01X1274002Y235144D02*
Y216498D01*
G01X1272172Y186934D02*
X1281910Y177196D01*
G01X1272172Y193845D02*
Y186934D01*
G01X1277906Y199579D02*
X1272172Y193845D01*
G01X1277906Y208234D02*
Y199579D01*
G01X1270729Y215411D02*
X1277906Y208234D01*
G01X1270729Y240650D02*
Y215411D01*
G01X1265036Y157664D02*
X1235028D01*
G01X1260283Y180426D02*
X1274128Y166581D01*
G01X1250947Y180426D02*
X1260283D01*
G01X1243288Y188085D02*
X1250947Y180426D01*
G01X1243288Y188363D02*
Y188085D01*
G01X1242365Y189286D02*
X1243288Y188363D01*
G01X1242087Y189286D02*
X1242365D01*
G01X1224227Y207146D02*
X1242087Y189286D01*
G01X1224227Y209510D02*
Y207146D01*
G01X1218868Y214869D02*
X1224227Y209510D01*
G01X1272686Y240295D02*
X1272761Y240220D01*
G01X1272657Y240295D02*
X1272686D01*
G01X1272305Y239943D02*
X1272657Y240295D01*
G01X1279950Y229338D02*
X1276859Y226247D01*
G01X1259664Y246304D02*
X1234952Y221592D01*
G01X1268404Y246304D02*
X1259664D01*
G01X1266702Y255300D02*
X1274100D01*
G01X1233294Y221892D02*
X1266702Y255300D01*
G01X1276628Y234270D02*
X1275607Y233249D01*
G01X1275577Y250999D02*
X1268362Y243784D01*
G01X1275577Y253123D02*
Y250999D01*
G01X1221587Y220974D02*
X1220531Y222030D01*
G01X1269577Y242589D02*
X1270478Y243490D01*
G01X1275154Y236296D02*
X1274002Y235144D01*
G01X1277509Y247430D02*
X1270729Y240650D01*
G01X1277509Y250341D02*
Y247430D01*
G01X1277504Y250346D02*
X1277509Y250341D01*
G01X1272500Y533731D02*
X1282678Y523553D01*
G01X1278422Y493820D02*
X1284684Y487558D01*
G01X1275056Y493820D02*
X1278422D01*
G01X1274872Y494004D02*
X1275056Y493820D01*
G01X1268000Y494004D02*
X1274872D01*
G01X1266162Y495842D02*
X1268000Y494004D01*
G01X1266162Y496404D02*
Y495842D01*
G01X1279633Y485102D02*
X1292361D01*
G01X1273354Y491381D02*
X1279633Y485102D01*
G01X1265534Y491381D02*
X1273354D01*
G01X1259609Y497306D02*
X1265534Y491381D01*
G01X1221916Y497306D02*
X1259609D01*
G01X1262057Y497553D02*
X1262843D01*
G01X1260400Y499210D02*
X1262057Y497553D01*
G01X1220457Y499210D02*
X1260400D01*
G01X1258945Y496554D02*
X1222794D01*
G01X1264885Y490614D02*
X1258945Y496554D01*
G01X1273057Y490614D02*
X1264885D01*
G01X1279321Y484350D02*
X1273057Y490614D01*
G01X1292049Y484350D02*
X1279321D01*
G01X1278777Y498085D02*
X1277800Y497108D01*
G01X1281554Y498085D02*
X1278777D01*
G01X1270055Y494967D02*
X1269006Y496016D01*
G01X1275293Y494967D02*
X1270055D01*
G01X1275421Y494839D02*
X1275293Y494967D01*
G01X1278762Y494839D02*
X1275421D01*
G01X1285091Y488510D02*
X1278762Y494839D01*
G01X1271376Y533508D02*
X1282283Y522601D01*
G01X1276121Y499237D02*
X1282032D01*
G01X1273488Y496604D02*
X1276121Y499237D01*
G01X1270716Y496604D02*
X1273488D01*
G01X1269710Y497610D02*
X1270716Y496604D01*
G01X1267240Y497610D02*
X1269710D01*
G01X1263465Y501385D02*
X1267240Y497610D01*
G01X1219350Y501385D02*
X1263465D01*
G01X1274627Y527473D02*
X1280800Y521300D01*
G01X1272517Y489162D02*
X1285451Y476228D01*
G01X1264345Y489162D02*
X1272517D01*
G01X1258507Y495000D02*
X1264345Y489162D01*
G01X1223232Y495000D02*
X1258507D01*
G01X1262148Y500633D02*
X1220250D01*
G01X1264466Y498315D02*
X1262148Y500633D01*
G01X1264466Y495055D02*
Y498315D01*
G01X1266569Y492952D02*
X1264466Y495055D01*
G01X1274119Y492952D02*
X1266569D01*
G01X1280465Y486606D02*
X1274119Y492952D01*
G01X1259921Y498058D02*
X1220958D01*
G01X1265846Y492133D02*
X1259921Y498058D01*
G01X1273666Y492133D02*
X1265846D01*
G01X1279945Y485854D02*
X1273666Y492133D01*
G01X1292673Y485854D02*
X1279945D01*
G01X1272500Y536260D02*
Y533731D01*
G01X1266864Y541896D02*
X1272500Y536260D01*
G01X1274217Y585042D02*
X1281714Y577545D01*
G01X1271868Y585042D02*
X1274217D01*
G01X1266300Y579474D02*
X1271868Y585042D01*
G01X1279568Y540248D02*
X1274664Y545152D01*
G01X1282784Y540248D02*
X1279568D01*
G01X1267907Y576907D02*
X1273200Y582200D01*
G01X1280000Y541000D02*
X1274700Y546300D01*
G01X1282472Y541000D02*
X1280000D01*
G01X1273748Y534113D02*
X1283156Y524705D01*
G01X1273748Y537252D02*
Y534113D01*
G01X1267952Y543048D02*
X1273748Y537252D01*
G01X1274700Y534508D02*
X1283551Y525657D01*
G01X1274700Y537700D02*
Y534508D01*
G01X1268400Y544000D02*
X1274700Y537700D01*
G01X1270435Y588600D02*
X1264765Y582930D01*
G01X1281700Y583600D02*
X1276700Y588600D01*
G01X1280000Y566500D02*
X1282371Y564129D01*
G01X1280000Y577629D02*
Y566500D01*
G01X1273853Y583776D02*
X1280000Y577629D01*
G01X1272232Y583776D02*
X1273853D01*
G01X1266778Y578322D02*
X1272232Y583776D01*
G01X1271376Y536037D02*
Y533508D01*
G01X1266469Y540944D02*
X1271376Y536037D01*
G01X1265054Y540944D02*
X1266469D01*
G01X1264917Y541081D02*
X1265054Y540944D01*
G01X1274391Y586260D02*
X1281689Y578962D01*
G01X1271456Y586260D02*
X1274391D01*
G01X1265822Y580626D02*
X1271456Y586260D01*
G01X1271877Y527473D02*
X1274627D01*
G01X1268150Y531200D02*
X1271877Y527473D01*
G01X1268150Y536501D02*
Y531200D01*
G01X1264522Y540129D02*
X1268150Y536501D01*
G01X1271044Y587478D02*
X1265344Y581778D01*
G01X1276122Y587478D02*
X1271044D01*
G01X1282600Y581000D02*
X1276122Y587478D01*
G01X1277276Y539024D02*
X1277200Y539100D01*
G01X1282753Y539024D02*
X1277276D01*
G01X1276700Y588600D02*
X1270435D01*
G01X1290353Y24318D02*
X1303068Y37033D01*
G01X1283073Y24318D02*
X1290353D01*
G01X1331007Y31346D02*
X1351139Y51478D01*
G01X1325964Y31346D02*
X1331007D01*
G01X1319686Y25068D02*
X1325964Y31346D01*
G01X1303990Y25068D02*
X1319686D01*
G01X1296455Y17533D02*
X1303990Y25068D01*
G01X1296455Y9357D02*
Y17533D01*
G01X1291104Y4006D02*
X1296455Y9357D01*
G01X1290482Y4006D02*
X1291104D01*
G01X1290481Y4007D02*
X1290482Y4006D01*
G01X1283643Y4007D02*
X1290481D01*
G01X1287700Y-16700D02*
X1286900Y-17500D01*
G01X1319062Y26572D02*
X1325340Y32850D01*
G01X1301603Y26572D02*
X1319062D01*
G01X1294951Y19920D02*
X1301603Y26572D01*
G01X1294951Y9981D02*
Y19920D01*
G01X1290481Y5511D02*
X1294951Y9981D01*
G01X1281880Y5511D02*
X1290481D01*
G01X1290793Y4759D02*
X1283331D01*
G01X1295703Y9669D02*
X1290793Y4759D01*
G01X1295703Y18504D02*
Y9669D01*
G01X1303019Y25820D02*
X1295703Y18504D01*
G01X1319374Y25820D02*
X1303019D01*
G01X1325652Y32098D02*
X1319374Y25820D01*
G01X1330695Y32098D02*
X1325652D01*
G01X1350827Y52230D02*
X1330695Y32098D01*
G01X1290041Y25070D02*
X1302756Y37785D01*
G01X1282761Y25070D02*
X1290041D01*
G01X1283605Y-16100D02*
X1282252Y-14747D01*
G01X1285800Y-16100D02*
X1283605D01*
G01X1286776Y-15124D02*
X1285800Y-16100D01*
G01X1288646Y-15124D02*
X1286776D01*
G01X1289382Y-15860D02*
X1288646Y-15124D01*
G01X1289382Y-19526D02*
Y-15860D01*
G01X1291499Y-21643D02*
X1289382Y-19526D01*
G01X1388572Y-21643D02*
X1291499D01*
G01X1290895Y-12742D02*
X1282880D01*
G01X1292280Y-11357D02*
X1290895Y-12742D01*
G01X1298711Y-11357D02*
X1292280D01*
G01X1303774Y-16420D02*
X1298711Y-11357D01*
G01X1303774Y-18842D02*
Y-16420D01*
G01X1291565Y2475D02*
X1284103D01*
G01X1297863Y8773D02*
X1291565Y2475D01*
G01X1297863Y16949D02*
Y8773D01*
G01X1304574Y23660D02*
X1297863Y16949D01*
G01X1320270Y23660D02*
X1304574D01*
G01X1326548Y29938D02*
X1320270Y23660D01*
G01X1331591Y29938D02*
X1326548D01*
G01X1351723Y50070D02*
X1331591Y29938D01*
G01X1292099Y20110D02*
X1284894D01*
G01X1301661Y29672D02*
X1292099Y20110D01*
G01X1304615Y29672D02*
X1301661D01*
G01X1309834Y34891D02*
X1304615Y29672D01*
G01X1291621Y21262D02*
X1304335Y33976D01*
G01X1284416Y21262D02*
X1291621D01*
G01X1290169Y6263D02*
X1281172D01*
G01X1294199Y10293D02*
X1290169Y6263D01*
G01X1294199Y20232D02*
Y10293D01*
G01X1302487Y28520D02*
X1294199Y20232D01*
G01X1305093Y28520D02*
X1302487D01*
G01X1310312Y33739D02*
X1305093Y28520D01*
G01X1291143Y22414D02*
X1303857Y35128D01*
G01X1283863Y22414D02*
X1291143D01*
G01X1291977Y-20491D02*
X1354409D01*
G01X1290534Y-19048D02*
X1291977Y-20491D01*
G01X1290534Y-15382D02*
Y-19048D01*
G01X1289124Y-13972D02*
X1290534Y-15382D01*
G01X1285411Y-13972D02*
X1289124D01*
G01X1284859Y-14524D02*
X1285411Y-13972D01*
G01X1290748Y23366D02*
X1303463Y36081D01*
G01X1283468Y23366D02*
X1290748D01*
G01X1320000Y95676D02*
Y85500D01*
G01X1341241Y93424D02*
X1371368D01*
G01X1340834Y93017D02*
X1341241Y93424D01*
G01X1336045Y93017D02*
X1340834D01*
G01X1334079Y91051D02*
X1336045Y93017D01*
G01X1334079Y82645D02*
Y91051D01*
G01X1331682Y80248D02*
X1334079Y82645D01*
G01X1331682Y43797D02*
Y80248D01*
G01X1326984Y39099D02*
X1331682Y43797D01*
G01X1307892Y39099D02*
X1326984D01*
G01X1305825Y37032D02*
X1307892Y39099D01*
G01X1305603Y37032D02*
X1305825D01*
G01X1305602Y37033D02*
X1305603Y37032D01*
G01X1303068Y37033D02*
X1305602D01*
G01X1297708Y37700D02*
X1296908Y36900D01*
G01X1300500Y37700D02*
X1297708D01*
G01X1302866Y40066D02*
X1300500Y37700D01*
G01X1304500Y40066D02*
X1302866D01*
G01X1330383Y32850D02*
X1346554Y49021D01*
G01X1325340Y32850D02*
X1330383D01*
G01X1333327Y82957D02*
Y94886D01*
G01X1330930Y80560D02*
X1333327Y82957D01*
G01X1330930Y44109D02*
Y80560D01*
G01X1326672Y39851D02*
X1330930Y44109D01*
G01X1307580Y39851D02*
X1326672D01*
G01X1307579Y39850D02*
X1307580Y39851D01*
G01X1307421Y39850D02*
X1307579D01*
G01X1305356Y37785D02*
X1307421Y39850D01*
G01X1302756Y37785D02*
X1305356D01*
G01X1289813Y62619D02*
X1286036D01*
G01X1294170Y66976D02*
X1289813Y62619D01*
G01X1294170Y89954D02*
Y66976D01*
G01X1297157Y92941D02*
X1294170Y89954D01*
G01X1297157Y98900D02*
Y92941D01*
G01X1328730Y34891D02*
X1309834D01*
G01X1336623Y42784D02*
X1328730Y34891D01*
G01X1336623Y54600D02*
Y42784D01*
G01X1339500Y57477D02*
X1336623Y54600D01*
G01X1339500Y73988D02*
Y57477D01*
G01X1341583Y76071D02*
X1339500Y73988D01*
G01X1341583Y87812D02*
Y76071D01*
G01X1342855Y89084D02*
X1341583Y87812D01*
G01X1340431Y88290D02*
X1342509Y90368D01*
G01X1340431Y77532D02*
Y88290D01*
G01X1334738Y71839D02*
X1340431Y77532D01*
G01X1334738Y42529D02*
Y71839D01*
G01X1328252Y36043D02*
X1334738Y42529D01*
G01X1309304Y36043D02*
X1328252D01*
G01X1307237Y33976D02*
X1309304Y36043D01*
G01X1304335Y33976D02*
X1307237D01*
G01X1329208Y33739D02*
X1310312D01*
G01X1337775Y42306D02*
X1329208Y33739D01*
G01X1337775Y45649D02*
Y42306D01*
G01X1345352Y53226D02*
X1337775Y45649D01*
G01X1339279Y88768D02*
X1342031Y91520D01*
G01X1339279Y81478D02*
Y88768D01*
G01X1333586Y75785D02*
X1339279Y81478D01*
G01X1333586Y43007D02*
Y75785D01*
G01X1327774Y37195D02*
X1333586Y43007D01*
G01X1308682Y37195D02*
X1327774D01*
G01X1306615Y35128D02*
X1308682Y37195D01*
G01X1303857Y35128D02*
X1306615D01*
G01X1341636Y92472D02*
X1371837D01*
G01X1340885Y91721D02*
X1341636Y92472D01*
G01X1336096Y91721D02*
X1340885D01*
G01X1335055Y90680D02*
X1336096Y91721D01*
G01X1335055Y82200D02*
Y90680D01*
G01X1332634Y79779D02*
X1335055Y82200D01*
G01X1332634Y43402D02*
Y79779D01*
G01X1327379Y38147D02*
X1332634Y43402D01*
G01X1308287Y38147D02*
X1327379D01*
G01X1306220Y36080D02*
X1308287Y38147D01*
G01X1305208Y36080D02*
X1306220D01*
G01X1305207Y36081D02*
X1305208Y36080D01*
G01X1303463Y36081D02*
X1305207D01*
G01X1296846Y89088D02*
X1302270Y94512D01*
G01X1296846Y66110D02*
Y89088D01*
G01X1290851Y60115D02*
X1296846Y66110D01*
G01X1287086Y60115D02*
X1290851D01*
G01X1318000Y97676D02*
X1320000Y95676D01*
G01X1318000Y129050D02*
Y97676D01*
G01X1319350Y130400D02*
X1318000Y129050D01*
G01X1327500Y130400D02*
X1319350D01*
G01X1329794Y132694D02*
X1327500Y130400D01*
G01X1397006Y132694D02*
X1329794D01*
G01X1284835Y142575D02*
Y167159D01*
G01X1282842Y140582D02*
X1284835Y142575D01*
G01X1282842Y126006D02*
Y140582D01*
G01X1290159Y127300D02*
Y105041D01*
G01X1291848Y128989D02*
X1290159Y127300D01*
G01X1291848Y143200D02*
Y128989D01*
G01X1290159Y144889D02*
X1291848Y143200D01*
G01X1290159Y154395D02*
Y144889D01*
G01X1293224Y157460D02*
X1290159Y154395D01*
G01X1280227Y153189D02*
Y147214D01*
G01X1336641Y98200D02*
X1350927D01*
G01X1333327Y94886D02*
X1336641Y98200D01*
G01X1288907Y128900D02*
Y105647D01*
G01X1290596Y130589D02*
X1288907Y128900D01*
G01X1290596Y142681D02*
Y130589D01*
G01X1288907Y144370D02*
X1290596Y142681D01*
G01X1288907Y154914D02*
Y144370D01*
G01X1290896Y156903D02*
X1288907Y154914D01*
G01X1281379Y164902D02*
Y144938D01*
G01X1282531Y144355D02*
Y165380D01*
G01X1294300Y101757D02*
X1297157Y98900D01*
G01X1294300Y107800D02*
Y101757D01*
G01X1297157Y110657D02*
X1294300Y107800D01*
G01X1297157Y126958D02*
Y110657D01*
G01X1301492Y131293D02*
X1297157Y126958D01*
G01X1301492Y152254D02*
Y131293D01*
G01X1302816Y153578D02*
X1301492Y152254D01*
G01X1302816Y161145D02*
Y153578D01*
G01X1291700Y126500D02*
Y104811D01*
G01X1293100Y127900D02*
X1291700Y126500D01*
G01X1293100Y145100D02*
Y127900D01*
G01X1297676Y149676D02*
X1293100Y145100D01*
G01X1297676Y167276D02*
Y149676D01*
G01X1284300Y140067D02*
Y103404D01*
G01X1286200Y141967D02*
X1284300Y140067D01*
G01X1286200Y158900D02*
Y141967D01*
G01X1283683Y166218D02*
Y143772D01*
G01X1306354Y131198D02*
X1306900Y131744D01*
G01X1306354Y102655D02*
Y131198D01*
G01X1302270Y98571D02*
X1306354Y102655D01*
G01X1302270Y94512D02*
Y98571D01*
G01X1283062Y168932D02*
Y177674D01*
G01X1284835Y167159D02*
X1283062Y168932D01*
G01X1293224Y162382D02*
Y157460D01*
G01X1294498Y163656D02*
X1293224Y162382D01*
G01X1294498Y174727D02*
Y163656D01*
G01X1288829Y180396D02*
X1294498Y174727D01*
G01X1285664Y180396D02*
X1288829D01*
G01X1282514Y196519D02*
Y196493D01*
G01X1282974Y196979D02*
X1282514Y196519D01*
G01X1282974Y211327D02*
Y196979D01*
G01X1290896Y161825D02*
Y156903D01*
G01X1293246Y164175D02*
X1290896Y161825D01*
G01X1293246Y174208D02*
Y164175D01*
G01X1288387Y179067D02*
X1293246Y174208D01*
G01X1285133Y179067D02*
X1288387D01*
G01X1281722Y210808D02*
Y197498D01*
G01X1280758Y167153D02*
Y176718D01*
G01X1282531Y165380D02*
X1280758Y167153D01*
G01X1301956Y162005D02*
X1302816Y161145D01*
G01X1301956Y171141D02*
Y162005D01*
G01X1290258Y182839D02*
X1301956Y171141D01*
G01X1284992Y182839D02*
X1290258D01*
G01X1281799Y186032D02*
X1284992Y182839D01*
G01X1281799Y193190D02*
Y186032D01*
G01X1300300Y169900D02*
X1297676Y167276D01*
G01X1318814Y216171D02*
Y225186D01*
G01X1320185Y214800D02*
X1318814Y216171D01*
G01X1324974Y214800D02*
X1320185D01*
G01X1326474Y216300D02*
X1324974Y214800D01*
G01X1326474Y216500D02*
Y216300D01*
G01X1291994Y164694D02*
X1286200Y158900D01*
G01X1291994Y173572D02*
Y164694D01*
G01X1287874Y177692D02*
X1291994Y173572D01*
G01X1284708Y177692D02*
X1287874D01*
G01X1280370Y210130D02*
Y198162D01*
G01X1281910Y167991D02*
X1283683Y166218D01*
G01X1281910Y177196D02*
Y167991D01*
G01X1301962Y272048D02*
Y296136D01*
G01X1315277Y258733D02*
X1301962Y272048D01*
G01X1315277Y243889D02*
Y258733D01*
G01X1312700Y241312D02*
X1315277Y243889D01*
G01X1312700Y231300D02*
Y241312D01*
G01X1318814Y225186D02*
X1312700Y231300D01*
G01X1300583Y300428D02*
X1299735Y301298D01*
G01X1301159Y300428D02*
X1300583D01*
G01X1301539Y300806D02*
X1301159Y300428D01*
G01X1301539Y302925D02*
Y300806D01*
G01X1298980Y305484D02*
X1301539Y302925D01*
G01X1298980Y308803D02*
Y305484D01*
G01X1303837Y313660D02*
X1298980Y308803D01*
G01X1303837Y350436D02*
Y313660D01*
G01X1323750Y322520D02*
Y319750D01*
G01X1323219Y323051D02*
X1323750Y322520D01*
G01X1323219Y347999D02*
Y323051D01*
G01X1305941Y312787D02*
Y349341D01*
G01X1303380Y310226D02*
X1305941Y312787D01*
G01X1303380Y309441D02*
Y310226D01*
G01X1335252Y297141D02*
X1345900D01*
G01X1329241Y303152D02*
X1335252Y297141D01*
G01X1329241Y336435D02*
Y303152D01*
G01X1331333Y338527D02*
X1329241Y336435D01*
G01X1331333Y345137D02*
Y338527D01*
G01X1328000Y340489D02*
Y347000D01*
G01X1328198Y340291D02*
X1328000Y340489D01*
G01X1328198Y339300D02*
Y340291D01*
G01X1327668Y338770D02*
X1328198Y339300D01*
G01X1327668Y338263D02*
Y338770D01*
G01X1326837Y337432D02*
X1327668Y338263D01*
G01X1326837Y300709D02*
Y337432D01*
G01X1333701Y293845D02*
X1326837Y300709D01*
G01X1337855Y293845D02*
X1333701D01*
G01X1345700Y286000D02*
X1337855Y293845D01*
G01X1300195Y299038D02*
X1299700Y298557D01*
G01X1300599Y299431D02*
X1300195Y299038D01*
G01X1300606Y299431D02*
X1300599D01*
G01X1300651Y299476D02*
X1300606Y299431D01*
G01X1301552Y299476D02*
X1300651D01*
G01X1302491Y300410D02*
X1301552Y299476D01*
G01X1302491Y303320D02*
Y300410D01*
G01X1299932Y305879D02*
X1302491Y303320D01*
G01X1299932Y308408D02*
Y305879D01*
G01X1304789Y313265D02*
X1299932Y308408D01*
G01X1304789Y349988D02*
Y313265D01*
G01X1336204Y298767D02*
X1346293D01*
G01X1333226Y301745D02*
X1336204Y298767D01*
G01X1333226Y330715D02*
Y301745D01*
G01X1336336Y333825D02*
X1333226Y330715D01*
G01X1338271Y288390D02*
X1343121Y283540D01*
G01X1335162Y288390D02*
X1338271D01*
G01X1325500Y298052D02*
X1335162Y288390D01*
G01X1325500Y324142D02*
Y298052D01*
G01X1324684Y324958D02*
X1325500Y324142D01*
G01X1324684Y344740D02*
Y324958D01*
G01X1322067Y322467D02*
Y348477D01*
G01X1320900Y321300D02*
X1322067Y322467D01*
G01X1309534Y309644D02*
Y348193D01*
G01X1313678Y305500D02*
X1309534Y309644D01*
G01X1316600Y305500D02*
X1313678D01*
G01X1301962Y296136D02*
X1302768Y296942D01*
G01X1334320Y295555D02*
X1345284D01*
G01X1327989Y301886D02*
X1334320Y295555D01*
G01X1327989Y336954D02*
Y301886D01*
G01X1328820Y337785D02*
X1327989Y336954D01*
G01X1328820Y338292D02*
Y337785D01*
G01X1329757Y339229D02*
X1328820Y338292D01*
G01X1329757Y346511D02*
Y339229D01*
G01X1310286Y315020D02*
Y347787D01*
G01X1318176Y307130D02*
X1310286Y315020D01*
G01X1318176Y303282D02*
Y307130D01*
G01X1316533Y301639D02*
X1318176Y303282D01*
G01X1316533Y293167D02*
Y301639D01*
G01X1308887Y285521D02*
X1316533Y293167D01*
G01X1308887Y285015D02*
Y285521D01*
G01X1307384Y353983D02*
X1303837Y350436D01*
G01X1307384Y366316D02*
Y353983D01*
G01X1308866Y367798D02*
X1307384Y366316D01*
G01X1308866Y413068D02*
Y367798D01*
G01X1327552Y352332D02*
X1323219Y347999D01*
G01X1327552Y354660D02*
Y352332D01*
G01X1338881Y365989D02*
X1327552Y354660D01*
G01X1338881Y369568D02*
Y365989D01*
G01X1341173Y371860D02*
X1338881Y369568D01*
G01X1341173Y391898D02*
Y371860D01*
G01X1339033Y394038D02*
X1341173Y391898D01*
G01X1339033Y411716D02*
Y394038D01*
G01X1310970Y366493D02*
Y413942D01*
G01X1309488Y365011D02*
X1310970Y366493D01*
G01X1309488Y352888D02*
Y365011D01*
G01X1305941Y349341D02*
X1309488Y352888D01*
G01X1337385Y351612D02*
X1336886Y351113D01*
G01X1339999Y351612D02*
X1337385D01*
G01X1347136Y358749D02*
X1339999Y351612D01*
G01X1332613Y346417D02*
X1331333Y345137D01*
G01X1340185Y394516D02*
Y411189D01*
G01X1342325Y392376D02*
X1340185Y394516D01*
G01X1340156Y369011D02*
X1342325Y371180D01*
G01X1340156Y365634D02*
Y369011D01*
G01X1334900Y360378D02*
X1340156Y365634D01*
G01X1334900Y349800D02*
Y360378D01*
G01X1333400Y348300D02*
X1334900Y349800D01*
G01X1329300Y348300D02*
X1333400D01*
G01X1328000Y347000D02*
X1329300Y348300D01*
G01X1308336Y353535D02*
X1304789Y349988D01*
G01X1308336Y365943D02*
Y353535D01*
G01X1309818Y367425D02*
X1308336Y365943D01*
G01X1309818Y413464D02*
Y367425D01*
G01X1315496Y416503D02*
Y361190D01*
G01X1326014Y346070D02*
X1324684Y344740D01*
G01X1326014Y347732D02*
Y346070D01*
G01X1337881Y393560D02*
Y412740D01*
G01X1340021Y391420D02*
X1337881Y393560D01*
G01X1340021Y372800D02*
Y391420D01*
G01X1337666Y370445D02*
X1340021Y372800D01*
G01X1337666Y366404D02*
Y370445D01*
G01X1326400Y355138D02*
X1337666Y366404D01*
G01X1326400Y352810D02*
Y355138D01*
G01X1322067Y348477D02*
X1326400Y352810D01*
G01X1313976Y364236D02*
Y415677D01*
G01X1312840Y363100D02*
X1313976Y364236D01*
G01X1312840Y351499D02*
Y363100D01*
G01X1309534Y348193D02*
X1312840Y351499D01*
G01X1340550Y349756D02*
X1339597D01*
G01X1348838Y358044D02*
X1340550Y349756D01*
G01X1337451Y344250D02*
X1350650Y357449D01*
G01X1335250Y344250D02*
X1337451D01*
G01X1314744Y363535D02*
Y415975D01*
G01X1313909Y362700D02*
X1314744Y363535D01*
G01X1313909Y351410D02*
Y362700D01*
G01X1310286Y347787D02*
X1313909Y351410D01*
G01X1302500Y419434D02*
X1308866Y413068D01*
G01X1302500Y421534D02*
Y419434D01*
G01X1288830Y435204D02*
X1302500Y421534D01*
G01X1288830Y437001D02*
Y435204D01*
G01X1285769Y440062D02*
X1288830Y437001D01*
G01X1347975Y420658D02*
X1339033Y411716D01*
G01X1294419Y439590D02*
X1288671Y445338D01*
G01X1302011Y439590D02*
X1294419D01*
G01X1308500Y433101D02*
X1302011Y439590D01*
G01X1308500Y416412D02*
Y433101D01*
G01X1310970Y413942D02*
X1308500Y416412D01*
G01X1340185Y411189D02*
X1352820Y423824D01*
G01X1303500Y419782D02*
X1309818Y413464D01*
G01X1303500Y421949D02*
Y419782D01*
G01X1289970Y435479D02*
X1303500Y421949D01*
G01X1289970Y439919D02*
Y435479D01*
G01X1286831Y443058D02*
X1289970Y439919D01*
G01X1315004Y416995D02*
X1315496Y416503D01*
G01X1315004Y422834D02*
Y416995D01*
G01X1316840Y424670D02*
X1315004Y422834D01*
G01X1324930Y424670D02*
X1316840D01*
G01X1327800Y427540D02*
X1324930Y424670D01*
G01X1327800Y458241D02*
Y427540D01*
G01X1333087Y463528D02*
X1327800Y458241D01*
G01X1341528Y463528D02*
X1333087D01*
G01X1337881Y412740D02*
X1346823Y421682D01*
G01X1321172Y461048D02*
Y464474D01*
G01X1322400Y459820D02*
X1321172Y461048D01*
G01X1322400Y438900D02*
Y459820D01*
G01X1318000Y434500D02*
X1322400Y438900D01*
G01X1318000Y428000D02*
Y434500D01*
G01X1313004Y423004D02*
X1318000Y428000D01*
G01X1313004Y416649D02*
Y423004D01*
G01X1313976Y415677D02*
X1313004Y416649D01*
G01X1323815Y461967D02*
Y463543D01*
G01X1323450Y461602D02*
X1323815Y461967D01*
G01X1323450Y426950D02*
Y461602D01*
G01X1322000Y425500D02*
X1323450Y426950D01*
G01X1316606Y425500D02*
X1322000D01*
G01X1314004Y422898D02*
X1316606Y425500D01*
G01X1314004Y416715D02*
Y422898D01*
G01X1314744Y415975D02*
X1314004Y416715D01*
G01X1332673Y494050D02*
X1347297D01*
G01X1318022Y508701D02*
X1332673Y494050D01*
G01X1309093Y508701D02*
X1318022D01*
G01X1303541Y514253D02*
X1309093Y508701D01*
G01X1303541Y518454D02*
Y514253D01*
G01X1298442Y523553D02*
X1303541Y518454D01*
G01X1282678Y523553D02*
X1298442D01*
G01X1330273Y484416D02*
X1344435Y470254D01*
G01X1302543Y484416D02*
X1330273D01*
G01X1300259Y486700D02*
X1302543Y484416D01*
G01X1294238Y486700D02*
X1300259D01*
G01X1293380Y487558D02*
X1294238Y486700D01*
G01X1284684Y487558D02*
X1293380D01*
G01X1341255Y468330D02*
X1357708D01*
G01X1327073Y482512D02*
X1341255Y468330D01*
G01X1294951Y482512D02*
X1327073D01*
G01X1292361Y485102D02*
X1294951Y482512D01*
G01X1340465Y466426D02*
X1348409D01*
G01X1326300Y480591D02*
X1340465Y466426D01*
G01X1293509Y480591D02*
X1326300D01*
G01X1291400Y482700D02*
X1293509Y480591D01*
G01X1290500Y482700D02*
X1291400D01*
G01X1317050Y519854D02*
X1305447Y531457D01*
G01X1321903Y519854D02*
X1317050D01*
G01X1329283Y512474D02*
X1321903Y519854D01*
G01X1329283Y505726D02*
Y512474D01*
G01X1332602Y502407D02*
X1329283Y505726D01*
G01X1340122Y502407D02*
X1332602D01*
G01X1342851Y499678D02*
X1340122Y502407D01*
G01X1317361Y520607D02*
X1306199Y531769D01*
G01X1324993Y520607D02*
X1317361D01*
G01X1344761Y500839D02*
X1324993Y520607D01*
G01X1333151Y495202D02*
X1346819D01*
G01X1318500Y509853D02*
X1333151Y495202D01*
G01X1309571Y509853D02*
X1318500D01*
G01X1304693Y514731D02*
X1309571Y509853D01*
G01X1304693Y518932D02*
Y514731D01*
G01X1298920Y524705D02*
X1304693Y518932D01*
G01X1283156Y524705D02*
X1298920D01*
G01X1317946Y522150D02*
X1307703Y532393D01*
G01X1330250Y522150D02*
X1317946D01*
G01X1336477Y528377D02*
X1330250Y522150D01*
G01X1333746Y495954D02*
X1346288D01*
G01X1318895Y510805D02*
X1333746Y495954D01*
G01X1309966Y510805D02*
X1318895D01*
G01X1305645Y515126D02*
X1309966Y510805D01*
G01X1305645Y519327D02*
Y515126D01*
G01X1299315Y525657D02*
X1305645Y519327D01*
G01X1283551Y525657D02*
X1299315D01*
G01X1294639Y481760D02*
X1292049Y484350D01*
G01X1326761Y481760D02*
X1294639D01*
G01X1340943Y467578D02*
X1326761Y481760D01*
G01X1348940Y467578D02*
X1340943D01*
G01X1289225Y490414D02*
X1281554Y498085D01*
G01X1294565Y490414D02*
X1289225D01*
G01X1295423Y489556D02*
X1294565Y490414D01*
G01X1301444Y489556D02*
X1295423D01*
G01X1303728Y487272D02*
X1301444Y489556D01*
G01X1334212Y487272D02*
X1303728D01*
G01X1344587Y476897D02*
X1334212Y487272D01*
G01X1281853Y496439D02*
X1280595D01*
G01X1288830Y489462D02*
X1281853Y496439D01*
G01X1294170Y489462D02*
X1288830D01*
G01X1295028Y488604D02*
X1294170Y489462D01*
G01X1301049Y488604D02*
X1295028D01*
G01X1303333Y486320D02*
X1301049Y488604D01*
G01X1333817Y486320D02*
X1303333D01*
G01X1347196Y472941D02*
X1333817Y486320D01*
G01X1293775Y488510D02*
X1285091D01*
G01X1294633Y487652D02*
X1293775Y488510D01*
G01X1300654Y487652D02*
X1294633D01*
G01X1302938Y485368D02*
X1300654Y487652D01*
G01X1331147Y485368D02*
X1302938D01*
G01X1345182Y471333D02*
X1331147Y485368D01*
G01X1321440Y499440D02*
X1320300Y498300D01*
G01X1321440Y503936D02*
Y499440D01*
G01X1317876Y507500D02*
X1321440Y503936D01*
G01X1308947Y507500D02*
X1317876D01*
G01X1302589Y513858D02*
X1308947Y507500D01*
G01X1302589Y518059D02*
Y513858D01*
G01X1298047Y522601D02*
X1302589Y518059D01*
G01X1282283Y522601D02*
X1298047D01*
G01X1290950Y480650D02*
X1290500Y480200D01*
G01X1291820Y480650D02*
X1290950D01*
G01X1293031Y479439D02*
X1291820Y480650D01*
G01X1325822Y479439D02*
X1293031D01*
G01X1339991Y465270D02*
X1325822Y479439D01*
G01X1347617Y465270D02*
X1339991D01*
G01X1316381Y489146D02*
X1350706D01*
G01X1314627Y490900D02*
X1316381Y489146D01*
G01X1295709Y490900D02*
X1314627D01*
G01X1295043Y491566D02*
X1295709Y490900D01*
G01X1289703Y491566D02*
X1295043D01*
G01X1282032Y499237D02*
X1289703Y491566D01*
G01X1331452Y492898D02*
X1347775D01*
G01X1328515Y495835D02*
X1331452Y492898D01*
G01X1318911Y495835D02*
X1328515D01*
G01X1317450Y497296D02*
X1318911Y495835D01*
G01X1308058Y497296D02*
X1317450D01*
G01X1298194Y507160D02*
X1308058Y497296D01*
G01X1295600Y507160D02*
X1298194D01*
G01X1294200Y508560D02*
X1295600Y507160D01*
G01X1294200Y518700D02*
Y508560D01*
G01X1291600Y521300D02*
X1294200Y518700D01*
G01X1280800Y521300D02*
X1291600D01*
G01X1285451Y476228D02*
X1301240D01*
G01X1330562Y521398D02*
X1336789Y527625D01*
G01X1317634Y521398D02*
X1330562D01*
G01X1306951Y532081D02*
X1317634Y521398D01*
G01X1292985Y486606D02*
X1280465D01*
G01X1294641Y484950D02*
X1292985Y486606D01*
G01X1299450Y484950D02*
X1294641D01*
G01X1316790Y519050D02*
X1304695Y531145D01*
G01X1321643Y519050D02*
X1316790D01*
G01X1328531Y512162D02*
X1321643Y519050D01*
G01X1328531Y505414D02*
Y512162D01*
G01X1332290Y501655D02*
X1328531Y505414D01*
G01X1338645Y501655D02*
X1332290D01*
G01X1341050Y499250D02*
X1338645Y501655D01*
G01X1341050Y498275D02*
Y499250D01*
G01X1329938Y522902D02*
X1336165Y529129D01*
G01X1318258Y522902D02*
X1329938D01*
G01X1308680Y532480D02*
X1318258Y522902D01*
G01X1295263Y483264D02*
X1292673Y485854D01*
G01X1327385Y483264D02*
X1295263D01*
G01X1341547Y469102D02*
X1327385Y483264D01*
G01X1367860Y469102D02*
X1341547D01*
G01X1330305Y542380D02*
X1350096D01*
G01X1329604Y541679D02*
X1330305Y542380D01*
G01X1326008Y541679D02*
X1329604D01*
G01X1322931Y544756D02*
X1326008Y541679D01*
G01X1322931Y547232D02*
Y544756D01*
G01X1326126Y550427D02*
X1322931Y547232D01*
G01X1326126Y610403D02*
Y550427D01*
G01X1289863Y576952D02*
X1292190D01*
G01X1289270Y577545D02*
X1289863Y576952D01*
G01X1281714Y577545D02*
X1289270D01*
G01X1284712Y542176D02*
X1282784Y540248D01*
G01X1297568Y542176D02*
X1284712D01*
G01X1305447Y534297D02*
X1297568Y542176D01*
G01X1305447Y531457D02*
Y534297D01*
G01X1284400Y542928D02*
X1282472Y541000D01*
G01X1297880Y542928D02*
X1284400D01*
G01X1306199Y534609D02*
X1297880Y542928D01*
G01X1306199Y531769D02*
Y534609D01*
G01X1296600Y580129D02*
Y588207D01*
G01X1296676Y580053D02*
X1296600Y580129D01*
G01X1296676Y578747D02*
Y580053D01*
G01X1296600Y578671D02*
X1296676Y578747D01*
G01X1296600Y564497D02*
Y578671D01*
G01X1294771Y562668D02*
X1296600Y564497D01*
G01X1294771Y548165D02*
Y562668D01*
G01X1307703Y535233D02*
X1294771Y548165D01*
G01X1307703Y532393D02*
Y535233D01*
G01X1390207Y528377D02*
X1336477D01*
G01X1333423Y548652D02*
X1347638D01*
G01X1330900Y551175D02*
X1333423Y548652D01*
G01X1330900Y612600D02*
Y551175D01*
G01X1282600Y583600D02*
X1281700D01*
G01X1290200Y563300D02*
X1290900D01*
G01X1289371Y564129D02*
X1290200Y563300D01*
G01X1282371Y564129D02*
X1289371D01*
G01X1328600Y549553D02*
Y611461D01*
G01X1331789Y546364D02*
X1328600Y549553D01*
G01X1348547Y546364D02*
X1331789D01*
G01X1281689Y578962D02*
X1290292D01*
G01X1332184Y547316D02*
X1348152D01*
G01X1329552Y549948D02*
X1332184Y547316D01*
G01X1329552Y611968D02*
Y549948D01*
G01X1336789Y527625D02*
X1389777D01*
G01X1306951Y534921D02*
Y532081D01*
G01X1296793Y545079D02*
X1306951Y534921D01*
G01X1284831Y545079D02*
X1296793D01*
G01X1280777Y549133D02*
X1284831Y545079D01*
G01X1280777Y554625D02*
Y549133D01*
G01X1284852Y558700D02*
X1280777Y554625D01*
G01X1292000Y558700D02*
X1284852D01*
G01X1293600Y560300D02*
X1292000Y558700D01*
G01X1293600Y563300D02*
Y560300D01*
G01X1294029Y563729D02*
X1293600Y563300D01*
G01X1294029Y577971D02*
Y563729D01*
G01X1290900Y581100D02*
X1294029Y577971D01*
G01X1290900Y582871D02*
Y581100D01*
G01X1294029Y586000D02*
X1290900Y582871D01*
G01X1294029Y594221D02*
Y586000D01*
G01X1283676Y539947D02*
X1282753Y539024D01*
G01X1283676Y540000D02*
Y539947D01*
G01X1298654Y540000D02*
X1283676D01*
G01X1304695Y533959D02*
X1298654Y540000D01*
G01X1304695Y531145D02*
Y533959D01*
G01X1327278Y546333D02*
Y610881D01*
G01X1327956Y545655D02*
X1327278Y546333D01*
G01X1336165Y529129D02*
X1394129D01*
G01X1308680Y535320D02*
Y532480D01*
G01X1295924Y548076D02*
X1308680Y535320D01*
G01X1295924Y562191D02*
Y548076D01*
G01X1297606Y563873D02*
X1295924Y562191D01*
G01X1297606Y588265D02*
Y563873D01*
G01X1324529Y612000D02*
X1326126Y610403D01*
G01X1294800Y612000D02*
X1324529D01*
G01X1291619Y615181D02*
X1294800Y612000D01*
G01X1283399Y615181D02*
X1291619D01*
G01X1282919Y614701D02*
X1283399Y615181D01*
G01X1295772Y594310D02*
X1292482Y597600D01*
G01X1295772Y589035D02*
Y594310D01*
G01X1296600Y588207D02*
X1295772Y589035D01*
G01X1327000Y616500D02*
X1330900Y612600D01*
G01X1305500Y616500D02*
X1327000D01*
G01X1299356Y622644D02*
X1305500Y616500D01*
G01X1301384Y618119D02*
X1298011Y621492D01*
G01X1313452Y621077D02*
X1311876Y619501D01*
G01X1315129Y621077D02*
X1313452D01*
G01X1315443Y620763D02*
X1315129Y621077D01*
G01X1381903Y620763D02*
X1315443D01*
G01X1300610Y614340D02*
X1296010Y618940D01*
G01X1325721Y614340D02*
X1300610D01*
G01X1328600Y611461D02*
X1325721Y614340D01*
G01X1326220Y615300D02*
X1329552Y611968D01*
G01X1300997Y615300D02*
X1326220D01*
G01X1296405Y619892D02*
X1300997Y615300D01*
G01X1307076Y617424D02*
X1372872D01*
G01X1301104Y623396D02*
X1307076Y617424D01*
G01X1291945Y596305D02*
X1294029Y594221D01*
G01X1314713Y619738D02*
X1381429D01*
G01X1314476Y619501D02*
X1314713Y619738D01*
G01X1295293Y613188D02*
X1291599Y616882D01*
G01X1324971Y613188D02*
X1295293D01*
G01X1327278Y610881D02*
X1324971Y613188D01*
G01X1296524Y589347D02*
X1297606Y588265D01*
G01X1296524Y595188D02*
Y589347D01*
G01X1292862Y598850D02*
X1296524Y595188D01*
G01X1392600Y-17615D02*
X1388572Y-21643D01*
G01X1392600Y507D02*
Y-17615D01*
G01X1396552Y4459D02*
X1392600Y507D01*
G01X1396552Y13822D02*
Y4459D01*
G01X1398898Y16168D02*
X1396552Y13822D01*
G01X1430125Y16168D02*
X1398898D01*
G01X1398486Y17386D02*
X1430537D01*
G01X1395400Y14300D02*
X1398486Y17386D01*
G01X1395400Y5030D02*
Y14300D01*
G01X1391382Y1012D02*
X1395400Y5030D01*
G01X1391382Y-17110D02*
Y1012D01*
G01X1388001Y-20491D02*
X1391382Y-17110D01*
G01X1360600Y-20491D02*
X1388001D01*
G01X1358209Y-18100D02*
X1360600Y-20491D01*
G01X1356800Y-18100D02*
X1358209D01*
G01X1354409Y-20491D02*
X1356800Y-18100D01*
G01X1371368Y93424D02*
X1373651Y95707D01*
G01X1402082Y86023D02*
X1411727D01*
G01X1401425Y86680D02*
X1402082Y86023D01*
G01X1398952Y86680D02*
X1401425D01*
G01X1397585Y88047D02*
X1398952Y86680D01*
G01X1386637Y88047D02*
X1397585D01*
G01X1383239Y84649D02*
X1386637Y88047D01*
G01X1378296Y84649D02*
X1383239D01*
G01X1373870Y80223D02*
X1378296Y84649D01*
G01X1373870Y73341D02*
Y80223D01*
G01X1369260Y68731D02*
X1373870Y73341D01*
G01X1369260Y56616D02*
Y68731D01*
G01X1364122Y51478D02*
X1369260Y56616D01*
G01X1351139Y51478D02*
X1364122D01*
G01X1402701Y87672D02*
X1412554D01*
G01X1402190Y88183D02*
X1402701Y87672D01*
G01X1401606Y88183D02*
X1402190D01*
G01X1401605Y88184D02*
X1401606Y88183D01*
G01X1399576Y88184D02*
X1401605D01*
G01X1398209Y89551D02*
X1399576Y88184D01*
G01X1386013Y89551D02*
X1398209D01*
G01X1382615Y86153D02*
X1386013Y89551D01*
G01X1377382Y86153D02*
X1382615D01*
G01X1371740Y80511D02*
X1377382Y86153D01*
G01X1371740Y74496D02*
Y80511D01*
G01X1367179Y69935D02*
X1371740Y74496D01*
G01X1348437Y69935D02*
X1367179D01*
G01X1346554Y68052D02*
X1348437Y69935D01*
G01X1346554Y49021D02*
Y68052D01*
G01X1363601Y52230D02*
X1350827D01*
G01X1368212Y56841D02*
X1363601Y52230D01*
G01X1368212Y69324D02*
Y56841D01*
G01X1372700Y73812D02*
X1368212Y69324D01*
G01X1372700Y80195D02*
Y73812D01*
G01X1377906Y85401D02*
X1372700Y80195D01*
G01X1382927Y85401D02*
X1377906D01*
G01X1386325Y88799D02*
X1382927Y85401D01*
G01X1397897Y88799D02*
X1386325D01*
G01X1399264Y87432D02*
X1397897Y88799D01*
G01X1401878Y87432D02*
X1399264D01*
G01X1402396Y86914D02*
X1401878Y87432D01*
G01X1412248Y86914D02*
X1402396D01*
G01X1364706Y50070D02*
X1351723D01*
G01X1375278Y60642D02*
X1364706Y50070D01*
G01X1375278Y70207D02*
Y60642D01*
G01X1381500Y76429D02*
X1375278Y70207D01*
G01X1381500Y80672D02*
Y76429D01*
G01X1387467Y86639D02*
X1381500Y80672D01*
G01X1397001Y86639D02*
X1387467D01*
G01X1398368Y85272D02*
X1397001Y86639D01*
G01X1410486Y85272D02*
X1398368D01*
G01X1382210Y89084D02*
X1342855D01*
G01X1384625Y91499D02*
X1382210Y89084D01*
G01X1397630Y91499D02*
X1384625D01*
G01X1403181Y97050D02*
X1397630Y91499D01*
G01X1397131Y92651D02*
X1408082Y103602D01*
G01X1383895Y92651D02*
X1397131D01*
G01X1381612Y90368D02*
X1383895Y92651D01*
G01X1342509Y90368D02*
X1381612D01*
G01X1345352Y68865D02*
Y53226D01*
G01X1348225Y71738D02*
X1345352Y68865D01*
G01X1367710Y71738D02*
X1348225D01*
G01X1370879Y74907D02*
X1367710Y71738D01*
G01X1370879Y80860D02*
Y74907D01*
G01X1376924Y86905D02*
X1370879Y80860D01*
G01X1382303Y86905D02*
X1376924D01*
G01X1385701Y90303D02*
X1382303Y86905D01*
G01X1398521Y90303D02*
X1385701D01*
G01X1399888Y88936D02*
X1398521Y90303D01*
G01X1402501Y88936D02*
X1399888D01*
G01X1403013Y88424D02*
X1402501Y88936D01*
G01X1412866Y88424D02*
X1403013D01*
G01X1396538Y93803D02*
X1406558Y103823D01*
G01X1374629Y93803D02*
X1396538D01*
G01X1372346Y91520D02*
X1374629Y93803D01*
G01X1342031Y91520D02*
X1372346D01*
G01X1371837Y92472D02*
X1374120Y94755D01*
G01X1401364Y128336D02*
X1397006Y132694D01*
G01X1401364Y127887D02*
Y128336D01*
G01X1401406Y127845D02*
X1401364Y127887D01*
G01X1401406Y127328D02*
Y127845D01*
G01X1410562Y118172D02*
X1401406Y127328D01*
G01X1400300Y116271D02*
Y121500D01*
G01X1404577Y111994D02*
X1400300Y116271D01*
G01X1395748Y95707D02*
X1404577Y104536D01*
G01X1373651Y95707D02*
X1395748D01*
G01X1399100Y116000D02*
X1398600Y116500D01*
G01X1399100Y115600D02*
Y116000D01*
G01X1403659Y111041D02*
X1399100Y115600D01*
G01X1395994Y97017D02*
X1403659Y104682D01*
G01X1368220Y97017D02*
X1395994D01*
G01X1365282Y99955D02*
X1368220Y97017D01*
G01X1352682Y99955D02*
X1365282D01*
G01X1350927Y98200D02*
X1352682Y99955D01*
G01X1409310Y97050D02*
X1403181D01*
G01X1401200Y123829D02*
Y124300D01*
G01X1404253Y120776D02*
X1401200Y123829D01*
G01X1405606Y113194D02*
X1402500Y116300D01*
G01X1396143Y94755D02*
X1405606Y104218D01*
G01X1374120Y94755D02*
X1396143D01*
G01X1362620Y209920D02*
Y243313D01*
G01X1362000Y209300D02*
X1362620Y209920D01*
G01X1403400Y204766D02*
X1406953Y208319D01*
G01X1402870Y216429D02*
Y207918D01*
G01X1401761Y217538D02*
X1402870Y216429D01*
G01X1401091Y217538D02*
X1401761D01*
G01X1394881Y223748D02*
X1401091Y217538D01*
G01X1359500Y209200D02*
Y229670D01*
G01X1356926Y209100D02*
Y242979D01*
G01X1399397Y260474D02*
X1405340Y254526D01*
G01X1399397Y261429D02*
Y260474D01*
G01X1399398Y261430D02*
X1399397Y261429D01*
G01X1399398Y277402D02*
Y261430D01*
G01X1395300Y281500D02*
X1399398Y277402D01*
G01X1394789Y257416D02*
X1399852Y252353D01*
G01X1394789Y263341D02*
Y257416D01*
G01X1394790Y263342D02*
X1394789Y263341D01*
G01X1394790Y275295D02*
Y263342D01*
G01X1378772Y291313D02*
X1394790Y275295D01*
G01X1373003Y270897D02*
X1359000Y284900D01*
G01X1373003Y253696D02*
Y270897D01*
G01X1362620Y243313D02*
X1373003Y253696D01*
G01X1402100Y232200D02*
X1398600Y228700D01*
G01X1402100Y243305D02*
Y232200D01*
G01X1400554Y244851D02*
X1402100Y243305D01*
G01X1400554Y248715D02*
Y244851D01*
G01X1395502Y253769D02*
X1400554Y248715D01*
G01X1393537Y255734D02*
X1395502Y253769D01*
G01X1393537Y263860D02*
Y255734D01*
G01X1393538Y263861D02*
X1393537Y263860D01*
G01X1393538Y274776D02*
Y263861D01*
G01X1377466Y290848D02*
X1393538Y274776D01*
G01X1403352Y231222D02*
X1401565Y229435D01*
G01X1403352Y243824D02*
Y231222D01*
G01X1401806Y245370D02*
X1403352Y243824D01*
G01X1401806Y252628D02*
Y245370D01*
G01X1395941Y258493D02*
X1401806Y252628D01*
G01X1395941Y262863D02*
Y258493D01*
G01X1395942Y262864D02*
X1395941Y262863D01*
G01X1395942Y275968D02*
Y262864D01*
G01X1388000Y283910D02*
X1395942Y275968D01*
G01X1400550Y260951D02*
Y282747D01*
G01X1406625Y254872D02*
X1400550Y260951D01*
G01X1399528Y233775D02*
X1399978D01*
G01X1399176Y233423D02*
X1399528Y233775D01*
G01X1399176Y231382D02*
Y233423D01*
G01X1398136Y230342D02*
X1399176Y231382D01*
G01X1397748Y230342D02*
X1398136D01*
G01X1397706Y230300D02*
X1397748Y230342D01*
G01X1391206Y230300D02*
X1397706D01*
G01X1390100Y231406D02*
X1391206Y230300D01*
G01X1390100Y248840D02*
Y231406D01*
G01X1388578Y250362D02*
X1390100Y248840D01*
G01X1388578Y269789D02*
Y250362D01*
G01X1364615Y293752D02*
X1388578Y269789D01*
G01X1397094Y276446D02*
X1389166Y284374D01*
G01X1397094Y262386D02*
Y276446D01*
G01X1397093Y262385D02*
X1397094Y262386D01*
G01X1397093Y258971D02*
Y262385D01*
G01X1402958Y253106D02*
X1397093Y258971D01*
G01X1402958Y245848D02*
Y253106D01*
G01X1404504Y244302D02*
X1402958Y245848D01*
G01X1399600Y225100D02*
X1404504Y230004D01*
G01X1399600Y223600D02*
Y225100D01*
G01X1400066Y237746D02*
Y236274D01*
G01X1391352Y246460D02*
X1400066Y237746D01*
G01X1391352Y249359D02*
Y246460D01*
G01X1389977Y250734D02*
X1391352Y249359D01*
G01X1389977Y270161D02*
Y250734D01*
G01X1364427Y295711D02*
X1389977Y270161D01*
G01X1397211Y227346D02*
Y226041D01*
G01X1395747Y228810D02*
X1397211Y227346D01*
G01X1393366Y228810D02*
X1395747D01*
G01X1392650Y228094D02*
X1393366Y228810D01*
G01X1386898Y228094D02*
X1392650D01*
G01X1383384Y231608D02*
X1386898Y228094D01*
G01X1383384Y257664D02*
Y231608D01*
G01X1385624Y259904D02*
X1383384Y257664D01*
G01X1385624Y266435D02*
Y259904D01*
G01X1383009Y269050D02*
X1385624Y266435D01*
G01X1377669Y269050D02*
X1383009D01*
G01X1370290Y276429D02*
X1377669Y269050D01*
G01X1370290Y284233D02*
Y276429D01*
G01X1394881Y226997D02*
Y223748D01*
G01X1370974Y269826D02*
X1355800Y285000D01*
G01X1370974Y254620D02*
Y269826D01*
G01X1360900Y244546D02*
X1370974Y254620D01*
G01X1360900Y231070D02*
Y244546D01*
G01X1359500Y229670D02*
X1360900Y231070D01*
G01X1361019Y275881D02*
X1352400Y284500D01*
G01X1361019Y247072D02*
Y275881D01*
G01X1356926Y242979D02*
X1361019Y247072D01*
G01X1388500Y230789D02*
X1388518D01*
G01X1388500Y230800D02*
Y230789D01*
G01X1388600Y230900D02*
X1388500Y230800D01*
G01X1388600Y248052D02*
Y230900D01*
G01X1387118Y249534D02*
X1388600Y248052D01*
G01X1387118Y269478D02*
Y249534D01*
G01X1364554Y292042D02*
X1387118Y269478D01*
G01X1398246Y276924D02*
X1390319Y284851D01*
G01X1398246Y261908D02*
Y276924D01*
G01X1398245Y261907D02*
X1398246Y261908D01*
G01X1398245Y259457D02*
Y261907D01*
G01X1404110Y253590D02*
X1398245Y259457D01*
G01X1402400Y226270D02*
X1405656Y229526D01*
G01X1402400Y223600D02*
Y226270D01*
G01X1395300Y290900D02*
Y281500D01*
G01X1400000Y295600D02*
X1395300Y290900D01*
G01X1400000Y311334D02*
Y295600D01*
G01X1396486Y314848D02*
X1400000Y311334D01*
G01X1396486Y320353D02*
Y314848D01*
G01X1402704Y326571D02*
X1396486Y320353D01*
G01X1402704Y326572D02*
Y326571D01*
G01X1402800Y326668D02*
X1402704Y326572D01*
G01X1402800Y330888D02*
Y326668D01*
G01X1404912Y333000D02*
X1402800Y330888D01*
G01X1378772Y310672D02*
Y291313D01*
G01X1380300Y312200D02*
X1378772Y310672D01*
G01X1383193Y312200D02*
X1380300D01*
G01X1386524Y315531D02*
X1383193Y312200D01*
G01X1386524Y321772D02*
Y315531D01*
G01X1394554Y329802D02*
X1386524Y321772D01*
G01X1394554Y333714D02*
Y329802D01*
G01X1402636Y341796D02*
X1394554Y333714D01*
G01X1377466Y319554D02*
Y290848D01*
G01X1380174Y322262D02*
X1377466Y319554D01*
G01X1385162Y322262D02*
X1380174D01*
G01X1392400Y329500D02*
X1385162Y322262D01*
G01X1392400Y330800D02*
Y329500D01*
G01X1388000Y321360D02*
Y283910D01*
G01X1395700Y329060D02*
X1388000Y321360D01*
G01X1395700Y329244D02*
Y329060D01*
G01X1396470Y330014D02*
X1395700Y329244D01*
G01X1353254Y333628D02*
Y392696D01*
G01X1358142Y328740D02*
X1353254Y333628D01*
G01X1362260Y328740D02*
X1358142D01*
G01X1366000Y325000D02*
X1362260Y328740D01*
G01X1366000Y322800D02*
Y325000D01*
G01X1367200Y321600D02*
X1366000Y322800D01*
G01X1352502Y333033D02*
Y392384D01*
G01X1357547Y327988D02*
X1352502Y333033D01*
G01X1361512Y327988D02*
X1357547D01*
G01X1364800Y324700D02*
X1361512Y327988D01*
G01X1364800Y322700D02*
Y324700D01*
G01X1363700Y321600D02*
X1364800Y322700D01*
G01X1401261Y313531D02*
X1404730Y317000D01*
G01X1401261Y301310D02*
Y313531D01*
G01X1405000Y297571D02*
X1401261Y301310D01*
G01X1400516Y286726D02*
X1405000Y291210D01*
G01X1400516Y282781D02*
Y286726D01*
G01X1400550Y282747D02*
X1400516Y282781D01*
G01X1349289Y293752D02*
X1364615D01*
G01X1345900Y297141D02*
X1349289Y293752D01*
G01X1345700Y285300D02*
Y286000D01*
G01X1400400Y327805D02*
Y335400D01*
G01X1394182Y321587D02*
X1400400Y327805D01*
G01X1394182Y314957D02*
Y321587D01*
G01X1393078Y313853D02*
X1394182Y314957D01*
G01X1391223Y313853D02*
X1393078D01*
G01X1389166Y311796D02*
X1391223Y313853D01*
G01X1389166Y284374D02*
Y311796D01*
G01X1349349Y295711D02*
X1364427D01*
G01X1346293Y298767D02*
X1349349Y295711D01*
G01X1365742Y288781D02*
X1370290Y284233D01*
G01X1350508Y288781D02*
X1365742D01*
G01X1348301Y286574D02*
X1350508Y288781D01*
G01X1348301Y285020D02*
Y286574D01*
G01X1346821Y283540D02*
X1348301Y285020D01*
G01X1343121Y283540D02*
X1346821D01*
G01X1352400Y284500D02*
Y285000D01*
G01X1348797Y292042D02*
X1364554D01*
G01X1345284Y295555D02*
X1348797Y292042D01*
G01X1401552Y333058D02*
X1408376Y339882D01*
G01X1401552Y327049D02*
Y333058D01*
G01X1395334Y320831D02*
X1401552Y327049D01*
G01X1395334Y314479D02*
Y320831D01*
G01X1393555Y312700D02*
X1395334Y314479D01*
G01X1391700Y312700D02*
X1393555D01*
G01X1390319Y311319D02*
X1391700Y312700D01*
G01X1390319Y284851D02*
Y311319D01*
G01X1409108Y341796D02*
X1402636D01*
G01X1348045Y397905D02*
Y407295D01*
G01X1353254Y392696D02*
X1348045Y397905D01*
G01X1347293Y397593D02*
Y407607D01*
G01X1352502Y392384D02*
X1347293Y397593D01*
G01X1347136Y390185D02*
Y358749D01*
G01X1342037Y395284D02*
X1347136Y390185D01*
G01X1342037Y409785D02*
Y395284D01*
G01X1342325Y371180D02*
Y392376D01*
G01X1348838Y389480D02*
Y358044D01*
G01X1348839Y389481D02*
X1348838Y389480D01*
G01X1348839Y390889D02*
Y389481D01*
G01X1343739Y395989D02*
X1348839Y390889D01*
G01X1343739Y409080D02*
Y395989D01*
G01X1345441Y396694D02*
Y408375D01*
G01X1350650Y391485D02*
X1345441Y396694D01*
G01X1350650Y357449D02*
Y391485D01*
G01X1391748Y437752D02*
X1404977D01*
G01X1389000Y440500D02*
X1391748Y437752D01*
G01X1373852Y440500D02*
X1389000D01*
G01X1373000Y441352D02*
X1373852Y440500D01*
G01X1373000Y445400D02*
Y441352D01*
G01X1375100Y447500D02*
X1373000Y445400D01*
G01X1357708Y468330D02*
X1362560Y463478D01*
G01X1347975Y460407D02*
Y420658D01*
G01X1349652Y462084D02*
X1347975Y460407D01*
G01X1349652Y465183D02*
Y462084D01*
G01X1398970Y447970D02*
X1405594D01*
G01X1396300Y445300D02*
X1398970Y447970D01*
G01X1379264Y445300D02*
X1396300D01*
G01X1377952Y446612D02*
X1379264Y445300D01*
G01X1377952Y448212D02*
Y446612D01*
G01X1375100Y451064D02*
X1377952Y448212D01*
G01X1375100Y452500D02*
Y451064D01*
G01X1391436Y437000D02*
X1405565D01*
G01X1388688Y439748D02*
X1391436Y437000D01*
G01X1373540Y439748D02*
X1388688D01*
G01X1372248Y441040D02*
X1373540Y439748D01*
G01X1372248Y445352D02*
Y441040D01*
G01X1370100Y447500D02*
X1372248Y445352D01*
G01X1382783Y449817D02*
X1385100Y447500D01*
G01X1382783Y453752D02*
Y449817D01*
G01X1381228Y455308D02*
X1382783Y453752D01*
G01X1367394Y455308D02*
X1381228D01*
G01X1367318Y455232D02*
X1367394Y455308D01*
G01X1364037Y455232D02*
X1367318D01*
G01X1363150Y454345D02*
X1364037Y455232D01*
G01X1363150Y422400D02*
Y454345D01*
G01X1348045Y407295D02*
X1363150Y422400D01*
G01X1381540Y456060D02*
X1385100Y452500D01*
G01X1367082Y456060D02*
X1381540D01*
G01X1367006Y455984D02*
X1367082Y456060D01*
G01X1363725Y455984D02*
X1367006D01*
G01X1362398Y454657D02*
X1363725Y455984D01*
G01X1362398Y422712D02*
Y454657D01*
G01X1347293Y407607D02*
X1362398Y422712D01*
G01X1356960Y424708D02*
X1342037Y409785D01*
G01X1356960Y443389D02*
Y424708D01*
G01X1355943Y444406D02*
X1356960Y443389D01*
G01X1355942Y444406D02*
X1355943D01*
G01X1354946Y445402D02*
X1355942Y444406D01*
G01X1354946Y458540D02*
Y445402D01*
G01X1357811Y461405D02*
X1354946Y458540D01*
G01X1365015Y461405D02*
X1357811D01*
G01X1367065Y463455D02*
X1365015Y461405D01*
G01X1384145Y463455D02*
X1367065D01*
G01X1390100Y457500D02*
X1384145Y463455D01*
G01X1352820Y463698D02*
X1348940Y467578D01*
G01X1352820Y423824D02*
Y463698D01*
G01X1348379Y464508D02*
X1347617Y465270D01*
G01X1348379Y462702D02*
Y464508D01*
G01X1346823Y461146D02*
X1348379Y462702D01*
G01X1346823Y421682D02*
Y461146D01*
G01X1358662Y424003D02*
X1343739Y409080D01*
G01X1358662Y444094D02*
Y424003D01*
G01X1356648Y446108D02*
X1358662Y444094D01*
G01X1356648Y457737D02*
Y446108D01*
G01X1358450Y459539D02*
X1356648Y457737D01*
G01X1365556Y459539D02*
X1358450D01*
G01X1367770Y461753D02*
X1365556Y459539D01*
G01X1383116Y461753D02*
X1367770D01*
G01X1390309Y454560D02*
X1383116Y461753D01*
G01X1391539Y454560D02*
X1390309D01*
G01X1392200Y453899D02*
X1391539Y454560D01*
G01X1392200Y450400D02*
Y453899D01*
G01X1395100Y447500D02*
X1392200Y450400D01*
G01X1388510Y452500D02*
X1390100D01*
G01X1380959Y460051D02*
X1388510Y452500D01*
G01X1368475Y460051D02*
X1380959D01*
G01X1366260Y457836D02*
X1368475Y460051D01*
G01X1362665Y457836D02*
X1366260D01*
G01X1358350Y453521D02*
X1362665Y457836D01*
G01X1358350Y446813D02*
Y453521D01*
G01X1360364Y444799D02*
X1358350Y446813D01*
G01X1360364Y423298D02*
Y444799D01*
G01X1345441Y408375D02*
X1360364Y423298D01*
G01X1399282Y447218D02*
X1405282D01*
G01X1396612Y444548D02*
X1399282Y447218D01*
G01X1378952Y444548D02*
X1396612D01*
G01X1377200Y446300D02*
X1378952Y444548D01*
G01X1377200Y447900D02*
Y446300D01*
G01X1372600Y452500D02*
X1377200Y447900D01*
G01X1370100Y452500D02*
X1372600D01*
G01X1391470Y459680D02*
X1385630Y465520D01*
G01X1399420Y459680D02*
X1391470D01*
G01X1400000Y459100D02*
X1399420Y459680D01*
G01X1400000Y452834D02*
Y459100D01*
G01X1401845Y450989D02*
X1400000Y452834D01*
G01X1405965Y450989D02*
X1401845D01*
G01X1391125Y509953D02*
X1396035Y514863D01*
G01X1391078Y509953D02*
X1391125D01*
G01X1391028Y509903D02*
X1391078Y509953D01*
G01X1378634Y509903D02*
X1391028D01*
G01X1378159Y509428D02*
X1378634Y509903D01*
G01X1370672Y509428D02*
X1378159D01*
G01X1369086Y511014D02*
X1370672Y509428D01*
G01X1355113Y511014D02*
X1369086D01*
G01X1351945Y507846D02*
X1355113Y511014D01*
G01X1351945Y498698D02*
Y507846D01*
G01X1347297Y494050D02*
X1351945Y498698D01*
G01X1353041Y474141D02*
X1354462D01*
G01X1349154Y470254D02*
X1353041Y474141D01*
G01X1344435Y470254D02*
X1349154D01*
G01X1348409Y466426D02*
X1349652Y465183D01*
G01X1342851Y497570D02*
Y499678D01*
G01X1343715Y496706D02*
X1342851Y497570D01*
G01X1345564Y496706D02*
X1343715D01*
G01X1349289Y500431D02*
X1345564Y496706D01*
G01X1349289Y509232D02*
Y500431D01*
G01X1354057Y514000D02*
X1349289Y509232D01*
G01X1370550Y514000D02*
X1354057D01*
G01X1372191Y512359D02*
X1370550Y514000D01*
G01X1388829Y512359D02*
X1372191D01*
G01X1394614Y518144D02*
X1388829Y512359D01*
G01X1400177Y518144D02*
X1394614D01*
G01X1403470Y514851D02*
X1400177Y518144D01*
G01X1410347Y514851D02*
X1403470D01*
G01X1344761Y498282D02*
Y500839D01*
G01X1403977Y511677D02*
X1402950Y510650D01*
G01X1403005Y513147D02*
X1403977Y512175D01*
G01X1401954Y513147D02*
X1403005D01*
G01X1398661Y516440D02*
X1401954Y513147D01*
G01X1395330Y516440D02*
X1398661D01*
G01X1389545Y510655D02*
X1395330Y516440D01*
G01X1371145Y510655D02*
X1389545D01*
G01X1369634Y512166D02*
X1371145Y510655D01*
G01X1355591Y512166D02*
X1369634D01*
G01X1355590Y512167D02*
X1355591Y512166D01*
G01X1354636Y512167D02*
X1355590D01*
G01X1350793Y508324D02*
X1354636Y512167D01*
G01X1350793Y499176D02*
Y508324D01*
G01X1346819Y495202D02*
X1350793Y499176D01*
G01X1394994Y523590D02*
X1390207Y528377D01*
G01X1397216Y523590D02*
X1394994D01*
G01X1404451Y516355D02*
X1397216Y523590D01*
G01X1403400Y514099D02*
X1405178Y512321D01*
G01X1402511Y514099D02*
X1403400D01*
G01X1399218Y517392D02*
X1402511Y514099D01*
G01X1394927Y517392D02*
X1399218D01*
G01X1389141Y511607D02*
X1394927Y517392D01*
G01X1371540Y511607D02*
X1389141D01*
G01X1370029Y513118D02*
X1371540Y511607D01*
G01X1354240Y513118D02*
X1370029D01*
G01X1350041Y508919D02*
X1354240Y513118D01*
G01X1350041Y499707D02*
Y508919D01*
G01X1346288Y495954D02*
X1350041Y499707D01*
G01X1347546Y476897D02*
X1344587D01*
G01X1348133Y471333D02*
X1345182D01*
G01X1350500Y473700D02*
X1348133Y471333D01*
G01X1350500Y475100D02*
Y473700D01*
G01X1397367Y498549D02*
X1441175D01*
G01X1390917Y504999D02*
X1397367Y498549D01*
G01X1380667Y504999D02*
X1390917D01*
G01X1379252Y503584D02*
X1380667Y504999D01*
G01X1360237Y503584D02*
X1379252D01*
G01X1356849Y500196D02*
X1360237Y503584D01*
G01X1356849Y495289D02*
Y500196D01*
G01X1350706Y489146D02*
X1356849Y495289D01*
G01X1400191Y507573D02*
X1406147D01*
G01X1398964Y508800D02*
X1400191Y507573D01*
G01X1391555Y508800D02*
X1398964D01*
G01X1391506Y508751D02*
X1391555Y508800D01*
G01X1379112Y508751D02*
X1391506D01*
G01X1378547Y508186D02*
X1379112Y508751D01*
G01X1374110Y508186D02*
X1378547D01*
G01X1373260Y507336D02*
X1374110Y508186D01*
G01X1358682Y507336D02*
X1373260D01*
G01X1353097Y501751D02*
X1358682Y507336D01*
G01X1353097Y498220D02*
Y501751D01*
G01X1347775Y492898D02*
X1353097Y498220D01*
G01X1396874Y522689D02*
X1403960Y515603D01*
G01X1394713Y522689D02*
X1396874D01*
G01X1389777Y527625D02*
X1394713Y522689D01*
G01X1394129Y529129D02*
X1403027Y520231D01*
G01X1371442Y465520D02*
X1367860Y469102D01*
G01X1385630Y465520D02*
X1371442D01*
G01X1400602Y551526D02*
X1409427Y542701D01*
G01X1389975Y551526D02*
X1400602D01*
G01X1387439Y548990D02*
X1389975Y551526D01*
G01X1382450Y548990D02*
X1387439D01*
G01X1381553Y548093D02*
X1382450Y548990D01*
G01X1369124Y548093D02*
X1381553D01*
G01X1367358Y546327D02*
X1369124Y548093D01*
G01X1354043Y546327D02*
X1367358D01*
G01X1350096Y542380D02*
X1354043Y546327D01*
G01X1398018Y568136D02*
X1436364D01*
G01X1384928Y555046D02*
X1398018Y568136D01*
G01X1379586Y555046D02*
X1384928D01*
G01X1378749Y554209D02*
X1379586Y555046D01*
G01X1374574Y554209D02*
X1378749D01*
G01X1371460Y557323D02*
X1374574Y554209D01*
G01X1356309Y557323D02*
X1371460D01*
G01X1347638Y548652D02*
X1356309Y557323D01*
G01X1357402Y555219D02*
X1348547Y546364D01*
G01X1370587Y555219D02*
X1357402D01*
G01X1373701Y552105D02*
X1370587Y555219D01*
G01X1379622Y552105D02*
X1373701D01*
G01X1380459Y552942D02*
X1379622Y552105D01*
G01X1385801Y552942D02*
X1380459D01*
G01X1398811Y565952D02*
X1385801Y552942D01*
G01X1434512Y565952D02*
X1398811D01*
G01X1398343Y566904D02*
X1434907D01*
G01X1387942Y556503D02*
X1398343Y566904D01*
G01X1387942Y556430D02*
Y556503D01*
G01X1385406Y553894D02*
X1387942Y556430D01*
G01X1380064Y553894D02*
X1385406D01*
G01X1379227Y553057D02*
X1380064Y553894D01*
G01X1374096Y553057D02*
X1379227D01*
G01X1370982Y556171D02*
X1374096Y553057D01*
G01X1357007Y556171D02*
X1370982D01*
G01X1348152Y547316D02*
X1357007Y556171D01*
G01X1384192Y618474D02*
X1381903Y620763D01*
G01X1388517Y618474D02*
X1384192D01*
G01X1392680Y614311D02*
X1388517Y618474D01*
G01X1392680Y605152D02*
Y614311D01*
G01X1401232Y596600D02*
X1392680Y605152D01*
G01X1409529Y596600D02*
X1401232D01*
G01X1400704Y595000D02*
X1409001D01*
G01X1391176Y604528D02*
X1400704Y595000D01*
G01X1391176Y607877D02*
Y604528D01*
G01X1380905Y618148D02*
X1391176Y607877D01*
G01X1373596Y618148D02*
X1380905D01*
G01X1372872Y617424D02*
X1373596Y618148D01*
G01X1400968Y595800D02*
X1409265D01*
G01X1391928Y604840D02*
X1400968Y595800D01*
G01X1391928Y613463D02*
Y604840D01*
G01X1387992Y617399D02*
X1391928Y613463D01*
G01X1383768Y617399D02*
X1387992D01*
G01X1381429Y619738D02*
X1383768Y617399D01*
G01X1441309Y17063D02*
X1468399D01*
G01X1436963Y21409D02*
X1441309Y17063D01*
G01X1436683Y21409D02*
X1436963D01*
G01X1428897Y29195D02*
X1436683Y21409D01*
G01X1428897Y36095D02*
Y29195D01*
G01X1441933Y18567D02*
X1485539D01*
G01X1430819Y29681D02*
X1441933Y18567D01*
G01X1430819Y37469D02*
Y29681D01*
G01X1430055Y29381D02*
Y37169D01*
G01X1441621Y17815D02*
X1430055Y29381D01*
G01X1469381Y17815D02*
X1441621D01*
G01X1446816Y-523D02*
X1430125Y16168D01*
G01X1446816Y-17505D02*
Y-523D01*
G01X1450957Y-21646D02*
X1446816Y-17505D01*
G01X1675098Y-21646D02*
X1450957D01*
G01X1427489Y28611D02*
Y36679D01*
G01X1440445Y15655D02*
X1427489Y28611D01*
G01X1467815Y15655D02*
X1440445D01*
G01X1435807Y28891D02*
Y38179D01*
G01X1444227Y20471D02*
X1435807Y28891D01*
G01X1486329Y20471D02*
X1444227D01*
G01X1434294Y27706D02*
Y37624D01*
G01X1442681Y19319D02*
X1434294Y27706D01*
G01X1485851Y19319D02*
X1442681D01*
G01X1451435Y-20494D02*
X1673104D01*
G01X1447968Y-17027D02*
X1451435Y-20494D01*
G01X1447968Y-45D02*
Y-17027D01*
G01X1430537Y17386D02*
X1447968Y-45D01*
G01X1421167Y86834D02*
X1410562Y97439D01*
G01X1421167Y77384D02*
Y86834D01*
G01X1425081Y73470D02*
X1421167Y77384D01*
G01X1425081Y48412D02*
Y73470D01*
G01X1428898Y36096D02*
X1428897Y36095D01*
G01X1428898Y37262D02*
Y36096D01*
G01X1426052Y40108D02*
X1428898Y37262D01*
G01X1419392Y40108D02*
X1426052D01*
G01X1415200Y44300D02*
X1419392Y40108D01*
G01X1415200Y50208D02*
Y44300D01*
G01X1419029Y54037D02*
X1415200Y50208D01*
G01X1419029Y72611D02*
Y54037D01*
G01X1416059Y75581D02*
X1419029Y72611D01*
G01X1416059Y81691D02*
Y75581D01*
G01X1411727Y86023D02*
X1416059Y81691D01*
G01X1420718Y47570D02*
X1430819Y37469D01*
G01X1420718Y73390D02*
Y47570D01*
G01X1417613Y76495D02*
X1420718Y73390D01*
G01X1417613Y82613D02*
Y76495D01*
G01X1412554Y87672D02*
X1417613Y82613D01*
G01X1416861Y82301D02*
X1412248Y86914D01*
G01X1416861Y76183D02*
Y82301D01*
G01X1419966Y73078D02*
X1416861Y76183D01*
G01X1419966Y53666D02*
Y73078D01*
G01X1418500Y52200D02*
X1419966Y53666D01*
G01X1418500Y44100D02*
Y52200D01*
G01X1421600Y41000D02*
X1418500Y44100D01*
G01X1426224Y41000D02*
X1421600D01*
G01X1430055Y37169D02*
X1426224Y41000D01*
G01X1414651Y81107D02*
X1410486Y85272D01*
G01X1414651Y74997D02*
Y81107D01*
G01X1414760Y74888D02*
X1414651Y74997D01*
G01X1414760Y74881D02*
Y74888D01*
G01X1417341Y72300D02*
X1414760Y74881D01*
G01X1417341Y54341D02*
Y72300D01*
G01X1413792Y50792D02*
X1417341Y54341D01*
G01X1413792Y43716D02*
Y50792D01*
G01X1418809Y38699D02*
X1413792Y43716D01*
G01X1419975Y38699D02*
X1418809D01*
G01X1419976Y38700D02*
X1419975Y38699D01*
G01X1425468Y38700D02*
X1419976D01*
G01X1427489Y36679D02*
X1425468Y38700D01*
G01X1419611Y86749D02*
X1409310Y97050D01*
G01X1419611Y77209D02*
Y86749D01*
G01X1422622Y74198D02*
X1419611Y77209D01*
G01X1422622Y48396D02*
Y74198D01*
G01X1424356Y46662D02*
X1422622Y48396D01*
G01X1427324Y46662D02*
X1424356D01*
G01X1435807Y38179D02*
X1427324Y46662D01*
G01X1418366Y82924D02*
X1412866Y88424D01*
G01X1418366Y82302D02*
Y82924D01*
G01X1418365Y82301D02*
X1418366Y82302D01*
G01X1418365Y76807D02*
Y82301D01*
G01X1421470Y73702D02*
X1418365Y76807D01*
G01X1421470Y47918D02*
Y73702D01*
G01X1423878Y45510D02*
X1421470Y47918D01*
G01X1426408Y45510D02*
X1423878D01*
G01X1434294Y37624D02*
X1426408Y45510D01*
G01X1410562Y97439D02*
Y118172D01*
G01X1404577Y104536D02*
Y111994D01*
G01X1403659Y104682D02*
Y111041D01*
G01X1404853Y120776D02*
X1404253D01*
G01X1405776Y119853D02*
X1404853Y120776D01*
G01X1405776Y119253D02*
Y119853D01*
G01X1406199Y118830D02*
X1405776Y119253D01*
G01X1406199Y116600D02*
Y118830D01*
G01X1408082Y114717D02*
X1406199Y116600D01*
G01X1408082Y103602D02*
Y114717D01*
G01X1404200Y116969D02*
Y119200D01*
G01X1406558Y114611D02*
X1404200Y116969D01*
G01X1406558Y103823D02*
Y114611D01*
G01X1405606Y104218D02*
Y113194D01*
G01X1455361Y211440D02*
Y244891D01*
G01X1464416Y202385D02*
X1455361Y211440D01*
G01X1464416Y189195D02*
Y202385D01*
G01X1468941Y184670D02*
X1464416Y189195D01*
G01X1406953Y208319D02*
Y220539D01*
G01X1463664Y188883D02*
X1468051Y184496D01*
G01X1463664Y193268D02*
Y188883D01*
G01X1451287Y205645D02*
X1463664Y193268D01*
G01X1447999Y205645D02*
X1451287D01*
G01X1465169Y189506D02*
X1469693Y184982D01*
G01X1465169Y203222D02*
Y189506D01*
G01X1456113Y212278D02*
X1465169Y203222D01*
G01X1456113Y245203D02*
Y212278D01*
G01X1458856Y192430D02*
X1458569Y192143D01*
G01X1458856Y195544D02*
Y192430D01*
G01X1450346Y204054D02*
X1458856Y195544D01*
G01X1448914Y204054D02*
X1450346D01*
G01X1448764Y203904D02*
X1448914Y204054D01*
G01X1446609Y203904D02*
X1448764D01*
G01X1446016Y204497D02*
X1446609Y203904D01*
G01X1446016Y206116D02*
Y204497D01*
G01X1453500Y213600D02*
X1446016Y206116D01*
G01X1453500Y242534D02*
Y213600D01*
G01X1439700Y252300D02*
Y253100D01*
G01X1445384Y246616D02*
X1439700Y252300D01*
G01X1453636Y246616D02*
X1445384D01*
G01X1455361Y244891D02*
X1453636Y246616D01*
G01X1405340Y247586D02*
X1407274Y245652D01*
G01X1405340Y254526D02*
Y247586D01*
G01X1464090Y265983D02*
X1465561Y267454D01*
G01X1464090Y264278D02*
Y265983D01*
G01X1465084Y263284D02*
X1464090Y264278D01*
G01X1468016Y263284D02*
X1465084D01*
G01X1440833Y268984D02*
X1442303Y270454D01*
G01X1440833Y266683D02*
Y268984D01*
G01X1444536Y262980D02*
X1440833Y266683D01*
G01X1444536Y257807D02*
Y262980D01*
G01X1451268Y251075D02*
X1444536Y257807D01*
G01X1452514Y251075D02*
X1451268D01*
G01X1452515Y251076D02*
X1452514Y251075D01*
G01X1457025Y251076D02*
X1452515D01*
G01X1460101Y248000D02*
X1457025Y251076D01*
G01X1464691Y248000D02*
X1460101D01*
G01X1466404Y246287D02*
X1464691Y248000D01*
G01X1406625Y250114D02*
Y254872D01*
G01X1408546Y248193D02*
X1406625Y250114D01*
G01X1409512Y243648D02*
X1408546Y248193D01*
G01X1409512Y240636D02*
Y243648D01*
G01X1410175Y239973D02*
X1409512Y240636D01*
G01X1410175Y225545D02*
Y239973D01*
G01X1408057Y223427D02*
X1410175Y225545D01*
G01X1408057Y221643D02*
Y223427D01*
G01X1406953Y220539D02*
X1408057Y221643D01*
G01X1464101Y258200D02*
X1465629D01*
G01X1459178Y263123D02*
X1464101Y258200D01*
G01X1459178Y265885D02*
Y263123D01*
G01X1460573Y267280D02*
X1459178Y265885D01*
G01X1462875Y267280D02*
X1460573D01*
G01X1463656Y268061D02*
X1462875Y267280D01*
G01X1463656Y271572D02*
Y268061D01*
G01X1462672Y272556D02*
X1463656Y271572D01*
G01X1462672Y303628D02*
Y272556D01*
G01X1453922Y247394D02*
X1456113Y245203D01*
G01X1445855Y247394D02*
X1453922D01*
G01X1441276Y251973D02*
X1445855Y247394D01*
G01X1441276Y254125D02*
Y251973D01*
G01X1440001Y255400D02*
X1441276Y254125D01*
G01X1438500Y255400D02*
X1440001D01*
G01X1404504Y230004D02*
Y244302D01*
G01X1464413Y252894D02*
X1465063Y253544D01*
G01X1461676Y252894D02*
X1464413D01*
G01X1461128Y253442D02*
X1461676Y252894D01*
G01X1461128Y258920D02*
Y253442D01*
G01X1457449Y262599D02*
X1461128Y258920D01*
G01X1457449Y267395D02*
Y262599D01*
G01X1459572Y269518D02*
X1457449Y267395D01*
G01X1459572Y271011D02*
Y269518D01*
G01X1458711Y271872D02*
X1459572Y271011D01*
G01X1457704Y271872D02*
X1458711D01*
G01X1456372Y273204D02*
X1457704Y271872D01*
G01X1456372Y309927D02*
Y273204D01*
G01X1438301Y258300D02*
X1437800D01*
G01X1442028Y254573D02*
X1438301Y258300D01*
G01X1442028Y252399D02*
Y254573D01*
G01X1446281Y248146D02*
X1442028Y252399D01*
G01X1449207Y248146D02*
X1446281D01*
G01X1449208Y248147D02*
X1449207Y248146D01*
G01X1455463Y248147D02*
X1449208D01*
G01X1459913Y243697D02*
X1455463Y248147D01*
G01X1459913Y228243D02*
Y243697D01*
G01X1465921Y222235D02*
X1459913Y228243D01*
G01X1459600Y273126D02*
Y308778D01*
G01X1460856Y271870D02*
X1459600Y273126D01*
G01X1461909Y271870D02*
X1460856D01*
G01X1462770Y271009D02*
X1461909Y271870D01*
G01X1462770Y269594D02*
Y271009D01*
G01X1461569Y268393D02*
X1462770Y269594D01*
G01X1460167Y268393D02*
X1461569D01*
G01X1458338Y266564D02*
X1460167Y268393D01*
G01X1458338Y262774D02*
Y266564D01*
G01X1464700Y256412D02*
X1458338Y262774D01*
G01X1464700Y256100D02*
Y256412D01*
G01X1462224Y251252D02*
X1469356D01*
G01X1460376Y253100D02*
X1462224Y251252D01*
G01X1460376Y258608D02*
Y253100D01*
G01X1456678Y262306D02*
X1460376Y258608D01*
G01X1456678Y269722D02*
Y262306D01*
G01X1456600Y269800D02*
X1456678Y269722D01*
G01X1456600Y270835D02*
Y269800D01*
G01X1455511Y271924D02*
X1456600Y270835D01*
G01X1454502Y271924D02*
X1455511D01*
G01X1453300Y273126D02*
X1454502Y271924D01*
G01X1453300Y287804D02*
Y273126D01*
G01X1452728Y243306D02*
X1453500Y242534D01*
G01X1440113Y269328D02*
Y289599D01*
G01X1440081Y269296D02*
X1440113Y269328D01*
G01X1440081Y266371D02*
Y269296D01*
G01X1440113Y266339D02*
X1440081Y266371D01*
G01X1440113Y266216D02*
Y266339D01*
G01X1443784Y262545D02*
X1440113Y266216D01*
G01X1443784Y252613D02*
Y262545D01*
G01X1446373Y250024D02*
X1443784Y252613D01*
G01X1448403Y250024D02*
X1446373D01*
G01X1448430Y250051D02*
X1448403Y250024D01*
G01X1456986Y250051D02*
X1448430D01*
G01X1460037Y247000D02*
X1456986Y250051D01*
G01X1463286Y247000D02*
X1460037D01*
G01X1464626Y245660D02*
X1463286Y247000D01*
G01X1464626Y244373D02*
Y245660D01*
G01X1473499Y235500D02*
X1464626Y244373D01*
G01X1465021Y259000D02*
X1465893D01*
G01X1459930Y264091D02*
X1465021Y259000D01*
G01X1459930Y265309D02*
Y264091D01*
G01X1460791Y266170D02*
X1459930Y265309D01*
G01X1462984Y266170D02*
X1460791D01*
G01X1464662Y267848D02*
X1462984Y266170D01*
G01X1464662Y270567D02*
Y267848D01*
G01X1465894Y271799D02*
X1464662Y270567D01*
G01X1450283Y272994D02*
Y291193D01*
G01X1451353Y271924D02*
X1450283Y272994D01*
G01X1452362Y271924D02*
X1451353D01*
G01X1453223Y271063D02*
X1452362Y271924D01*
G01X1453223Y269491D02*
Y271063D01*
G01X1455926Y266788D02*
X1453223Y269491D01*
G01X1455926Y261994D02*
Y266788D01*
G01X1457176Y260744D02*
X1455926Y261994D01*
G01X1457176Y254277D02*
Y260744D01*
G01X1461197Y250256D02*
X1457176Y254277D01*
G01X1465627Y250256D02*
X1461197D01*
G01X1445454Y272615D02*
Y273603D01*
G01X1446924Y271145D02*
X1445454Y272615D01*
G01X1446924Y263116D02*
Y271145D01*
G01X1450624Y259416D02*
X1446924Y263116D01*
G01X1450624Y253847D02*
Y259416D01*
G01X1451891Y252580D02*
X1450624Y253847D01*
G01X1457721Y252580D02*
X1451891D01*
G01X1460797Y249504D02*
X1457721Y252580D01*
G01X1465315Y249504D02*
X1460797D01*
G01X1465319Y249500D02*
X1465315Y249504D01*
G01X1447133Y272994D02*
Y289960D01*
G01X1448203Y271924D02*
X1447133Y272994D01*
G01X1449212Y271924D02*
X1448203D01*
G01X1450086Y271050D02*
X1449212Y271924D01*
G01X1450086Y261414D02*
Y271050D01*
G01X1452200Y259300D02*
X1450086Y261414D01*
G01X1452200Y254500D02*
Y259300D01*
G01X1463568Y262532D02*
X1461400Y264700D01*
G01X1467704Y262532D02*
X1463568D01*
G01X1404110Y246326D02*
Y253590D01*
G01X1405656Y244780D02*
X1404110Y246326D01*
G01X1405656Y229526D02*
Y244780D01*
G01X1443984Y264992D02*
Y289960D01*
G01X1445288Y263688D02*
X1443984Y264992D01*
G01X1445288Y258119D02*
Y263688D01*
G01X1451580Y251827D02*
X1445288Y258119D01*
G01X1452202Y251827D02*
X1451580D01*
G01X1452203Y251828D02*
X1452202Y251827D01*
G01X1457373Y251828D02*
X1452203D01*
G01X1460449Y248752D02*
X1457373Y251828D01*
G01X1465003Y248752D02*
X1460449D01*
G01X1465007Y248748D02*
X1465003Y248752D01*
G01X1466543Y248748D02*
X1465007D01*
G01X1408250Y333000D02*
X1404912D01*
G01X1466684Y318255D02*
X1463610Y321329D01*
G01X1410512Y340392D02*
X1409108Y341796D01*
G01X1410512Y338011D02*
Y340392D01*
G01X1410489Y337988D02*
X1410512Y338011D01*
G01X1410190Y334594D02*
X1408348Y336436D01*
G01X1410190Y331935D02*
Y334594D01*
G01X1404730Y326475D02*
X1410190Y331935D01*
G01X1404730Y317000D02*
Y326475D01*
G01X1405000Y291210D02*
Y297571D01*
G01X1461202Y305098D02*
X1462672Y303628D01*
G01X1454902Y311397D02*
X1456372Y309927D01*
G01X1456400Y313048D02*
X1454902Y314546D01*
G01X1456400Y310970D02*
Y313048D01*
G01X1457443Y309927D02*
X1456400Y310970D01*
G01X1458451Y309927D02*
X1457443D01*
G01X1459600Y308778D02*
X1458451Y309927D01*
G01X1440910Y317190D02*
Y316693D01*
G01X1441000Y317280D02*
X1440910Y317190D01*
G01X1441000Y318000D02*
Y317280D01*
G01X1439350Y319650D02*
X1441000Y318000D01*
G01X1439350Y350332D02*
Y319650D01*
G01X1459980Y330000D02*
X1469502D01*
G01X1450571Y320591D02*
X1459980Y330000D01*
G01X1449190Y320591D02*
X1450571D01*
G01X1447124Y318525D02*
X1449190Y320591D01*
G01X1447124Y316793D02*
Y318525D01*
G01X1445998Y315667D02*
X1447124Y316793D01*
G01X1445998Y313939D02*
Y315667D01*
G01X1447124Y312813D02*
X1445998Y313939D01*
G01X1447124Y303618D02*
Y312813D01*
G01X1445454Y301948D02*
X1447124Y303618D01*
G01X1447133Y300477D02*
X1445454Y298798D01*
G01X1447133Y302557D02*
Y300477D01*
G01X1448204Y303628D02*
X1447133Y302557D01*
G01X1449212Y303628D02*
X1448204D01*
G01X1450073Y304489D02*
X1449212Y303628D01*
G01X1450073Y312006D02*
Y304489D01*
G01X1449212Y312867D02*
X1450073Y312006D01*
G01X1448203Y312867D02*
X1449212D01*
G01X1447133Y313937D02*
X1448203Y312867D01*
G01X1447133Y315155D02*
Y313937D01*
G01X1448204Y316226D02*
X1447133Y315155D01*
G01X1449212Y316226D02*
X1448204D01*
G01X1450146Y317160D02*
X1449212Y316226D01*
G01X1450146Y318168D02*
Y317160D01*
G01X1460978Y329000D02*
X1450146Y318168D01*
G01X1470731Y329000D02*
X1460978D01*
G01X1460176Y346096D02*
X1469731Y336541D01*
G01X1451753Y289351D02*
X1453300Y287804D01*
G01X1443880Y309821D02*
X1442304Y311397D01*
G01X1443880Y291780D02*
Y309821D01*
G01X1443086Y290986D02*
X1443880Y291780D01*
G01X1441500Y290986D02*
X1443086D01*
G01X1440113Y289599D02*
X1441500Y290986D01*
G01X1464351Y301948D02*
X1465894Y300405D01*
G01X1453432Y297328D02*
X1454902Y298798D01*
G01X1453432Y294342D02*
Y297328D01*
G01X1450283Y291193D02*
X1453432Y294342D01*
G01X1449697Y313452D02*
X1448603Y314546D01*
G01X1449711Y313452D02*
X1449697D01*
G01X1450296Y312867D02*
X1449711Y313452D01*
G01X1452362Y312867D02*
X1450296D01*
G01X1453223Y312006D02*
X1452362Y312867D01*
G01X1453223Y304489D02*
Y312006D01*
G01X1452362Y303628D02*
X1453223Y304489D01*
G01X1451000Y303628D02*
X1452362D01*
G01X1450073Y302701D02*
X1451000Y303628D01*
G01X1450073Y292900D02*
Y302701D01*
G01X1447133Y289960D02*
X1450073Y292900D01*
G01X1447107Y297302D02*
X1448603Y298798D01*
G01X1447107Y291865D02*
Y297302D01*
G01X1446063Y290821D02*
X1447107Y291865D01*
G01X1444845Y290821D02*
X1446063D01*
G01X1443984Y289960D02*
X1444845Y290821D01*
G01X1464160Y363840D02*
X1466620Y361380D01*
G01X1461370Y363840D02*
X1464160D01*
G01X1459160Y361630D02*
X1461370Y363840D01*
G01X1459160Y359160D02*
Y361630D01*
G01X1457374Y357374D02*
X1459160Y359160D01*
G01X1457374Y355747D02*
Y357374D01*
G01X1457848Y355273D02*
X1457374Y355747D01*
G01X1457848Y352259D02*
Y355273D01*
G01X1459459Y350648D02*
X1457848Y352259D01*
G01X1471175Y350648D02*
X1459459D01*
G01X1464150Y344250D02*
X1471553D01*
G01X1460800Y347600D02*
X1464150Y344250D01*
G01X1458251Y347600D02*
X1460800D01*
G01X1453900Y351951D02*
X1458251Y347600D01*
G01X1453900Y353350D02*
Y351951D01*
G01X1464523Y366293D02*
X1466417Y368187D01*
G01X1462434Y366293D02*
X1464523D01*
G01X1458328Y362187D02*
X1462434Y366293D01*
G01X1458328Y359735D02*
Y362187D01*
G01X1456622Y358029D02*
X1458328Y359735D01*
G01X1456622Y355334D02*
Y358029D01*
G01X1456980Y354976D02*
X1456622Y355334D01*
G01X1456980Y352063D02*
Y354976D01*
G01X1459147Y349896D02*
X1456980Y352063D01*
G01X1470603Y349896D02*
X1459147D01*
G01X1459111Y354946D02*
Y356353D01*
G01X1458824Y354659D02*
X1459111Y354946D01*
G01X1458824Y352347D02*
Y354659D01*
G01X1459771Y351400D02*
X1458824Y352347D01*
G01X1471487Y351400D02*
X1459771D01*
G01X1462900Y352200D02*
X1471751D01*
G01X1462100Y353000D02*
X1462900Y352200D01*
G01X1460400Y353000D02*
X1462100D01*
G01X1463217Y369445D02*
X1466727D01*
G01X1457576Y363804D02*
X1463217Y369445D01*
G01X1457576Y360047D02*
Y363804D01*
G01X1455870Y358341D02*
X1457576Y360047D01*
G01X1455870Y354814D02*
Y358341D01*
G01X1456228Y354456D02*
X1455870Y354814D01*
G01X1456228Y351751D02*
Y354456D01*
G01X1458835Y349144D02*
X1456228Y351751D01*
G01X1470057Y349144D02*
X1458835D01*
G01X1444876Y355858D02*
X1439350Y350332D01*
G01X1444876Y359335D02*
Y355858D01*
G01X1452940Y367399D02*
X1444876Y359335D01*
G01X1452940Y394990D02*
Y367399D01*
G01X1458550Y400600D02*
X1452940Y394990D01*
G01X1471910Y400600D02*
X1458550D01*
G01X1457438Y346096D02*
X1460176D01*
G01X1452385Y351149D02*
X1457438Y346096D01*
G01X1450938Y351149D02*
X1452385D01*
G01X1447924Y354163D02*
X1450938Y351149D01*
G01X1447924Y356224D02*
Y354163D01*
G01X1462400Y370700D02*
X1447924Y356224D01*
G01X1466918Y370700D02*
X1462400D01*
G01X1462042Y347426D02*
X1470505D01*
G01X1461076Y348392D02*
X1462042Y347426D01*
G01X1458523Y348392D02*
X1461076D01*
G01X1455476Y351439D02*
X1458523Y348392D01*
G01X1455476Y354003D02*
Y351439D01*
G01X1453251Y356228D02*
X1455476Y354003D01*
G01X1453251Y356676D02*
Y356228D01*
G01X1453464Y360700D02*
X1456000D01*
G01X1451453Y358689D02*
X1453464Y360700D01*
G01X1451453Y355748D02*
Y358689D01*
G01X1452050Y355151D02*
X1451453Y355748D01*
G01X1452050Y352548D02*
Y355151D01*
G01X1457750Y346848D02*
X1452050Y352548D01*
G01X1460488Y346848D02*
X1457750D01*
G01X1470483Y336853D02*
X1460488Y346848D01*
G01X1404977Y437752D02*
X1408225Y441000D01*
G01X1410019Y443545D02*
X1412375D01*
G01X1405594Y447970D02*
X1410019Y443545D01*
G01X1407958Y438500D02*
X1408225Y438233D01*
G01X1407065Y438500D02*
X1407958D01*
G01X1405565Y437000D02*
X1407065Y438500D01*
G01X1411752Y440748D02*
X1412484D01*
G01X1405282Y447218D02*
X1411752Y440748D01*
G01X1409687Y447267D02*
X1405965Y450989D01*
G01X1414107Y447267D02*
X1409687D01*
G01X1463770Y496185D02*
X1466851Y493104D01*
G01X1463770Y504154D02*
Y496185D01*
G01X1430524Y537400D02*
X1463770Y504154D01*
G01X1416248Y508950D02*
X1410347Y514851D01*
G01X1441451Y508950D02*
X1416248D01*
G01X1454628Y495773D02*
X1441451Y508950D01*
G01X1454628Y495159D02*
Y495773D01*
G01X1458950Y490837D02*
X1454628Y495159D01*
G01X1458950Y486602D02*
Y490837D01*
G01X1460661Y484891D02*
X1458950Y486602D01*
G01X1403977Y512175D02*
Y511677D01*
G01X1410971Y516355D02*
X1404451D01*
G01X1415204Y512122D02*
X1410971Y516355D01*
G01X1442600Y512122D02*
X1415204D01*
G01X1450321Y504401D02*
X1442600Y512122D01*
G01X1453500Y504401D02*
X1450321D01*
G01X1458060Y499841D02*
X1453500Y504401D01*
G01X1458060Y495020D02*
Y499841D01*
G01X1405178Y511422D02*
X1405950Y510650D01*
G01X1405178Y512321D02*
Y511422D01*
G01X1464522Y508841D02*
X1464553Y508872D01*
G01X1464522Y496497D02*
Y508841D01*
G01X1467808Y493211D02*
X1464522Y496497D01*
G01X1460400Y520400D02*
X1467190Y513610D01*
G01X1458800Y520400D02*
X1460400D01*
G01X1456781Y522419D02*
X1458800Y520400D01*
G01X1456781Y539781D02*
Y522419D01*
G01X1459000Y475800D02*
X1470664Y464136D01*
G01X1452602Y475800D02*
X1459000D01*
G01X1446101Y482301D02*
X1452602Y475800D01*
G01X1446101Y486213D02*
Y482301D01*
G01X1447328Y487440D02*
X1446101Y486213D01*
G01X1447328Y492396D02*
Y487440D01*
G01X1441175Y498549D02*
X1447328Y492396D01*
G01X1458683Y478749D02*
X1472700Y464732D01*
G01X1456719Y478749D02*
X1458683D01*
G01X1452305Y483163D02*
X1456719Y478749D01*
G01X1452305Y487223D02*
Y483163D01*
G01X1452188Y487223D02*
X1452305D01*
G01X1451621Y493945D02*
X1456590Y488976D01*
G01X1451621Y496086D02*
Y493945D01*
G01X1442574Y505133D02*
X1451621Y496086D01*
G01X1408587Y505133D02*
X1442574D01*
G01X1406147Y507573D02*
X1408587Y505133D01*
G01X1455739Y522397D02*
Y542510D01*
G01X1458488Y519648D02*
X1455739Y522397D01*
G01X1459490Y519648D02*
X1458488D01*
G01X1466430Y512708D02*
X1459490Y519648D01*
G01X1461061Y489790D02*
X1461267D01*
G01X1456484Y494367D02*
X1461061Y489790D01*
G01X1456484Y496133D02*
Y494367D01*
G01X1441717Y510900D02*
X1456484Y496133D01*
G01X1415362Y510900D02*
X1441717D01*
G01X1410659Y515603D02*
X1415362Y510900D01*
G01X1403960Y515603D02*
X1410659D01*
G01X1463018Y495873D02*
X1466099Y492792D01*
G01X1463018Y502854D02*
Y495873D01*
G01X1440730Y525142D02*
X1463018Y502854D01*
G01X1436358Y525142D02*
X1440730D01*
G01X1408649Y512751D02*
X1407884D01*
G01X1414900Y506500D02*
X1408649Y512751D01*
G01X1442837Y506500D02*
X1414900D01*
G01X1453613Y495724D02*
X1442837Y506500D01*
G01X1453613Y494737D02*
Y495724D01*
G01X1458166Y490184D02*
X1453613Y494737D01*
G01X1458166Y487428D02*
Y490184D01*
G01X1456602Y485864D02*
X1458166Y487428D01*
G01X1465346Y484554D02*
X1479650Y470250D01*
G01X1462266Y495561D02*
X1465346Y492481D01*
G01X1462266Y502542D02*
Y495561D01*
G01X1443278Y521530D02*
X1462266Y502542D01*
G01X1431690Y521530D02*
X1443278D01*
G01X1424900Y537400D02*
X1430524D01*
G01X1419599Y542701D02*
X1424900Y537400D01*
G01X1409427Y542701D02*
X1419599D01*
G01X1457529Y572100D02*
X1466864Y581435D01*
G01X1452250Y572100D02*
X1457529D01*
G01X1451150Y573200D02*
X1452250Y572100D01*
G01X1441409Y563091D02*
Y561117D01*
G01X1436364Y568136D02*
X1441409Y563091D01*
G01X1457824Y571048D02*
X1467459Y580683D01*
G01X1452298Y571048D02*
X1457824D01*
G01X1451150Y569900D02*
X1452298Y571048D01*
G01X1438336Y562128D02*
X1434512Y565952D01*
G01X1438336Y559201D02*
Y562128D01*
G01X1442731Y554806D02*
X1438336Y559201D01*
G01X1453406Y554806D02*
X1442731D01*
G01X1463100Y564500D02*
X1453406Y554806D01*
G01X1463100Y573303D02*
Y564500D01*
G01X1468370Y578573D02*
X1463100Y573303D01*
G01X1461000Y544000D02*
X1456781Y539781D01*
G01X1461000Y554400D02*
Y544000D01*
G01X1465840Y559240D02*
X1461000Y554400D01*
G01X1462148Y573698D02*
X1467975Y579525D01*
G01X1462148Y564895D02*
Y573698D01*
G01X1453011Y555758D02*
X1462148Y564895D01*
G01X1443126Y555758D02*
X1453011D01*
G01X1439288Y559596D02*
X1443126Y555758D01*
G01X1439288Y561733D02*
Y559596D01*
G01X1439289Y561734D02*
X1439288Y561733D01*
G01X1439289Y562522D02*
Y561734D01*
G01X1434907Y566904D02*
X1439289Y562522D01*
G01X1465160Y572230D02*
X1466431D01*
G01X1464124Y571194D02*
X1465160Y572230D01*
G01X1464124Y564935D02*
Y571194D01*
G01X1465070Y563989D02*
X1464124Y564935D01*
G01X1465070Y560889D02*
Y563989D01*
G01X1458701Y554520D02*
X1465070Y560889D01*
G01X1458701Y545472D02*
Y554520D01*
G01X1455739Y542510D02*
X1458701Y545472D01*
G01X1412000Y594129D02*
X1409529Y596600D01*
G01X1426239Y594129D02*
X1412000D01*
G01X1434500Y602390D02*
X1426239Y594129D01*
G01X1434500Y604000D02*
Y602390D01*
G01X1435858Y605358D02*
X1434500Y604000D01*
G01X1435858Y617467D02*
Y605358D01*
G01X1438758Y620367D02*
X1435858Y617467D01*
G01X1461020Y620367D02*
X1438758D01*
G01X1465055Y624402D02*
X1461020Y620367D01*
G01X1545556Y624402D02*
X1465055D01*
G01X1462145Y618445D02*
X1466598Y622898D01*
G01X1449128Y618445D02*
X1462145D01*
G01X1437824Y607141D02*
X1449128Y618445D01*
G01X1437824Y603586D02*
Y607141D01*
G01X1426863Y592625D02*
X1437824Y603586D01*
G01X1411376Y592625D02*
X1426863D01*
G01X1409001Y595000D02*
X1411376Y592625D01*
G01X1461415Y619415D02*
X1465650Y623650D01*
G01X1439305Y619415D02*
X1461415D01*
G01X1436883Y616993D02*
X1439305Y619415D01*
G01X1436883Y603709D02*
Y616993D01*
G01X1426551Y593377D02*
X1436883Y603709D01*
G01X1411688Y593377D02*
X1426551D01*
G01X1409265Y595800D02*
X1411688Y593377D01*
G01X1480841Y8990D02*
X1485242Y4589D01*
G01X1476530Y8990D02*
X1480841D01*
G01X1469077Y16443D02*
X1476530Y8990D01*
G01X1469019Y16443D02*
X1469077D01*
G01X1468399Y17063D02*
X1469019Y16443D01*
G01X1501900Y-7700D02*
Y-9124D01*
G01X1495583Y-1383D02*
X1501900Y-7700D01*
G01X1495583Y8523D02*
Y-1383D01*
G01X1485539Y18567D02*
X1495583Y8523D01*
G01X1477454Y9742D02*
X1469381Y17815D01*
G01X1484257Y9742D02*
X1477454D01*
G01X1486992Y7007D02*
X1484257Y9742D01*
G01X1486992Y3049D02*
Y7007D01*
G01X1488434Y1607D02*
X1486992Y3049D01*
G01X1491193Y1607D02*
X1488434D01*
G01X1499682Y-6882D02*
X1491193Y1607D01*
G01X1499682Y-10430D02*
Y-6882D01*
G01X1500058Y-10806D02*
X1499682Y-10430D01*
G01X1523334Y-10806D02*
X1500058D01*
G01X1523335Y-10805D02*
X1523334Y-10806D01*
G01X1523665Y-10805D02*
X1523335D01*
G01X1523666Y-10806D02*
X1523665Y-10805D01*
G01X1524288Y-10806D02*
X1523666D01*
G01X1524290Y-10804D02*
X1524288Y-10806D01*
G01X1546758Y-10804D02*
X1524290D01*
G01X1487200Y-3730D02*
X1467815Y15655D01*
G01X1487200Y-6800D02*
Y-3730D01*
G01X1490600Y-10200D02*
X1487200Y-6800D01*
G01X1496600Y-10200D02*
X1490600D01*
G01X1496600Y-10206D02*
Y-10200D01*
G01X1496606Y-10206D02*
X1496600D01*
G01X1496606Y-10252D02*
Y-10206D01*
G01X1496660Y-10252D02*
X1496606D01*
G01X1486342Y-19342D02*
X1482000Y-15000D01*
G01X1596658Y-19342D02*
X1486342D01*
G01X1497707Y9093D02*
X1486329Y20471D01*
G01X1497707Y-678D02*
Y9093D01*
G01X1505929Y-8900D02*
X1497707Y-678D01*
G01X1545900Y-8900D02*
X1505929D01*
G01X1496532Y8638D02*
X1485851Y19319D01*
G01X1496532Y-1133D02*
Y8638D01*
G01X1505451Y-10052D02*
X1496532Y-1133D01*
G01X1523022Y-10052D02*
X1505451D01*
G01X1523023Y-10053D02*
X1523022Y-10052D01*
G01X1523977Y-10053D02*
X1523023D01*
G01X1523978Y-10052D02*
X1523977Y-10053D01*
G01X1546446Y-10052D02*
X1523978D01*
G01X1526414Y87964D02*
X1532147D01*
G01X1525210Y86760D02*
X1526414Y87964D01*
G01X1524638Y86760D02*
X1525210D01*
G01X1519580Y81702D02*
X1524638Y86760D01*
G01X1519580Y81313D02*
Y81702D01*
G01X1516229Y79717D02*
X1517162Y78784D01*
G01X1516229Y83710D02*
Y79717D01*
G01X1516971Y84452D02*
X1516229Y83710D01*
G01X1516971Y89690D02*
Y84452D01*
G01X1517622Y90341D02*
X1516971Y89690D01*
G01X1517622Y96047D02*
Y90341D01*
G01X1526108Y86028D02*
X1535496D01*
G01X1525688Y85608D02*
X1526108Y86028D01*
G01X1525116Y85608D02*
X1525688D01*
G01X1521355Y81847D02*
X1525116Y85608D01*
G01X1521355Y79704D02*
Y81847D01*
G01X1520531Y78880D02*
X1521355Y79704D01*
G01X1520314Y78880D02*
X1520531D01*
G01X1520014Y86532D02*
Y113178D01*
G01X1519599Y86117D02*
X1520014Y86532D01*
G01X1526732Y84524D02*
X1538967D01*
G01X1526312Y84104D02*
X1526732Y84524D01*
G01X1525740Y84104D02*
X1526312D01*
G01X1523073Y81437D02*
X1525740Y84104D01*
G01X1523073Y77736D02*
Y81437D01*
G01X1521505Y76168D02*
X1523073Y77736D01*
G01X1517269Y76168D02*
X1521505D01*
G01X1515477Y77960D02*
X1517269Y76168D01*
G01X1515477Y84022D02*
Y77960D01*
G01X1516150Y84695D02*
X1515477Y84022D01*
G01X1516150Y89933D02*
Y84695D01*
G01X1516870Y90653D02*
X1516150Y89933D01*
G01X1516870Y95735D02*
Y90653D01*
G01X1526420Y85276D02*
X1539279D01*
G01X1526000Y84856D02*
X1526420Y85276D01*
G01X1525428Y84856D02*
X1526000D01*
G01X1522108Y81536D02*
X1525428Y84856D01*
G01X1522108Y78170D02*
Y81536D01*
G01X1520998Y77060D02*
X1522108Y78170D01*
G01X1519090Y77060D02*
X1520998D01*
G01X1518738Y77412D02*
X1519090Y77060D01*
G01X1518738Y79437D02*
Y77412D01*
G01X1516981Y81194D02*
X1518738Y79437D01*
G01X1516981Y83398D02*
Y81194D01*
G01X1517723Y84140D02*
X1516981Y83398D01*
G01X1517723Y89378D02*
Y84140D01*
G01X1518374Y90029D02*
X1517723Y89378D01*
G01X1518374Y96451D02*
Y90029D01*
G01X1493074Y150600D02*
X1495848D01*
G01X1490237Y153437D02*
X1493074Y150600D01*
G01X1490237Y156917D02*
Y153437D01*
G01X1522727Y153723D02*
Y175183D01*
G01X1526310Y150140D02*
X1522727Y153723D01*
G01X1526310Y142190D02*
Y150140D01*
G01X1511300Y127050D02*
X1511800D01*
G01X1507725Y130625D02*
X1511300Y127050D01*
G01X1507725Y136145D02*
Y130625D01*
G01X1504521Y139349D02*
X1507725Y136145D01*
G01X1501244Y139349D02*
X1504521D01*
G01X1500348Y140245D02*
X1501244Y139349D01*
G01X1500348Y143336D02*
Y140245D01*
G01X1504500Y147488D02*
X1500348Y143336D01*
G01X1504500Y158679D02*
Y147488D01*
G01X1526728Y123272D02*
Y124168D01*
G01X1528340Y121660D02*
X1526728Y123272D01*
G01X1513130Y112600D02*
X1513879Y113349D01*
G01X1510850Y112600D02*
X1513130D01*
G01X1506187Y117263D02*
X1510850Y112600D01*
G01X1506187Y128768D02*
Y117263D01*
G01X1505621Y129334D02*
X1506187Y128768D01*
G01X1505621Y135272D02*
Y129334D01*
G01X1503648Y137245D02*
X1505621Y135272D01*
G01X1500371Y137245D02*
X1503648D01*
G01X1498244Y139372D02*
X1500371Y137245D01*
G01X1498244Y141046D02*
Y139372D01*
G01X1498243Y141047D02*
X1498244Y141046D01*
G01X1498243Y142791D02*
Y141047D01*
G01X1498244Y142792D02*
X1498243Y142791D01*
G01X1498244Y145591D02*
Y142792D01*
G01X1499230Y146577D02*
X1498244Y145591D01*
G01X1499230Y151230D02*
Y146577D01*
G01X1501243Y153243D02*
X1499230Y151230D01*
G01X1501296Y153243D02*
X1501243D01*
G01X1502219Y154166D02*
X1501296Y153243D01*
G01X1502219Y154219D02*
Y154166D01*
G01X1502342Y154342D02*
X1502219Y154219D01*
G01X1502342Y158976D02*
Y154342D01*
G01X1508704Y151999D02*
Y161487D01*
G01X1509206Y151497D02*
X1508704Y151999D01*
G01X1509206Y145212D02*
Y151497D01*
G01X1507656Y143662D02*
X1509206Y145212D01*
G01X1507656Y140344D02*
Y143662D01*
G01X1510029Y137971D02*
X1507656Y140344D01*
G01X1510029Y132470D02*
Y137971D01*
G01X1511595Y130904D02*
X1510029Y132470D01*
G01X1512796Y130904D02*
X1511595D01*
G01X1517072Y126628D02*
X1512796Y130904D01*
G01X1517072Y112803D02*
Y126628D01*
G01X1518376Y111499D02*
X1517072Y112803D01*
G01X1520253Y139647D02*
Y177705D01*
G01X1522534Y137366D02*
X1520253Y139647D01*
G01X1526095Y137366D02*
X1522534D01*
G01X1528727Y139998D02*
X1526095Y137366D01*
G01X1525454Y126439D02*
X1528981D01*
G01X1524000Y124985D02*
X1525454Y126439D01*
G01X1524000Y123300D02*
Y124985D01*
G01X1512665Y101004D02*
X1517622Y96047D01*
G01X1512043Y101004D02*
X1512665D01*
G01X1512042Y101003D02*
X1512043Y101004D01*
G01X1510229Y101003D02*
X1512042D01*
G01X1504683Y106549D02*
X1510229Y101003D01*
G01X1504683Y128144D02*
Y106549D01*
G01X1504117Y128710D02*
X1504683Y128144D01*
G01X1504117Y133311D02*
Y128710D01*
G01X1502190Y135238D02*
X1504117Y133311D01*
G01X1499698Y135238D02*
X1502190D01*
G01X1496500Y138436D02*
X1499698Y135238D01*
G01X1496500Y145975D02*
Y138436D01*
G01X1497726Y147201D02*
X1496500Y145975D01*
G01X1497726Y155340D02*
Y147201D01*
G01X1497034Y156032D02*
X1497726Y155340D01*
G01X1493920Y156032D02*
X1497034D01*
G01X1491594Y158358D02*
X1493920Y156032D01*
G01X1476994Y149606D02*
X1473354Y153246D01*
G01X1476994Y143053D02*
Y149606D01*
G01X1485210Y134837D02*
X1476994Y143053D01*
G01X1519501Y138899D02*
X1524744Y133656D01*
G01X1519501Y178017D02*
Y138899D01*
G01X1500643Y154819D02*
X1497538Y157924D01*
G01X1521005Y142995D02*
Y176329D01*
G01X1524900Y139100D02*
X1521005Y142995D01*
G01X1511560Y153184D02*
Y160078D01*
G01X1516549Y148195D02*
X1511560Y153184D01*
G01X1516549Y129651D02*
Y148195D01*
G01X1518224Y127976D02*
X1516549Y129651D01*
G01X1518224Y114968D02*
Y127976D01*
G01X1520014Y113178D02*
X1518224Y114968D01*
G01X1510408Y152706D02*
Y160780D01*
G01X1510910Y152204D02*
X1510408Y152706D01*
G01X1510910Y143340D02*
Y152204D01*
G01X1510184Y142614D02*
X1510910Y143340D01*
G01X1507752Y151604D02*
Y161882D01*
G01X1508251Y151105D02*
X1507752Y151604D01*
G01X1508251Y148813D02*
Y151105D01*
G01X1508253Y148811D02*
X1508251Y148813D01*
G01X1508253Y148189D02*
Y148811D01*
G01X1508252Y148188D02*
X1508253Y148189D01*
G01X1508252Y145605D02*
Y148188D01*
G01X1505133Y142486D02*
X1508252Y145605D01*
G01X1503466Y142486D02*
X1505133D01*
G01X1506000Y150000D02*
Y163000D01*
G01X1507500Y148500D02*
X1506000Y150000D01*
G01X1507500Y145917D02*
Y148500D01*
G01X1505645Y144062D02*
X1507500Y145917D01*
G01X1502813Y144062D02*
X1505645D01*
G01X1501500Y142749D02*
X1502813Y144062D01*
G01X1501500Y141499D02*
Y142749D01*
G01X1502498Y140501D02*
X1501500Y141499D01*
G01X1505299Y140501D02*
X1502498D01*
G01X1508877Y136923D02*
X1505299Y140501D01*
G01X1508877Y131664D02*
Y136923D01*
G01X1510841Y129700D02*
X1508877Y131664D01*
G01X1511550Y129700D02*
X1510841D01*
G01X1514600Y126650D02*
X1511550Y129700D01*
G01X1512354Y100251D02*
X1516870Y95735D01*
G01X1509917Y100251D02*
X1512354D01*
G01X1503931Y106237D02*
X1509917Y100251D01*
G01X1503931Y127832D02*
Y106237D01*
G01X1501800Y129963D02*
X1503931Y127832D01*
G01X1499912Y129963D02*
X1501800D01*
G01X1497786Y132089D02*
X1499912Y129963D01*
G01X1497786Y134479D02*
Y132089D01*
G01X1492476Y139789D02*
X1497786Y134479D01*
G01X1492476Y150134D02*
Y139789D01*
G01X1485804Y156806D02*
X1492476Y150134D01*
G01X1484171Y147030D02*
Y165482D01*
G01X1497034Y134167D02*
X1484171Y147030D01*
G01X1497034Y131777D02*
Y134167D01*
G01X1499600Y129211D02*
X1497034Y131777D01*
G01X1501488Y129211D02*
X1499600D01*
G01X1503179Y127520D02*
X1501488Y129211D01*
G01X1503179Y107847D02*
Y127520D01*
G01X1502256Y106924D02*
X1503179Y107847D01*
G01X1500176Y106924D02*
X1502256D01*
G01X1498810Y108290D02*
X1500176Y106924D01*
G01X1509656Y152394D02*
Y161092D01*
G01X1510158Y151892D02*
X1509656Y152394D01*
G01X1510158Y144817D02*
Y151892D01*
G01X1508608Y143267D02*
X1510158Y144817D01*
G01X1508608Y140789D02*
Y143267D01*
G01X1510887Y138510D02*
X1508608Y140789D01*
G01X1511660Y138510D02*
X1510887D01*
G01X1518438Y108562D02*
Y100926D01*
G01X1516120Y110880D02*
X1518438Y108562D01*
G01X1516120Y120827D02*
Y110880D01*
G01X1512897Y124050D02*
X1516120Y120827D01*
G01X1512252Y124050D02*
X1512897D01*
G01X1506573Y129729D02*
X1512252Y124050D01*
G01X1506573Y135667D02*
Y129729D01*
G01X1504043Y138197D02*
X1506573Y135667D01*
G01X1500766Y138197D02*
X1504043D01*
G01X1499196Y139767D02*
X1500766Y138197D01*
G01X1499196Y144832D02*
Y139767D01*
G01X1500182Y145818D02*
X1499196Y144832D01*
G01X1500182Y149500D02*
Y145818D01*
G01X1503294Y152612D02*
X1500182Y149500D01*
G01X1503294Y159371D02*
Y152612D01*
G01X1513020Y101805D02*
X1518374Y96451D01*
G01X1510491Y101805D02*
X1513020D01*
G01X1505435Y106861D02*
X1510491Y101805D01*
G01X1505435Y128456D02*
Y106861D01*
G01X1504869Y129022D02*
X1505435Y128456D01*
G01X1504869Y133623D02*
Y129022D01*
G01X1502502Y135990D02*
X1504869Y133623D01*
G01X1500010Y135990D02*
X1502502D01*
G01X1497491Y138509D02*
X1500010Y135990D01*
G01X1497491Y145902D02*
Y138509D01*
G01X1498478Y146889D02*
X1497491Y145902D01*
G01X1498478Y155911D02*
Y146889D01*
G01X1497370Y157019D02*
X1498478Y155911D01*
G01X1468941Y182478D02*
Y184670D01*
G01X1475767Y175652D02*
X1468941Y182478D01*
G01X1475767Y172380D02*
Y175652D01*
G01X1476735Y171412D02*
X1475767Y172380D01*
G01X1487736Y171412D02*
X1476735D01*
G01X1488900Y172576D02*
X1487736Y171412D01*
G01X1490842Y157522D02*
X1490237Y156917D01*
G01X1490842Y160436D02*
Y157522D01*
G01X1490120Y161158D02*
X1490842Y160436D01*
G01X1490120Y163353D02*
Y161158D01*
G01X1490119Y163354D02*
X1490120Y163353D01*
G01X1490119Y163976D02*
Y163354D01*
G01X1491948Y165805D02*
X1490119Y163976D01*
G01X1492022Y165805D02*
X1491948D01*
G01X1499944Y173727D02*
X1492022Y165805D01*
G01X1499944Y173801D02*
Y173727D01*
G01X1499946Y173803D02*
X1499944Y173801D01*
G01X1499946Y174425D02*
Y173803D01*
G01X1499945Y174426D02*
X1499946Y174425D01*
G01X1499945Y175048D02*
Y174426D01*
G01X1499944Y175049D02*
X1499945Y175048D01*
G01X1499944Y178789D02*
Y175049D01*
G01X1495216Y183517D02*
X1499944Y178789D01*
G01X1495216Y201209D02*
Y183517D01*
G01X1494709Y201716D02*
X1495216Y201209D01*
G01X1494709Y218046D02*
Y201716D01*
G01X1522727Y175183D02*
X1527844Y180300D01*
G01X1504446Y158733D02*
X1504500Y158679D01*
G01X1504446Y159849D02*
Y158733D01*
G01X1502167Y162128D02*
X1504446Y159849D01*
G01X1501051Y162128D02*
X1502167D01*
G01X1500519Y162660D02*
X1501051Y162128D01*
G01X1500519Y165691D02*
Y162660D01*
G01X1505873Y171045D02*
X1500519Y165691D01*
G01X1505873Y181157D02*
Y171045D01*
G01X1503959Y183071D02*
X1505873Y181157D01*
G01X1503959Y221379D02*
Y183071D01*
G01X1501294Y160024D02*
X1502342Y158976D01*
G01X1496926Y160024D02*
X1501294D01*
G01X1495803Y161147D02*
X1496926Y160024D01*
G01X1495803Y165016D02*
Y161147D01*
G01X1503017Y172230D02*
X1495803Y165016D01*
G01X1503017Y179972D02*
Y172230D01*
G01X1498224Y184765D02*
X1503017Y179972D01*
G01X1498224Y200585D02*
Y184765D01*
G01X1501103Y203464D02*
X1498224Y200585D01*
G01X1501103Y222776D02*
Y203464D01*
G01X1516870Y205791D02*
X1516616Y205537D01*
G01X1518116Y205791D02*
X1516870D01*
G01X1518408Y205499D02*
X1518116Y205791D01*
G01X1518408Y193927D02*
Y205499D01*
G01X1518941Y193394D02*
X1518408Y193927D01*
G01X1520300Y193394D02*
X1518941D01*
G01X1520975Y194069D02*
X1520300Y193394D01*
G01X1520975Y209896D02*
Y194069D01*
G01X1521700Y210621D02*
X1520975Y209896D01*
G01X1521700Y229185D02*
Y210621D01*
G01X1519940Y209969D02*
Y229185D01*
G01X1519425Y209454D02*
X1519940Y209969D01*
G01X1518695Y209454D02*
X1519425D01*
G01X1518180Y209969D02*
X1518695Y209454D01*
G01X1518180Y229185D02*
Y209969D01*
G01X1509400Y216376D02*
Y219165D01*
G01X1507341Y214317D02*
X1509400Y216376D01*
G01X1507341Y184141D02*
Y214317D01*
G01X1508729Y182753D02*
X1507341Y184141D01*
G01X1508729Y161512D02*
Y182753D01*
G01X1508704Y161487D02*
X1508729Y161512D01*
G01X1525661Y211069D02*
X1528131Y213539D01*
G01X1525661Y207508D02*
Y211069D01*
G01X1524638Y206485D02*
X1525661Y207508D01*
G01X1524638Y182090D02*
Y206485D01*
G01X1520253Y177705D02*
X1524638Y182090D01*
G01X1468051Y179558D02*
X1473888Y173721D01*
G01X1468051Y184496D02*
Y179558D01*
G01X1491594Y160748D02*
Y158358D01*
G01X1490872Y161470D02*
X1491594Y160748D01*
G01X1490872Y163665D02*
Y161470D01*
G01X1492260Y165053D02*
X1490872Y163665D01*
G01X1492334Y165053D02*
X1492260D01*
G01X1500696Y173415D02*
X1492334Y165053D01*
G01X1500696Y173489D02*
Y173415D01*
G01X1500698Y173491D02*
X1500696Y173489D01*
G01X1500698Y174737D02*
Y173491D01*
G01X1500697Y174738D02*
X1500698Y174737D01*
G01X1500697Y175360D02*
Y174738D01*
G01X1500696Y175361D02*
X1500697Y175360D01*
G01X1500696Y179101D02*
Y175361D01*
G01X1495968Y183829D02*
X1500696Y179101D01*
G01X1495968Y201521D02*
Y183829D01*
G01X1495461Y202028D02*
X1495968Y201521D01*
G01X1495461Y217734D02*
Y202028D01*
G01X1495849Y218122D02*
X1495461Y217734D01*
G01X1489056Y179832D02*
X1489015D01*
G01X1489056Y180057D02*
Y179832D01*
G01X1485350Y183763D02*
X1489056Y180057D01*
G01X1482918Y183763D02*
X1485350D01*
G01X1472041Y194640D02*
X1482918Y183763D01*
G01X1472041Y211983D02*
Y194640D01*
G01X1476729Y216671D02*
X1472041Y211983D01*
G01X1478685Y216671D02*
X1476729D01*
G01X1481720Y219706D02*
X1478685Y216671D01*
G01X1523886Y182402D02*
X1519501Y178017D01*
G01X1523886Y206797D02*
Y182402D01*
G01X1524909Y207820D02*
X1523886Y206797D01*
G01X1524909Y211381D02*
Y207820D01*
G01X1527146Y213618D02*
X1524909Y211381D01*
G01X1477388Y175095D02*
Y172988D01*
G01X1469693Y182790D02*
X1477388Y175095D01*
G01X1469693Y184982D02*
Y182790D01*
G01X1515060Y192827D02*
Y192443D01*
G01X1515600Y193367D02*
X1515060Y192827D01*
G01X1515600Y201800D02*
Y193367D01*
G01X1514700Y202700D02*
X1515600Y201800D01*
G01X1514700Y214941D02*
Y202700D01*
G01X1516628Y216869D02*
X1514700Y214941D01*
G01X1516628Y219371D02*
Y216869D01*
G01X1465921Y190005D02*
Y222235D01*
G01X1470550Y185376D02*
X1465921Y190005D01*
G01X1470550Y182997D02*
Y185376D01*
G01X1476120Y177427D02*
X1470550Y182997D01*
G01X1484537Y177427D02*
X1476120D01*
G01X1487664Y174300D02*
X1484537Y177427D01*
G01X1490933Y174300D02*
X1487664D01*
G01X1492597Y172636D02*
X1490933Y174300D01*
G01X1500351Y203776D02*
Y223088D01*
G01X1497472Y200897D02*
X1500351Y203776D01*
G01X1497472Y184453D02*
Y200897D01*
G01X1502249Y179676D02*
X1497472Y184453D01*
G01X1502249Y172526D02*
Y179676D01*
G01X1495050Y165327D02*
X1502249Y172526D01*
G01X1495050Y162284D02*
Y165327D01*
G01X1495051Y162283D02*
X1495050Y162284D01*
G01X1495051Y162232D02*
Y162283D01*
G01X1493363Y160544D02*
X1495051Y162232D01*
G01X1493363Y158847D02*
Y160544D01*
G01X1494286Y157924D02*
X1493363Y158847D01*
G01X1497538Y157924D02*
X1494286D01*
G01X1526142Y205757D02*
X1527166Y206781D01*
G01X1526142Y181466D02*
Y205757D01*
G01X1521005Y176329D02*
X1526142Y181466D01*
G01X1493957Y201404D02*
Y218358D01*
G01X1494464Y200897D02*
X1493957Y201404D01*
G01X1494464Y183205D02*
Y200897D01*
G01X1499192Y178477D02*
X1494464Y183205D01*
G01X1499192Y174737D02*
Y178477D01*
G01X1499193Y174736D02*
X1499192Y174737D01*
G01X1499193Y174114D02*
Y174736D01*
G01X1499192Y174113D02*
X1499193Y174114D01*
G01X1499192Y174039D02*
Y174113D01*
G01X1491711Y166558D02*
X1499192Y174039D01*
G01X1491637Y166558D02*
X1491711D01*
G01X1491612Y166533D02*
X1491637Y166558D01*
G01X1490366Y166533D02*
X1491612D01*
G01X1486556Y162723D02*
X1490366Y166533D01*
G01X1486556Y160044D02*
Y162723D01*
G01X1488300Y158300D02*
X1486556Y160044D01*
G01X1509797Y202540D02*
X1512500Y199837D01*
G01X1509797Y213298D02*
Y202540D01*
G01X1511857Y215358D02*
X1509797Y213298D01*
G01X1511857Y217394D02*
Y215358D01*
G01X1511856Y217395D02*
X1511857Y217394D01*
G01X1511856Y220875D02*
Y217395D01*
G01X1515476Y217347D02*
Y218884D01*
G01X1510949Y212820D02*
X1515476Y217347D01*
G01X1510949Y204477D02*
Y212820D01*
G01X1514276Y201150D02*
X1510949Y204477D01*
G01X1514276Y193888D02*
Y201150D01*
G01X1513484Y193096D02*
X1514276Y193888D01*
G01X1513484Y191790D02*
Y193096D01*
G01X1514276Y190998D02*
X1513484Y191790D01*
G01X1514276Y162794D02*
Y190998D01*
G01X1511560Y160078D02*
X1514276Y162794D01*
G01X1511104Y217083D02*
Y220283D01*
G01X1511105Y217082D02*
X1511104Y217083D01*
G01X1511105Y215670D02*
Y217082D01*
G01X1509045Y213610D02*
X1511105Y215670D01*
G01X1509045Y184848D02*
Y213610D01*
G01X1513013Y180880D02*
X1509045Y184848D01*
G01X1513013Y163385D02*
Y180880D01*
G01X1510408Y160780D02*
X1513013Y163385D01*
G01X1505948Y184187D02*
Y220733D01*
G01X1507777Y182358D02*
X1505948Y184187D01*
G01X1507777Y161907D02*
Y182358D01*
G01X1507752Y161882D02*
X1507777Y161907D01*
G01X1497700Y162285D02*
X1497493Y162078D01*
G01X1497700Y165849D02*
Y162285D01*
G01X1503769Y171918D02*
X1497700Y165849D01*
G01X1503769Y180284D02*
Y171918D01*
G01X1501855Y182198D02*
X1503769Y180284D01*
G01X1501855Y222464D02*
Y182198D01*
G01X1505113Y183552D02*
Y220997D01*
G01X1505111Y183550D02*
X1505113Y183552D01*
G01X1507025Y181636D02*
X1505111Y183550D01*
G01X1507025Y164025D02*
Y181636D01*
G01X1506000Y163000D02*
X1507025Y164025D01*
G01X1485804Y163222D02*
Y156806D01*
G01X1489892Y167310D02*
X1485804Y163222D01*
G01X1491399Y167310D02*
X1489892D01*
G01X1498440Y174351D02*
X1491399Y167310D01*
G01X1498440Y178165D02*
Y174351D01*
G01X1493712Y182893D02*
X1498440Y178165D01*
G01X1493712Y196775D02*
Y182893D01*
G01X1493711Y196776D02*
X1493712Y196775D01*
G01X1493711Y197398D02*
Y196776D01*
G01X1493712Y197399D02*
X1493711Y197398D01*
G01X1493712Y200585D02*
Y197399D01*
G01X1493205Y201092D02*
X1493712Y200585D01*
G01X1493205Y218670D02*
Y201092D01*
G01X1489572Y215590D02*
Y222226D01*
G01X1490560Y214602D02*
X1489572Y215590D01*
G01X1490560Y184385D02*
Y214602D01*
G01X1496264Y178681D02*
X1490560Y184385D01*
G01X1496264Y178655D02*
Y178681D01*
G01X1496359Y178560D02*
X1496264Y178655D01*
G01X1496359Y177254D02*
Y178560D01*
G01X1495000Y175895D02*
X1496359Y177254D01*
G01X1495000Y172209D02*
Y175895D01*
G01X1492853Y170062D02*
X1495000Y172209D01*
G01X1488751Y170062D02*
X1492853D01*
G01X1484171Y165482D02*
X1488751Y170062D01*
G01X1510352Y216771D02*
Y219667D01*
G01X1510353Y216770D02*
X1510352Y216771D01*
G01X1510353Y215982D02*
Y216770D01*
G01X1508293Y213922D02*
X1510353Y215982D01*
G01X1508293Y184536D02*
Y213922D01*
G01X1512261Y180568D02*
X1508293Y184536D01*
G01X1512261Y163697D02*
Y180568D01*
G01X1509656Y161092D02*
X1512261Y163697D01*
G01X1501689Y160976D02*
X1503294Y159371D01*
G01X1500573Y160976D02*
X1501689D01*
G01X1499367Y162182D02*
X1500573Y160976D01*
G01X1499367Y166169D02*
Y162182D01*
G01X1504721Y171523D02*
X1499367Y166169D01*
G01X1504721Y180679D02*
Y171523D01*
G01X1502807Y182593D02*
X1504721Y180679D01*
G01X1502807Y222069D02*
Y182593D01*
G01X1493997Y157019D02*
X1497370D01*
G01X1492346Y158670D02*
X1493997Y157019D01*
G01X1492346Y161060D02*
Y158670D01*
G01X1491624Y161782D02*
X1492346Y161060D01*
G01X1491624Y163353D02*
Y161782D01*
G01X1492547Y164276D02*
X1491624Y163353D01*
G01X1492621Y164276D02*
X1492547D01*
G01X1501448Y173103D02*
X1492621Y164276D01*
G01X1501448Y173177D02*
Y173103D01*
G01X1501497Y173226D02*
X1501448Y173177D01*
G01X1501497Y179364D02*
Y173226D01*
G01X1496720Y184141D02*
X1501497Y179364D01*
G01X1496720Y201209D02*
Y184141D01*
G01X1499599Y204088D02*
X1496720Y201209D01*
G01X1499599Y223400D02*
Y204088D01*
G01X1495097Y218434D02*
X1494709Y218046D01*
G01X1495097Y228285D02*
Y218434D01*
G01X1489311Y234071D02*
X1495097Y228285D01*
G01X1489311Y245019D02*
Y234071D01*
G01X1488254Y246076D02*
X1489311Y245019D01*
G01X1485533Y246076D02*
X1488254D01*
G01X1483976Y247633D02*
X1485533Y246076D01*
G01X1483976Y248653D02*
Y247633D01*
G01X1480827Y251802D02*
X1483976Y248653D01*
G01X1480827Y261038D02*
Y251802D01*
G01X1475268Y266597D02*
X1480827Y261038D01*
G01X1475268Y271063D02*
Y266597D01*
G01X1474331Y272000D02*
X1475268Y271063D01*
G01X1473322Y272000D02*
X1474331D01*
G01X1472328Y272994D02*
X1473322Y272000D01*
G01X1472328Y275283D02*
Y272994D01*
G01X1473798Y276753D02*
X1472328Y275283D01*
G01X1526081Y277116D02*
Y281119D01*
G01X1527062Y276135D02*
X1526081Y277116D01*
G01X1534076Y250300D02*
X1527062Y257314D01*
G01X1466684Y270898D02*
Y318255D01*
G01X1465561Y269775D02*
X1466684Y270898D01*
G01X1465561Y267454D02*
Y269775D01*
G01X1470556Y260744D02*
X1468016Y263284D01*
G01X1470556Y256900D02*
Y260744D01*
G01X1466404Y245350D02*
Y246287D01*
G01X1520287Y278096D02*
Y286713D01*
G01X1523658Y274725D02*
X1520287Y278096D01*
G01X1523658Y255904D02*
Y274725D01*
G01X1528017Y251545D02*
X1523658Y255904D01*
G01X1503961Y221381D02*
X1503959Y221379D01*
G01X1503961Y221475D02*
Y221381D01*
G01X1504621Y222135D02*
X1503961Y221475D01*
G01X1504621Y232819D02*
Y222135D01*
G01X1501576Y235864D02*
X1504621Y232819D01*
G01X1501576Y241260D02*
Y235864D01*
G01X1494799Y248037D02*
X1501576Y241260D01*
G01X1494799Y250048D02*
Y248037D01*
G01X1490471Y254376D02*
X1494799Y250048D01*
G01X1490471Y255891D02*
Y254376D01*
G01X1489831Y256531D02*
X1490471Y255891D01*
G01X1489831Y259805D02*
Y256531D01*
G01X1494267Y264241D02*
X1489831Y259805D01*
G01X1494267Y269989D02*
Y264241D01*
G01X1485951Y278305D02*
X1494267Y269989D01*
G01X1485951Y281418D02*
Y278305D01*
G01X1525360Y256609D02*
X1529719Y252250D01*
G01X1525360Y275430D02*
Y256609D01*
G01X1524379Y276411D02*
X1525360Y275430D01*
G01X1524379Y280021D02*
Y276411D01*
G01X1506472Y254958D02*
X1505946Y254432D01*
G01X1506472Y260028D02*
Y254958D01*
G01X1501660Y264840D02*
X1506472Y260028D01*
G01X1501660Y270000D02*
Y264840D01*
G01X1500656Y271004D02*
X1501660Y270000D01*
G01X1500656Y277592D02*
Y271004D01*
G01X1502009Y278945D02*
X1500656Y277592D01*
G01X1502009Y280875D02*
Y278945D01*
G01X1501765Y223438D02*
X1501103Y222776D01*
G01X1501765Y226481D02*
Y223438D01*
G01X1495339Y232907D02*
X1501765Y226481D01*
G01X1495339Y243446D02*
Y232907D01*
G01X1495340Y243446D02*
X1495339D01*
G01X1495340Y243455D02*
Y243446D01*
G01X1491942Y246853D02*
X1495340Y243455D01*
G01X1491942Y248864D02*
Y246853D01*
G01X1487614Y253192D02*
X1491942Y248864D01*
G01X1487614Y254707D02*
Y253192D01*
G01X1486422Y255899D02*
X1487614Y254707D01*
G01X1486422Y265200D02*
Y255899D01*
G01X1484927Y266695D02*
X1486422Y265200D01*
G01X1484927Y270853D02*
Y266695D01*
G01X1483780Y272000D02*
X1484927Y270853D01*
G01X1481701Y272000D02*
X1483780D01*
G01X1480098Y273603D02*
X1481701Y272000D01*
G01X1472328Y271924D02*
X1470649Y273603D01*
G01X1472328Y266093D02*
Y271924D01*
G01X1475672Y262749D02*
X1472328Y266093D01*
G01X1475672Y255328D02*
Y262749D01*
G01X1478500Y252500D02*
X1475672Y255328D01*
G01X1478500Y252000D02*
Y252500D01*
G01X1504716Y276702D02*
Y281428D01*
G01X1506218Y275200D02*
X1504716Y276702D01*
G01X1506218Y273897D02*
Y275200D01*
G01X1505328Y273007D02*
X1506218Y273897D01*
G01X1505328Y265673D02*
Y273007D01*
G01X1508776Y262225D02*
X1505328Y265673D01*
G01X1508776Y259224D02*
Y262225D01*
G01X1510300Y257700D02*
X1508776Y259224D01*
G01X1510300Y257696D02*
Y257700D01*
G01X1510457Y257539D02*
X1510300Y257696D01*
G01X1510457Y254047D02*
Y257539D01*
G01X1509814Y253404D02*
X1510457Y254047D01*
G01X1509814Y247215D02*
Y253404D01*
G01X1521185Y229700D02*
X1521700Y229185D01*
G01X1520455Y229700D02*
X1521185D01*
G01X1519940Y229185D02*
X1520455Y229700D01*
G01X1517665D02*
X1518180Y229185D01*
G01X1516935Y229700D02*
X1517665D01*
G01X1516420Y229185D02*
X1516935Y229700D01*
G01X1516420Y223815D02*
Y229185D01*
G01X1515905Y223300D02*
X1516420Y223815D01*
G01X1515175Y223300D02*
X1515905D01*
G01X1514660Y223815D02*
X1515175Y223300D01*
G01X1514660Y235742D02*
Y223815D01*
G01X1511131Y239271D02*
X1514660Y235742D01*
G01X1511131Y241724D02*
Y239271D01*
G01X1512568Y243161D02*
X1511131Y241724D01*
G01X1512568Y252898D02*
Y243161D01*
G01X1514672Y255002D02*
X1512568Y252898D01*
G01X1514672Y270920D02*
Y255002D01*
G01X1514172Y271420D02*
X1514672Y270920D01*
G01X1513412Y271420D02*
X1514172D01*
G01X1512912Y270920D02*
X1513412Y271420D01*
G01X1512912Y260315D02*
Y270920D01*
G01X1512397Y259800D02*
X1512912Y260315D01*
G01X1511667Y259800D02*
X1512397D01*
G01X1511152Y260315D02*
X1511667Y259800D01*
G01X1511152Y265763D02*
Y260315D01*
G01X1510800Y266115D02*
X1511152Y265763D01*
G01X1510161Y266115D02*
X1510800D01*
G01X1509809Y266467D02*
X1510161Y266115D01*
G01X1509809Y267615D02*
Y266467D01*
G01X1510161Y267967D02*
X1509809Y267615D01*
G01X1510800Y267967D02*
X1510161D01*
G01X1511152Y268319D02*
X1510800Y267967D01*
G01X1511152Y269467D02*
Y268319D01*
G01X1510800Y269819D02*
X1511152Y269467D01*
G01X1510377Y269819D02*
X1510800D01*
G01X1510025Y270171D02*
X1510377Y269819D01*
G01X1510025Y271319D02*
Y270171D01*
G01X1510377Y271671D02*
X1510025Y271319D01*
G01X1510800Y271671D02*
X1510377D01*
G01X1511152Y272023D02*
X1510800Y271671D01*
G01X1511152Y273526D02*
Y272023D01*
G01X1507020Y277658D02*
X1511152Y273526D01*
G01X1507020Y282385D02*
Y277658D01*
G01X1467176Y254174D02*
X1468450Y252900D01*
G01X1467176Y256653D02*
Y254174D01*
G01X1465629Y258200D02*
X1467176Y256653D01*
G01X1488076Y279224D02*
Y283991D01*
G01X1490900Y276400D02*
X1488076Y279224D01*
G01X1493775Y276400D02*
X1490900D01*
G01X1495075Y275100D02*
X1493775Y276400D01*
G01X1495075Y272046D02*
Y275100D01*
G01X1498452Y268669D02*
X1495075Y272046D01*
G01X1498452Y258975D02*
Y268669D01*
G01X1500963Y256464D02*
X1498452Y258975D01*
G01X1500963Y254463D02*
Y256464D01*
G01X1497896Y251396D02*
X1500963Y254463D01*
G01X1497896Y249118D02*
Y251396D01*
G01X1504579Y242435D02*
X1497896Y249118D01*
G01X1504579Y237148D02*
Y242435D01*
G01X1507599Y234128D02*
X1504579Y237148D01*
G01X1507599Y220964D02*
Y234128D01*
G01X1509400Y219165D02*
X1507599Y220964D01*
G01X1517081Y277831D02*
Y281919D01*
G01X1520223Y274689D02*
X1517081Y277831D01*
G01X1520223Y274677D02*
Y274689D01*
G01X1520899Y274001D02*
X1520223Y274677D01*
G01X1520899Y248936D02*
Y274001D01*
G01X1526144Y243691D02*
X1520899Y248936D01*
G01X1526144Y240257D02*
Y243691D01*
G01X1528131Y238270D02*
X1526144Y240257D01*
G01X1527019Y228073D02*
X1528131Y229185D01*
G01Y221861D02*
X1527019Y222973D01*
G01X1495849Y228660D02*
Y218122D01*
G01X1490063Y234446D02*
X1495849Y228660D01*
G01X1490063Y245027D02*
Y234446D01*
G01X1490064Y245028D02*
X1490063Y245027D01*
G01X1490064Y245330D02*
Y245028D01*
G01X1489385Y246009D02*
X1490064Y245330D01*
G01X1489385Y247691D02*
Y246009D01*
G01X1487510Y249566D02*
X1489385Y247691D01*
G01X1484705Y249566D02*
X1487510D01*
G01X1481672Y252599D02*
X1484705Y249566D01*
G01X1481672Y262358D02*
Y252599D01*
G01X1477568Y266462D02*
X1481672Y262358D01*
G01X1477568Y268995D02*
Y266462D01*
G01X1478418Y269845D02*
X1477568Y268995D01*
G01X1478418Y271063D02*
Y269845D01*
G01X1477481Y272000D02*
X1478418Y271063D01*
G01X1476472Y272000D02*
X1477481D01*
G01X1475478Y272994D02*
X1476472Y272000D01*
G01X1475478Y277152D02*
Y272994D01*
G01X1474407Y278223D02*
X1475478Y277152D01*
G01X1473398Y278223D02*
X1474407D01*
G01X1472328Y279293D02*
X1473398Y278223D01*
G01X1472328Y291029D02*
Y279293D01*
G01X1481720Y222199D02*
Y219706D01*
G01X1482004Y222483D02*
X1481720Y222199D01*
G01X1524977Y222338D02*
X1527146Y220169D01*
G01X1524977Y231222D02*
Y222338D01*
G01X1521990Y234209D02*
X1524977Y231222D01*
G01X1521990Y240177D02*
Y234209D01*
G01X1520908Y241259D02*
X1521990Y240177D01*
G01X1520908Y246140D02*
Y241259D01*
G01X1518953Y248095D02*
X1520908Y246140D01*
G01X1518953Y272249D02*
Y248095D01*
G01X1513730Y277472D02*
X1518953Y272249D01*
G01X1512446Y277472D02*
X1513730D01*
G01X1510724Y279194D02*
X1512446Y277472D01*
G01X1510724Y285202D02*
Y279194D01*
G01X1516549Y236775D02*
Y234278D01*
G01X1514824Y238500D02*
X1516549Y236775D01*
G01X1514824Y241179D02*
Y238500D01*
G01X1516159Y242514D02*
X1514824Y241179D01*
G01X1516159Y271181D02*
Y242514D01*
G01X1512420Y274920D02*
X1516159Y271181D01*
G01X1511388Y274920D02*
X1512420D01*
G01X1508172Y278136D02*
X1511388Y274920D01*
G01X1508172Y282863D02*
Y278136D01*
G01X1485943Y244500D02*
X1487500D01*
G01X1484019Y246424D02*
X1485943Y244500D01*
G01X1481476Y246424D02*
X1484019D01*
G01X1476848Y251052D02*
X1481476Y246424D01*
G01X1476848Y252705D02*
Y251052D01*
G01X1474548Y255005D02*
X1476848Y252705D01*
G01X1473298Y255005D02*
X1474548D01*
G01X1472400Y255903D02*
X1473298Y255005D01*
G01X1472400Y261195D02*
Y255903D01*
G01X1467369Y266226D02*
X1472400Y261195D01*
G01X1467369Y268457D02*
Y266226D01*
G01X1468386Y269474D02*
X1467369Y268457D01*
G01X1468386Y304914D02*
Y269474D01*
G01X1481777Y277153D02*
X1477558Y281372D01*
G01X1481777Y276144D02*
Y277153D01*
G01X1482848Y275073D02*
X1481777Y276144D01*
G01X1483856Y275073D02*
X1482848D01*
G01X1484717Y274212D02*
X1483856Y275073D01*
G01X1484717Y273204D02*
Y274212D01*
G01X1485997Y271924D02*
X1484717Y273204D01*
G01X1487006Y271924D02*
X1485997D01*
G01X1487867Y271063D02*
X1487006Y271924D01*
G01X1487867Y269845D02*
Y271063D01*
G01X1487006Y268984D02*
X1487867Y269845D01*
G01X1486863Y268984D02*
X1487006D01*
G01X1486574Y268695D02*
X1486863Y268984D01*
G01X1486574Y267127D02*
Y268695D01*
G01X1512500Y223499D02*
X1516628Y219371D01*
G01X1512500Y236272D02*
Y223499D01*
G01X1509979Y238793D02*
X1512500Y236272D01*
G01X1509979Y242202D02*
Y238793D01*
G01X1511400Y243623D02*
X1509979Y242202D01*
G01X1511400Y253360D02*
Y243623D01*
G01X1511700Y253660D02*
X1511400Y253360D01*
G01X1511700Y257930D02*
Y253660D01*
G01X1509973Y259657D02*
X1511700Y257930D01*
G01X1509973Y262958D02*
Y259657D01*
G01X1507515Y265416D02*
X1509973Y262958D01*
G01X1507515Y270007D02*
Y265416D01*
G01X1508832Y271324D02*
X1507515Y270007D01*
G01X1508832Y274216D02*
Y271324D01*
G01X1505868Y277180D02*
X1508832Y274216D01*
G01X1505868Y281907D02*
Y277180D01*
G01X1478628Y278222D02*
X1476948Y279902D01*
G01X1478628Y272994D02*
Y278222D01*
G01X1479698Y271924D02*
X1478628Y272994D01*
G01X1480707Y271924D02*
X1479698D01*
G01X1481568Y271063D02*
X1480707Y271924D01*
G01X1481568Y265722D02*
Y271063D01*
G01X1485670Y261620D02*
X1481568Y265722D01*
G01X1485670Y256211D02*
Y261620D01*
G01X1485669Y256210D02*
X1485670Y256211D01*
G01X1485669Y255588D02*
Y256210D01*
G01X1486862Y254395D02*
X1485669Y255588D01*
G01X1486862Y252880D02*
Y254395D01*
G01X1491190Y248552D02*
X1486862Y252880D01*
G01X1491190Y246503D02*
Y248552D01*
G01X1494586Y243107D02*
X1491190Y246503D01*
G01X1494586Y232596D02*
Y243107D01*
G01X1501013Y226169D02*
X1494586Y232596D01*
G01X1501013Y223750D02*
Y226169D01*
G01X1500351Y223088D02*
X1501013Y223750D01*
G01X1469356Y251252D02*
X1470950Y252846D01*
G01X1469179Y268790D02*
Y290724D01*
G01X1468350Y267961D02*
X1469179Y268790D01*
G01X1468350Y266309D02*
Y267961D01*
G01X1473400Y261259D02*
X1468350Y266309D01*
G01X1473400Y257402D02*
Y261259D01*
G01X1474096Y256706D02*
X1473400Y257402D01*
G01X1518585Y277391D02*
Y282679D01*
G01X1521956Y274020D02*
X1518585Y277391D01*
G01X1521956Y248943D02*
Y274020D01*
G01X1526904Y243995D02*
X1521956Y248943D01*
G01X1526904Y241097D02*
Y243995D01*
G01X1528883Y239118D02*
X1526904Y241097D01*
G01X1474520Y250941D02*
Y251740D01*
G01X1483935Y241526D02*
X1474520Y250941D01*
G01X1483935Y238383D02*
Y241526D01*
G01X1494345Y227973D02*
X1483935Y238383D01*
G01X1494345Y218746D02*
Y227973D01*
G01X1493957Y218358D02*
X1494345Y218746D01*
G01X1510066Y222665D02*
X1511856Y220875D01*
G01X1510066Y235446D02*
Y222665D01*
G01X1507035Y238477D02*
X1510066Y235446D01*
G01X1507035Y250988D02*
Y238477D01*
G01X1504196Y253827D02*
X1507035Y250988D01*
G01X1504196Y256706D02*
Y253827D01*
G01X1500908Y259994D02*
X1504196Y256706D01*
G01X1500908Y269688D02*
Y259994D01*
G01X1499904Y270692D02*
X1500908Y269688D01*
G01X1499904Y277904D02*
Y270692D01*
G01X1501257Y279257D02*
X1499904Y277904D01*
G01X1501257Y280563D02*
Y279257D01*
G01X1503161Y278467D02*
Y281353D01*
G01X1501808Y277114D02*
X1503161Y278467D01*
G01X1501808Y271482D02*
Y277114D01*
G01X1504034Y269256D02*
X1501808Y271482D01*
G01X1504034Y264465D02*
Y269256D01*
G01X1507624Y260875D02*
X1504034Y264465D01*
G01X1507624Y258746D02*
Y260875D01*
G01X1509148Y257222D02*
X1507624Y258746D01*
G01X1509148Y257218D02*
Y257222D01*
G01X1509305Y257061D02*
X1509148Y257218D01*
G01X1509305Y254622D02*
Y257061D01*
G01X1508187Y253504D02*
X1509305Y254622D01*
G01X1508187Y238955D02*
Y253504D01*
G01X1511218Y235924D02*
X1508187Y238955D01*
G01X1511218Y223143D02*
Y235924D01*
G01X1513008Y221353D02*
X1511218Y223143D01*
G01X1513008Y221352D02*
Y221353D01*
G01X1515476Y218884D02*
X1513008Y221352D01*
G01X1498658Y278887D02*
X1499681Y279910D01*
G01X1498658Y275406D02*
Y278887D01*
G01X1499152Y274912D02*
X1498658Y275406D01*
G01X1499152Y270380D02*
Y274912D01*
G01X1500156Y269376D02*
X1499152Y270380D01*
G01X1500156Y259682D02*
Y269376D01*
G01X1503444Y256394D02*
X1500156Y259682D01*
G01X1503444Y253515D02*
Y256394D01*
G01X1506283Y250676D02*
X1503444Y253515D01*
G01X1506283Y238165D02*
Y250676D01*
G01X1509303Y235145D02*
X1506283Y238165D01*
G01X1509303Y222084D02*
Y235145D01*
G01X1511104Y220283D02*
X1509303Y222084D01*
G01X1487089Y278411D02*
Y282360D01*
G01X1490206Y275294D02*
X1487089Y278411D01*
G01X1493404Y275294D02*
X1490206D01*
G01X1493498Y275200D02*
X1493404Y275294D01*
G01X1493523Y275200D02*
X1493498D01*
G01X1494000Y274723D02*
X1493523Y275200D01*
G01X1494000Y274698D02*
Y274723D01*
G01X1494323Y274375D02*
X1494000Y274698D01*
G01X1494323Y273073D02*
Y274375D01*
G01X1494000Y272750D02*
X1494323Y273073D01*
G01X1494000Y271774D02*
Y272750D01*
G01X1497500Y268274D02*
X1494000Y271774D01*
G01X1497500Y267056D02*
Y268274D01*
G01X1497410Y266966D02*
X1497500Y267056D01*
G01X1497410Y255194D02*
Y266966D01*
G01X1496944Y254728D02*
X1497410Y255194D01*
G01X1496944Y248723D02*
Y254728D01*
G01X1503627Y242040D02*
X1496944Y248723D01*
G01X1503627Y236753D02*
Y242040D01*
G01X1506547Y233833D02*
X1503627Y236753D01*
G01X1506547Y221332D02*
Y233833D01*
G01X1505948Y220733D02*
X1506547Y221332D01*
G01X1502517Y223126D02*
X1501855Y222464D01*
G01X1502517Y231946D02*
Y223126D01*
G01X1496336Y238127D02*
X1502517Y231946D01*
G01X1496336Y243523D02*
Y238127D01*
G01X1492694Y247165D02*
X1496336Y243523D01*
G01X1492694Y249176D02*
Y247165D01*
G01X1488366Y253504D02*
X1492694Y249176D01*
G01X1488366Y255019D02*
Y253504D01*
G01X1487423Y255962D02*
X1488366Y255019D01*
G01X1487423Y265756D02*
Y255962D01*
G01X1488076Y266409D02*
X1487423Y265756D01*
G01X1488076Y267913D02*
Y266409D01*
G01X1489147Y268984D02*
X1488076Y267913D01*
G01X1490155Y268984D02*
X1489147D01*
G01X1491016Y269845D02*
X1490155Y268984D01*
G01X1491016Y271063D02*
Y269845D01*
G01X1483647Y278432D02*
X1491016Y271063D01*
G01X1482638Y278432D02*
X1483647D01*
G01X1480098Y280972D02*
X1482638Y278432D01*
G01X1482257Y235500D02*
X1473499D01*
G01X1491265Y226492D02*
X1482257Y235500D01*
G01X1496030Y262289D02*
Y267665D01*
G01X1494034Y260293D02*
X1496030Y262289D01*
G01X1494034Y258751D02*
Y260293D01*
G01X1491623Y256340D02*
X1494034Y258751D01*
G01X1491623Y254854D02*
Y256340D01*
G01X1495951Y250526D02*
X1491623Y254854D01*
G01X1495951Y248515D02*
Y250526D01*
G01X1502728Y241738D02*
X1495951Y248515D01*
G01X1502728Y236342D02*
Y241738D01*
G01X1505773Y233297D02*
X1502728Y236342D01*
G01X1505773Y221657D02*
Y233297D01*
G01X1505113Y220997D02*
X1505773Y221657D01*
G01X1513906Y279147D02*
Y287723D01*
G01X1514358Y278695D02*
X1513906Y279147D01*
G01X1515153Y278695D02*
X1514358D01*
G01X1519471Y274377D02*
X1515153Y278695D01*
G01X1519471Y274365D02*
Y274377D01*
G01X1520147Y273689D02*
X1519471Y274365D01*
G01X1520147Y248579D02*
Y273689D01*
G01X1525324Y243402D02*
X1520147Y248579D01*
G01X1525324Y239477D02*
Y243402D01*
G01X1526400Y238401D02*
X1525324Y239477D01*
G01X1526400Y234700D02*
Y238401D01*
G01X1526150Y234450D02*
X1526400Y234700D01*
G01X1526150Y234300D02*
Y234450D01*
G01X1493593Y219058D02*
X1493205Y218670D01*
G01X1493593Y227661D02*
Y219058D01*
G01X1482375Y238879D02*
X1493593Y227661D01*
G01X1482375Y241175D02*
Y238879D01*
G01X1472640Y250910D02*
X1482375Y241175D01*
G01X1472640Y253535D02*
Y250910D01*
G01X1471603Y254572D02*
X1472640Y253535D01*
G01X1469506Y254572D02*
X1471603D01*
G01X1468228Y255850D02*
X1469506Y254572D01*
G01X1468228Y256665D02*
Y255850D01*
G01X1465893Y259000D02*
X1468228Y256665D01*
G01X1465894Y300405D02*
Y271799D01*
G01X1465631Y250252D02*
X1465627Y250256D01*
G01X1468703Y250252D02*
X1465631D01*
G01X1471055Y247900D02*
X1468703Y250252D01*
G01X1472600Y247900D02*
X1471055D01*
G01X1473300Y247200D02*
X1472600Y247900D01*
G01X1473300Y244400D02*
Y247200D01*
G01X1474050Y243650D02*
X1473300Y244400D01*
G01X1478016Y243650D02*
X1474050D01*
G01X1481623Y240043D02*
X1478016Y243650D01*
G01X1481623Y239191D02*
Y240043D01*
G01X1481622Y239190D02*
X1481623Y239191D01*
G01X1481622Y238568D02*
Y239190D01*
G01X1492841Y227349D02*
X1481622Y238568D01*
G01X1492841Y225495D02*
Y227349D01*
G01X1489572Y222226D02*
X1492841Y225495D01*
G01X1468391Y249500D02*
X1465319D01*
G01X1471604Y246287D02*
X1468391Y249500D01*
G01X1496400Y275600D02*
X1489700Y282300D01*
G01X1497400Y275600D02*
X1496400D01*
G01X1498400Y274600D02*
X1497400Y275600D01*
G01X1498400Y270068D02*
Y274600D01*
G01X1499404Y269064D02*
X1498400Y270068D01*
G01X1499404Y259370D02*
Y269064D01*
G01X1502692Y256082D02*
X1499404Y259370D01*
G01X1502692Y253203D02*
Y256082D01*
G01X1505531Y250364D02*
X1502692Y253203D01*
G01X1505531Y237543D02*
Y250364D01*
G01X1508551Y234523D02*
X1505531Y237543D01*
G01X1508551Y221468D02*
Y234523D01*
G01X1510352Y219667D02*
X1508551Y221468D01*
G01X1503469Y222731D02*
X1502807Y222069D01*
G01X1503469Y232341D02*
Y222731D01*
G01X1497381Y238429D02*
X1503469Y232341D01*
G01X1497381Y243825D02*
Y238429D01*
G01X1493646Y247560D02*
X1497381Y243825D01*
G01X1493646Y249470D02*
Y247560D01*
G01X1493647Y249471D02*
X1493646Y249470D01*
G01X1493647Y249570D02*
Y249471D01*
G01X1489318Y253899D02*
X1493647Y249570D01*
G01X1489318Y255414D02*
Y253899D01*
G01X1488678Y256054D02*
X1489318Y255414D01*
G01X1488678Y257008D02*
Y256054D01*
G01X1488679Y257009D02*
X1488678Y257008D01*
G01X1488679Y260283D02*
Y257009D01*
G01X1491127Y262731D02*
X1488679Y260283D01*
G01X1491127Y267954D02*
Y262731D01*
G01X1491767Y268594D02*
X1491127Y267954D01*
G01X1491767Y269532D02*
Y268594D01*
G01X1491768Y269533D02*
X1491767Y269532D01*
G01X1491768Y271375D02*
Y269533D01*
G01X1485200Y277943D02*
X1491768Y271375D01*
G01X1485200Y280028D02*
Y277943D01*
G01X1500261Y224062D02*
X1499599Y223400D01*
G01X1500261Y225857D02*
Y224062D01*
G01X1493625Y232493D02*
X1500261Y225857D01*
G01X1493625Y243004D02*
Y232493D01*
G01X1490438Y246191D02*
X1493625Y243004D01*
G01X1490438Y248240D02*
Y246191D01*
G01X1486110Y252568D02*
X1490438Y248240D01*
G01X1486110Y253895D02*
Y252568D01*
G01X1485003Y255002D02*
X1486110Y253895D01*
G01X1483500Y255002D02*
X1485003D01*
G01X1482424Y256078D02*
X1483500Y255002D01*
G01X1482424Y262899D02*
Y256078D01*
G01X1478628Y266695D02*
X1482424Y262899D01*
G01X1478628Y268984D02*
Y266695D01*
G01X1480098Y270454D02*
X1478628Y268984D01*
G01X1468980Y261256D02*
X1467704Y262532D01*
G01X1468980Y256162D02*
Y261256D01*
G01X1469818Y255324D02*
X1468980Y256162D01*
G01X1471915Y255324D02*
X1469818D01*
G01X1472987Y254252D02*
X1471915Y255324D01*
G01X1474237Y254252D02*
X1472987D01*
G01X1476096Y252393D02*
X1474237Y254252D01*
G01X1476096Y250430D02*
Y252393D01*
G01X1476500Y250026D02*
X1476096Y250430D01*
G01X1476500Y250025D02*
Y250026D01*
G01X1481957Y244568D02*
X1476500Y250025D01*
G01X1483457Y244568D02*
X1481957D01*
G01X1469004Y246287D02*
X1466543Y248748D01*
G01X1467497Y269988D02*
Y310324D01*
G01X1466460Y268951D02*
X1467497Y269988D01*
G01X1466460Y265754D02*
Y268951D01*
G01X1466006Y265300D02*
X1466460Y265754D01*
G01X1475444Y322646D02*
Y341423D01*
G01X1478524Y319566D02*
X1475444Y322646D01*
G01X1478524Y318900D02*
Y319566D01*
G01X1516138Y305117D02*
Y310749D01*
G01X1522658Y298597D02*
X1516138Y305117D01*
G01X1522658Y290787D02*
Y298597D01*
G01X1524843Y288602D02*
X1522658Y290787D01*
G01X1524843Y284381D02*
Y288602D01*
G01X1529600Y279624D02*
X1524843Y284381D01*
G01X1522596Y306998D02*
X1531320Y298274D01*
G01X1522596Y307620D02*
Y306998D01*
G01X1522597Y307621D02*
X1522596Y307620D01*
G01X1522597Y312488D02*
Y307621D01*
G01X1522596Y312489D02*
X1522597Y312488D01*
G01X1522596Y313111D02*
Y312489D01*
G01X1526263Y316778D02*
X1522596Y313111D01*
G01X1526263Y326545D02*
Y316778D01*
G01X1529113Y329395D02*
X1526263Y326545D01*
G01X1525102Y334712D02*
X1529113Y330701D01*
G01X1519667Y334712D02*
X1525102D01*
G01X1503769Y350610D02*
X1519667Y334712D01*
G01X1503159Y340132D02*
X1502041Y341250D01*
G01X1503159Y337571D02*
Y340132D01*
G01X1508200Y332530D02*
X1503159Y337571D01*
G01X1511600Y332530D02*
X1508200D01*
G01X1512220Y331910D02*
X1511600Y332530D01*
G01X1512220Y326280D02*
Y331910D01*
G01X1515711Y322789D02*
X1512220Y326280D01*
G01X1515711Y314955D02*
Y322789D01*
G01X1513610Y312854D02*
X1515711Y314955D01*
G01X1513610Y306581D02*
Y312854D01*
G01X1521506Y298684D02*
X1513610Y306581D01*
G01X1521506Y290309D02*
Y298684D01*
G01X1523691Y288124D02*
X1521506Y290309D01*
G01X1523691Y283509D02*
Y288124D01*
G01X1526081Y281119D02*
X1523691Y283509D01*
G01X1521092Y306374D02*
X1529633Y297833D01*
G01X1521092Y314565D02*
Y306374D01*
G01X1522292Y315765D02*
X1521092Y314565D01*
G01X1522292Y320152D02*
Y315765D01*
G01X1523470Y321330D02*
X1522292Y320152D01*
G01X1523470Y332620D02*
Y321330D01*
G01X1522307Y333783D02*
X1523470Y332620D01*
G01X1519532Y333783D02*
X1522307D01*
G01X1506713Y346602D02*
X1519532Y333783D01*
G01X1479002Y324168D02*
Y342821D01*
G01X1484717Y318453D02*
X1479002Y324168D01*
G01X1484717Y313832D02*
Y318453D01*
G01X1483247Y312362D02*
X1484717Y313832D01*
G01X1483247Y311397D02*
Y312362D01*
G01X1521844Y306686D02*
X1530568Y297962D01*
G01X1521844Y307932D02*
Y306686D01*
G01X1521845Y307933D02*
X1521844Y307932D01*
G01X1521845Y312176D02*
Y307933D01*
G01X1521844Y312177D02*
X1521845Y312176D01*
G01X1521844Y313423D02*
Y312177D01*
G01X1525511Y317090D02*
X1521844Y313423D01*
G01X1525511Y327458D02*
Y317090D01*
G01X1527537Y329484D02*
X1525511Y327458D01*
G01X1478418Y309717D02*
X1476948Y308247D01*
G01X1478418Y312006D02*
Y309717D01*
G01X1476350Y314074D02*
X1478418Y312006D01*
G01X1476350Y320416D02*
Y314074D01*
G01X1474692Y322074D02*
X1476350Y320416D01*
G01X1474692Y341111D02*
Y322074D01*
G01X1471553Y344250D02*
X1474692Y341111D01*
G01X1478250Y323708D02*
Y342249D01*
G01X1481679Y320279D02*
X1478250Y323708D01*
G01X1481679Y316534D02*
Y320279D01*
G01X1483247Y314966D02*
X1481679Y316534D01*
G01X1483247Y314546D02*
Y314966D01*
G01X1496964Y336940D02*
X1496400Y336376D01*
G01X1498910Y336940D02*
X1496964D01*
G01X1502350Y333500D02*
X1498910Y336940D01*
G01X1502350Y329456D02*
Y333500D01*
G01X1510206Y321600D02*
X1502350Y329456D01*
G01X1510206Y307992D02*
Y321600D01*
G01X1510205Y307991D02*
X1510206Y307992D01*
G01X1510205Y305088D02*
Y307991D01*
G01X1518102Y297189D02*
X1510205Y305088D01*
G01X1518102Y288898D02*
Y297189D01*
G01X1520287Y286713D02*
X1518102Y288898D01*
G01X1484927Y282442D02*
X1485951Y281418D01*
G01X1484927Y283451D02*
Y282442D01*
G01X1483646Y284732D02*
X1484927Y283451D01*
G01X1482638Y284732D02*
X1483646D01*
G01X1481777Y285593D02*
X1482638Y284732D01*
G01X1481777Y290360D02*
Y285593D01*
G01X1484717Y293300D02*
X1481777Y290360D01*
G01X1484717Y297328D02*
Y293300D01*
G01X1483247Y298798D02*
X1484717Y297328D01*
G01X1479754Y324520D02*
Y343133D01*
G01X1482764Y321510D02*
X1479754Y324520D01*
G01X1485109Y321510D02*
X1482764D01*
G01X1488076Y318543D02*
X1485109Y321510D01*
G01X1488076Y307103D02*
Y318543D01*
G01X1489275Y305904D02*
X1488076Y307103D01*
G01X1489275Y304298D02*
Y305904D01*
G01X1491149Y302424D02*
X1489275Y304298D01*
G01X1491149Y290125D02*
Y302424D01*
G01X1493290Y287984D02*
X1491149Y290125D01*
G01X1495300Y300979D02*
Y297300D01*
G01X1493349Y302930D02*
X1495300Y300979D01*
G01X1492891Y302930D02*
X1493349D01*
G01X1491965Y303856D02*
X1492891Y302930D01*
G01X1491965Y308014D02*
Y303856D01*
G01X1491016Y308963D02*
X1491965Y308014D01*
G01X1491016Y318334D02*
Y308963D01*
G01X1487088Y322262D02*
X1491016Y318334D01*
G01X1483076Y322262D02*
X1487088D01*
G01X1480506Y324832D02*
X1483076Y322262D01*
G01X1480506Y343445D02*
Y324832D01*
G01X1521989Y282411D02*
X1524379Y280021D01*
G01X1521989Y287419D02*
Y282411D01*
G01X1519804Y289604D02*
X1521989Y287419D01*
G01X1519804Y297894D02*
Y289604D01*
G01X1511907Y305793D02*
X1519804Y297894D01*
G01X1511907Y307285D02*
Y305793D01*
G01X1511908Y307286D02*
X1511907Y307285D01*
G01X1511908Y322305D02*
Y307286D01*
G01X1506090Y328123D02*
X1511908Y322305D01*
G01X1506090Y332220D02*
Y328123D01*
G01X1500141Y338169D02*
X1506090Y332220D01*
G01X1500141Y338631D02*
Y338169D01*
G01X1498592Y340180D02*
X1500141Y338631D01*
G01X1497180Y340180D02*
X1498592D01*
G01X1495724Y338724D02*
X1497180Y340180D01*
G01X1495445Y338724D02*
X1495724D01*
G01X1497350Y285534D02*
X1502009Y280875D01*
G01X1495465Y285534D02*
X1497350D01*
G01X1494900Y286099D02*
X1495465Y285534D01*
G01X1494900Y295300D02*
Y286099D01*
G01X1491901Y298299D02*
X1494900Y295300D01*
G01X1491901Y302736D02*
Y298299D01*
G01X1490896Y303741D02*
X1491901Y302736D01*
G01X1490896Y306897D02*
Y303741D01*
G01X1489546Y308247D02*
X1490896Y306897D01*
G01X1525052Y339297D02*
X1528091D01*
G01X1523094Y341255D02*
X1525052Y339297D01*
G01X1510851Y341400D02*
Y340113D01*
G01X1525995Y284859D02*
X1531624Y279230D01*
G01X1525995Y289080D02*
Y284859D01*
G01X1523810Y291265D02*
X1525995Y289080D01*
G01X1523810Y299075D02*
Y291265D01*
G01X1518436Y304449D02*
X1523810Y299075D01*
G01X1518436Y315667D02*
Y304449D01*
G01X1519636Y316867D02*
X1518436Y315667D01*
G01X1519636Y325164D02*
Y316867D01*
G01X1515430Y329370D02*
X1519636Y325164D01*
G01X1515430Y331560D02*
Y329370D01*
G01X1512660Y334330D02*
X1515430Y331560D01*
G01X1511709Y334330D02*
X1512660D01*
G01X1506900Y339139D02*
X1511709Y334330D01*
G01X1506900Y341461D02*
Y339139D01*
G01X1481258Y332308D02*
X1482550Y333600D01*
G01X1481258Y325542D02*
Y332308D01*
G01X1482700Y324100D02*
X1481258Y325542D01*
G01X1486451Y324100D02*
X1482700D01*
G01X1494181Y316370D02*
X1486451Y324100D01*
G01X1494181Y305798D02*
Y316370D01*
G01X1494970Y305009D02*
X1494181Y305798D01*
G01X1494970Y302439D02*
Y305009D01*
G01X1495145Y302264D02*
X1494970Y302439D01*
G01X1495145Y302263D02*
Y302264D01*
G01X1496199Y301209D02*
X1495145Y302263D01*
G01X1496199Y298480D02*
Y301209D01*
G01X1498517Y296162D02*
X1496199Y298480D01*
G01X1498517Y292188D02*
Y296162D01*
G01X1501837Y288868D02*
X1498517Y292188D01*
G01X1501837Y284307D02*
Y288868D01*
G01X1504716Y281428D02*
X1501837Y284307D01*
G01X1504141Y285264D02*
X1507020Y282385D01*
G01X1504141Y298078D02*
Y285264D01*
G01X1498985Y303234D02*
X1504141Y298078D01*
G01X1498985Y315116D02*
Y303234D01*
G01X1485702Y328399D02*
X1498985Y315116D01*
G01X1485702Y332002D02*
Y328399D01*
G01X1487000Y333300D02*
X1485702Y332002D01*
G01X1487867Y297328D02*
X1486397Y298798D01*
G01X1487867Y294000D02*
Y297328D01*
G01X1484927Y291060D02*
X1487867Y294000D01*
G01X1484927Y285593D02*
Y291060D01*
G01X1485788Y284732D02*
X1484927Y285593D01*
G01X1487335Y284732D02*
X1485788D01*
G01X1488076Y283991D02*
X1487335Y284732D01*
G01X1493414Y335870D02*
Y372564D01*
G01X1498896Y330388D02*
X1493414Y335870D01*
G01X1498896Y329395D02*
Y330388D01*
G01X1507708Y320583D02*
X1498896Y329395D01*
G01X1507708Y315988D02*
Y320583D01*
G01X1506002Y314282D02*
X1507708Y315988D01*
G01X1506002Y311881D02*
Y314282D01*
G01X1507673Y310210D02*
X1506002Y311881D01*
G01X1507673Y303525D02*
Y310210D01*
G01X1510305Y300893D02*
X1507673Y303525D01*
G01X1510305Y291901D02*
Y300893D01*
G01X1512378Y289828D02*
X1510305Y291901D01*
G01X1512865Y289828D02*
X1512378D01*
G01X1514658Y288035D02*
X1512865Y289828D01*
G01X1514658Y284342D02*
Y288035D01*
G01X1517081Y281919D02*
X1514658Y284342D01*
G01X1476948Y295649D02*
X1472328Y291029D01*
G01X1510324Y285602D02*
X1510724Y285202D01*
G01X1510324Y289154D02*
Y285602D01*
G01X1508175Y291303D02*
X1510324Y289154D01*
G01X1508175Y299284D02*
Y291303D01*
G01X1502689Y304770D02*
X1508175Y299284D01*
G01X1502689Y313918D02*
Y304770D01*
G01X1505530Y316759D02*
X1502689Y313918D01*
G01X1505530Y319870D02*
Y316759D01*
G01X1496780Y328620D02*
X1505530Y319870D01*
G01X1496780Y329628D02*
Y328620D01*
G01X1491510Y334898D02*
X1496780Y329628D01*
G01X1491510Y341960D02*
Y334898D01*
G01X1505293Y285742D02*
X1508172Y282863D01*
G01X1505293Y298556D02*
Y285742D01*
G01X1500137Y303712D02*
X1505293Y298556D01*
G01X1500137Y315594D02*
Y303712D01*
G01X1498297Y317434D02*
X1500137Y315594D01*
G01X1498297Y317461D02*
Y317434D01*
G01X1489010Y326748D02*
X1498297Y317461D01*
G01X1489010Y333600D02*
Y326748D01*
G01X1487010Y335600D02*
X1489010Y333600D01*
G01X1485941Y335600D02*
X1487010D01*
G01X1482585Y338956D02*
X1485941Y335600D01*
G01X1482585Y340856D02*
Y338956D01*
G01X1470249Y306777D02*
X1468386Y304914D01*
G01X1472328Y306777D02*
X1470249D01*
G01X1473798Y308247D02*
X1472328Y306777D01*
G01X1524101Y312488D02*
X1529734Y318121D01*
G01X1524101Y307621D02*
Y312488D01*
G01X1532824Y298898D02*
X1524101Y307621D01*
G01X1477348Y323296D02*
Y341853D01*
G01X1480922Y319722D02*
X1477348Y323296D01*
G01X1480922Y315862D02*
Y319722D01*
G01X1481777Y315007D02*
X1480922Y315862D01*
G01X1481777Y304489D02*
Y315007D01*
G01X1482848Y303418D02*
X1481777Y304489D01*
G01X1483856Y303418D02*
X1482848D01*
G01X1484717Y302557D02*
X1483856Y303418D01*
G01X1484717Y301339D02*
Y302557D01*
G01X1483646Y300268D02*
X1484717Y301339D01*
G01X1476339Y300268D02*
X1483646D01*
G01X1475478Y299407D02*
X1476339Y300268D01*
G01X1475478Y298189D02*
Y299407D01*
G01X1476434Y297233D02*
X1475478Y298189D01*
G01X1477443Y297233D02*
X1476434D01*
G01X1478418Y296258D02*
X1477443Y297233D01*
G01X1478418Y292900D02*
Y296258D01*
G01X1475478Y289960D02*
X1478418Y292900D01*
G01X1475478Y282443D02*
Y289960D01*
G01X1476549Y281372D02*
X1475478Y282443D01*
G01X1477558Y281372D02*
X1476549D01*
G01X1502989Y284786D02*
X1505868Y281907D01*
G01X1502989Y289672D02*
Y284786D01*
G01X1499746Y292915D02*
X1502989Y289672D01*
G01X1499746Y296655D02*
Y292915D01*
G01X1497286Y299115D02*
X1499746Y296655D01*
G01X1497286Y301230D02*
Y299115D01*
G01X1495897Y302619D02*
X1497286Y301230D01*
G01X1495897Y305226D02*
Y302619D01*
G01X1495609Y305514D02*
X1495897Y305226D01*
G01X1495609Y307823D02*
Y305514D01*
G01X1497712Y309926D02*
X1495609Y307823D01*
G01X1497712Y314759D02*
Y309926D01*
G01X1484219Y328252D02*
X1497712Y314759D01*
G01X1483347Y328252D02*
X1484219D01*
G01X1482524Y329075D02*
X1483347Y328252D01*
G01X1482524Y331124D02*
Y329075D01*
G01X1484126Y332726D02*
X1482524Y331124D01*
G01X1484126Y335186D02*
Y332726D01*
G01X1482386Y336926D02*
X1484126Y335186D01*
G01X1518438Y340960D02*
X1513076Y346322D01*
G01X1518438Y340035D02*
Y340960D01*
G01X1521432Y337041D02*
X1518438Y340035D01*
G01X1525965Y337041D02*
X1521432D01*
G01X1531369Y331637D02*
X1525965Y337041D01*
G01X1469502Y330000D02*
X1470276Y330774D01*
G01X1524962Y291743D02*
X1527147Y289558D01*
G01X1524962Y299555D02*
Y291743D01*
G01X1519588Y304929D02*
X1524962Y299555D01*
G01X1519588Y315189D02*
Y304929D01*
G01X1520788Y316389D02*
X1519588Y315189D01*
G01X1520788Y320776D02*
Y316389D01*
G01X1521668Y321656D02*
X1520788Y320776D01*
G01X1521668Y327792D02*
Y321656D01*
G01X1513925Y335535D02*
X1521668Y327792D01*
G01X1512134Y335535D02*
X1513925D01*
G01X1508300Y339369D02*
X1512134Y335535D01*
G01X1508300Y341719D02*
Y339369D01*
G01X1471852Y330121D02*
X1470731Y329000D01*
G01X1471852Y331484D02*
Y330121D01*
G01X1469731Y333605D02*
X1471852Y331484D01*
G01X1469731Y336541D02*
Y333605D01*
G01X1480098Y311618D02*
Y311397D01*
G01X1478378Y313338D02*
X1480098Y311618D01*
G01X1478378Y316675D02*
Y313338D01*
G01X1479994Y318291D02*
X1478378Y316675D01*
G01X1479994Y319509D02*
Y318291D01*
G01X1476596Y322907D02*
X1479994Y319509D01*
G01X1476596Y341335D02*
Y322907D01*
G01X1509100Y339633D02*
Y342059D01*
G01X1512445Y336288D02*
X1509100Y339633D01*
G01X1514236Y336288D02*
X1512445D01*
G01X1522420Y328104D02*
X1514236Y336288D01*
G01X1522420Y321968D02*
Y328104D01*
G01X1522421Y321967D02*
X1522420Y321968D01*
G01X1522421Y321345D02*
Y321967D01*
G01X1521540Y320464D02*
X1522421Y321345D01*
G01X1521540Y316077D02*
Y320464D01*
G01X1520340Y314877D02*
X1521540Y316077D01*
G01X1520340Y305241D02*
Y314877D01*
G01X1528476Y297105D02*
X1520340Y305241D01*
G01X1524740Y338545D02*
X1527779D01*
G01X1522342Y340943D02*
X1524740Y338545D01*
G01X1522342Y341653D02*
Y340943D01*
G01X1481776Y303419D02*
X1483247Y301948D01*
G01X1473190Y303419D02*
X1481776D01*
G01X1472119Y302348D02*
X1473190Y303419D01*
G01X1472119Y293664D02*
Y302348D01*
G01X1469179Y290724D02*
X1472119Y293664D01*
G01X1500400Y333000D02*
X1498600Y334800D01*
G01X1500400Y328999D02*
Y333000D01*
G01X1508460Y320939D02*
X1500400Y328999D01*
G01X1508460Y315676D02*
Y320939D01*
G01X1506754Y313970D02*
X1508460Y315676D01*
G01X1506754Y312270D02*
Y313970D01*
G01X1508468Y310556D02*
X1506754Y312270D01*
G01X1508468Y304418D02*
Y310556D01*
G01X1516298Y296586D02*
X1508468Y304418D01*
G01X1516298Y284966D02*
Y296586D01*
G01X1518585Y282679D02*
X1516298Y284966D01*
G01X1497599Y284221D02*
X1501257Y280563D01*
G01X1493980Y284221D02*
X1497599D01*
G01X1489569Y288632D02*
X1493980Y284221D01*
G01X1489569Y296962D02*
Y288632D01*
G01X1488076Y298455D02*
X1489569Y296962D01*
G01X1488076Y305732D02*
Y298455D01*
G01X1486397Y307411D02*
X1488076Y305732D01*
G01X1486397Y308247D02*
Y307411D01*
G01X1516934Y340201D02*
X1502112Y355023D01*
G01X1516934Y339283D02*
Y340201D01*
G01X1520680Y335537D02*
X1516934Y339283D01*
G01X1525341Y335537D02*
X1520680D01*
G01X1529865Y331013D02*
X1525341Y335537D01*
G01X1527015Y326233D02*
X1529865Y329083D01*
G01X1527015Y316466D02*
Y326233D01*
G01X1523349Y312800D02*
X1527015Y316466D01*
G01X1523349Y307309D02*
Y312800D01*
G01X1532072Y298586D02*
X1523349Y307309D01*
G01X1525653Y336289D02*
X1530617Y331325D01*
G01X1520992Y336289D02*
X1525653D01*
G01X1517686Y339595D02*
X1520992Y336289D01*
G01X1517686Y340648D02*
Y339595D01*
G01X1508600Y349734D02*
X1517686Y340648D01*
G01X1496900Y290716D02*
Y293900D01*
G01X1498217Y289399D02*
X1496900Y290716D01*
G01X1498217Y286297D02*
Y289399D01*
G01X1503161Y281353D02*
X1498217Y286297D01*
G01X1519190Y340347D02*
Y341535D01*
G01X1521744Y337793D02*
X1519190Y340347D01*
G01X1526277Y337793D02*
X1521744D01*
G01X1532121Y331949D02*
X1526277Y337793D01*
G01X1487089Y282360D02*
X1486397Y283052D01*
G01X1480098D02*
Y280972D01*
G01X1492662Y335558D02*
Y363880D01*
G01X1498144Y330076D02*
X1492662Y335558D01*
G01X1498144Y329055D02*
Y330076D01*
G01X1506810Y320389D02*
X1498144Y329055D01*
G01X1506810Y316154D02*
Y320389D01*
G01X1504028Y313372D02*
X1506810Y316154D01*
G01X1504028Y305299D02*
Y313372D01*
G01X1509459Y299868D02*
X1504028Y305299D01*
G01X1509459Y291683D02*
Y299868D01*
G01X1512067Y289075D02*
X1509459Y291683D01*
G01X1512554Y289075D02*
X1512067D01*
G01X1513906Y287723D02*
X1512554Y289075D01*
G01X1470483Y333917D02*
Y336853D01*
G01X1473940Y330460D02*
X1470483Y333917D01*
G01X1473940Y321762D02*
Y330460D01*
G01X1475268Y320434D02*
X1473940Y321762D01*
G01X1475268Y307638D02*
Y320434D01*
G01X1474407Y306777D02*
X1475268Y307638D01*
G01X1473398Y306777D02*
X1474407D01*
G01X1472200Y305579D02*
X1473398Y306777D01*
G01X1472200Y304534D02*
Y305579D01*
G01X1470649Y302983D02*
X1472200Y304534D01*
G01X1470649Y301948D02*
Y302983D01*
G01X1487189Y286202D02*
X1486397D01*
G01X1489700Y283691D02*
X1487189Y286202D01*
G01X1489700Y282300D02*
Y283691D01*
G01X1483646Y281582D02*
X1485200Y280028D01*
G01X1482638Y281582D02*
X1483646D01*
G01X1481660Y282560D02*
X1482638Y281582D01*
G01X1481660Y283569D02*
Y282560D01*
G01X1480707Y284522D02*
X1481660Y283569D01*
G01X1479699Y284522D02*
X1480707D01*
G01X1478628Y285593D02*
X1479699Y284522D01*
G01X1478628Y290105D02*
Y285593D01*
G01X1481568Y293045D02*
X1478628Y290105D01*
G01X1481568Y296258D02*
Y293045D01*
G01X1480678Y297148D02*
X1481568Y296258D01*
G01X1478598Y297148D02*
X1480678D01*
G01X1476948Y298798D02*
X1478598Y297148D01*
G01X1472328Y313076D02*
X1473798Y314546D01*
G01X1470249Y313076D02*
X1472328D01*
G01X1467497Y310324D02*
X1470249Y313076D01*
G01X1471017Y345850D02*
X1469000D01*
G01X1475444Y341423D02*
X1471017Y345850D01*
G01X1502970Y350610D02*
X1503769D01*
G01X1526322Y355231D02*
X1530188Y351365D01*
G01X1526322Y361094D02*
Y355231D01*
G01X1524195Y363221D02*
X1526322Y361094D01*
G01X1524195Y378165D02*
Y363221D01*
G01X1523005Y379355D02*
X1524195Y378165D01*
G01X1523005Y381907D02*
Y379355D01*
G01X1524195Y383097D02*
X1523005Y381907D01*
G01X1524195Y385121D02*
Y383097D01*
G01X1523005Y386311D02*
X1524195Y385121D01*
G01X1523005Y388716D02*
Y386311D01*
G01X1524575Y390286D02*
X1523005Y388716D01*
G01X1524575Y392193D02*
Y390286D01*
G01X1522354Y394414D02*
X1524575Y392193D01*
G01X1520675Y394414D02*
X1522354D01*
G01X1502041Y341250D02*
X1499829D01*
G01X1502922Y346602D02*
X1506713D01*
G01X1501360Y348164D02*
X1502922Y346602D01*
G01X1501360Y359840D02*
Y348164D01*
G01X1500800Y360400D02*
X1501360Y359840D01*
G01X1500800Y374794D02*
Y360400D01*
G01X1499605Y402713D02*
X1500795Y403903D01*
G01X1499605Y400876D02*
Y402713D01*
G01X1497655Y398926D02*
X1499605Y400876D01*
G01X1497655Y397015D02*
Y398926D01*
G01X1495428Y394788D02*
X1497655Y397015D01*
G01X1495428Y393358D02*
Y394788D01*
G01X1493755Y391685D02*
X1495428Y393358D01*
G01X1493755Y390255D02*
Y391685D01*
G01X1491805Y388305D02*
X1493755Y390255D01*
G01X1491805Y387763D02*
Y388305D01*
G01X1489886Y385844D02*
X1491805Y387763D01*
G01X1486874Y385844D02*
X1489886D01*
G01X1486630Y385600D02*
X1486874Y385844D01*
G01X1472289Y385600D02*
X1486630D01*
G01X1471370Y384681D02*
X1472289Y385600D01*
G01X1471370Y383172D02*
Y384681D01*
G01X1472322Y382220D02*
X1471370Y383172D01*
G01X1475260Y382220D02*
X1472322D01*
G01X1478290Y379190D02*
X1475260Y382220D01*
G01X1478290Y371690D02*
Y379190D01*
G01X1471210Y364610D02*
X1478290Y371690D01*
G01X1471210Y363530D02*
Y364610D01*
G01X1469060Y361380D02*
X1471210Y363530D01*
G01X1466620Y361380D02*
X1469060D01*
G01X1479002Y342821D02*
X1471175Y350648D01*
G01X1477605Y387105D02*
X1484600Y394100D01*
G01X1471666Y387105D02*
X1477605D01*
G01X1469864Y385303D02*
X1471666Y387105D01*
G01X1469864Y380099D02*
Y385303D01*
G01X1471821Y378142D02*
X1469864Y380099D01*
G01X1471821Y378141D02*
Y378142D01*
G01X1472082Y377880D02*
X1471821Y378141D01*
G01X1474650Y377880D02*
X1472082D01*
G01X1475300Y377230D02*
X1474650Y377880D01*
G01X1475300Y372100D02*
Y377230D01*
G01X1471387Y368187D02*
X1475300Y372100D01*
G01X1466417Y368187D02*
X1471387D01*
G01X1478250Y342249D02*
X1470603Y349896D01*
G01X1479754Y343133D02*
X1471487Y351400D01*
G01X1527074Y357155D02*
X1531638Y352591D01*
G01X1524955Y363525D02*
X1527074Y361406D01*
G01X1524955Y378167D02*
Y363525D01*
G01X1526399Y379611D02*
X1524955Y378167D01*
G01X1526399Y381927D02*
Y379611D01*
G01X1528095Y383623D02*
X1526399Y381927D01*
G01X1526905Y386293D02*
X1528095Y385103D01*
G01X1526905Y388451D02*
Y386293D01*
G01X1528095Y389641D02*
X1526905Y388451D01*
G01X1525560Y394414D02*
X1528095Y391879D01*
G01X1524575Y394414D02*
X1525560D01*
G01X1471751Y352200D02*
X1480506Y343445D01*
G01X1520295Y379053D02*
X1519105Y380243D01*
G01X1520295Y369790D02*
Y379053D01*
G01X1522698Y367387D02*
X1520295Y369790D01*
G01X1522698Y364542D02*
Y367387D01*
G01X1520900Y362744D02*
X1522698Y364542D01*
G01X1520900Y360765D02*
Y362744D01*
G01X1522752Y358913D02*
X1520900Y360765D01*
G01X1522752Y355349D02*
Y358913D01*
G01X1522757Y355344D02*
X1522752Y355349D01*
G01X1522757Y353414D02*
Y355344D01*
G01X1522752Y353409D02*
X1522757Y353414D01*
G01X1522752Y350833D02*
Y353409D01*
G01X1525940Y347645D02*
X1522752Y350833D01*
G01X1529672Y347645D02*
X1525940D01*
G01X1505400Y357800D02*
X1507200Y356000D01*
G01X1505400Y359900D02*
Y357800D01*
G01X1506500Y361000D02*
X1505400Y359900D01*
G01X1506500Y367900D02*
Y361000D01*
G01X1504700Y369700D02*
X1506500Y367900D01*
G01X1504700Y374200D02*
Y369700D01*
G01X1523094Y341965D02*
Y341255D01*
G01X1521731Y343328D02*
X1523094Y341965D01*
G01X1519525Y343328D02*
X1521731D01*
G01X1514324Y348529D02*
X1519525Y343328D01*
G01X1514324Y351756D02*
Y348529D01*
G01X1511875Y354205D02*
X1514324Y351756D01*
G01X1511875Y359936D02*
Y354205D01*
G01X1515328Y363389D02*
X1511875Y359936D01*
G01X1523629Y344636D02*
X1528425D01*
G01X1519319Y348946D02*
X1523629Y344636D01*
G01X1519319Y350793D02*
Y348946D01*
G01X1517233Y352879D02*
X1519319Y350793D01*
G01X1517233Y361340D02*
Y352879D01*
G01X1517650Y361757D02*
X1517233Y361340D01*
G01X1517650Y364351D02*
Y361757D01*
G01X1517305Y364696D02*
X1517650Y364351D01*
G01X1517305Y367558D02*
Y364696D01*
G01X1514692Y370171D02*
X1517305Y367558D01*
G01X1514692Y374895D02*
Y370171D01*
G01X1513255Y376332D02*
X1514692Y374895D01*
G01X1513255Y378199D02*
Y376332D01*
G01X1506401Y345850D02*
X1510851Y341400D01*
G01X1502610Y345850D02*
X1506401D01*
G01X1500600Y347860D02*
X1502610Y345850D01*
G01X1500600Y357714D02*
Y347860D01*
G01X1498309Y360005D02*
X1500600Y357714D01*
G01X1525005Y345388D02*
X1528737D01*
G01X1520071Y350322D02*
X1525005Y345388D01*
G01X1520071Y351136D02*
Y350322D01*
G01X1517985Y353222D02*
X1520071Y351136D01*
G01X1517985Y361028D02*
Y353222D01*
G01X1518402Y361445D02*
X1517985Y361028D01*
G01X1518402Y364820D02*
Y361445D01*
G01X1518056Y365166D02*
X1518402Y364820D01*
G01X1518056Y367870D02*
Y365166D01*
G01X1516395Y369531D02*
X1518056Y367870D01*
G01X1516395Y378165D02*
Y369531D01*
G01X1505391Y342970D02*
X1506900Y341461D01*
G01X1501600Y342970D02*
X1505391D01*
G01X1496000Y348570D02*
X1501600Y342970D01*
G01X1496000Y350000D02*
Y348570D01*
G01X1506645Y402310D02*
X1505075Y403880D01*
G01X1506645Y398205D02*
Y402310D01*
G01X1503505Y395065D02*
X1506645Y398205D01*
G01X1503505Y393635D02*
Y395065D01*
G01X1501555Y391685D02*
X1503505Y393635D01*
G01X1501555Y391143D02*
Y391685D01*
G01X1498845Y388433D02*
X1501555Y391143D01*
G01X1498845Y387003D02*
Y388433D01*
G01X1497088Y385246D02*
X1498845Y387003D01*
G01X1497088Y382928D02*
Y385246D01*
G01X1495705Y381545D02*
X1497088Y382928D01*
G01X1495705Y380115D02*
Y381545D01*
G01X1493755Y378165D02*
X1495705Y380115D01*
G01X1493755Y372905D02*
Y378165D01*
G01X1493414Y372564D02*
X1493755Y372905D01*
G01X1487900Y345570D02*
X1491510Y341960D01*
G01X1487900Y354310D02*
Y345570D01*
G01X1490560Y356970D02*
X1487900Y354310D01*
G01X1490560Y370821D02*
Y356970D01*
G01X1489475Y371906D02*
X1490560Y370821D01*
G01X1489475Y380894D02*
Y371906D01*
G01X1470653Y387900D02*
X1473962D01*
G01X1468928Y386175D02*
X1470653Y387900D01*
G01X1468928Y379971D02*
Y386175D01*
G01X1471069Y377830D02*
X1468928Y379971D01*
G01X1471069Y377829D02*
Y377830D01*
G01X1471450Y377448D02*
X1471069Y377829D01*
G01X1471450Y374168D02*
Y377448D01*
G01X1466727Y369445D02*
X1471450Y374168D01*
G01X1477348Y341853D02*
X1470057Y349144D01*
G01X1525628Y346893D02*
X1529360D01*
G01X1522000Y350521D02*
X1525628Y346893D01*
G01X1522000Y353721D02*
Y350521D01*
G01X1522005Y353726D02*
X1522000Y353721D01*
G01X1522005Y355032D02*
Y353726D01*
G01X1522000Y355037D02*
X1522005Y355032D01*
G01X1522000Y358601D02*
Y355037D01*
G01X1520148Y360453D02*
X1522000Y358601D01*
G01X1520148Y363055D02*
Y360453D01*
G01X1521947Y364854D02*
X1520148Y363055D01*
G01X1521947Y366780D02*
Y364854D01*
G01X1521196Y367531D02*
X1521947Y366780D01*
G01X1521196Y367538D02*
Y367531D01*
G01X1518725Y370009D02*
X1521196Y367538D01*
G01X1518725Y377514D02*
Y370009D01*
G01X1476097Y404787D02*
X1471910Y400600D01*
G01X1505789Y344230D02*
X1508300Y341719D01*
G01X1501990Y344230D02*
X1505789D01*
G01X1498246Y347974D02*
X1501990Y344230D01*
G01X1498246Y352305D02*
Y347974D01*
G01X1512503Y380522D02*
X1512875Y380894D01*
G01X1512503Y375219D02*
Y380522D01*
G01X1513335Y374387D02*
X1512503Y375219D01*
G01X1513335Y370465D02*
Y374387D01*
G01X1516475Y367325D02*
X1513335Y370465D01*
G01X1516475Y364463D02*
Y367325D01*
G01X1516898Y364040D02*
X1516475Y364463D01*
G01X1516898Y362069D02*
Y364040D01*
G01X1516463Y361634D02*
X1516898Y362069D01*
G01X1514958Y361634D02*
X1516463D01*
G01X1512649Y359325D02*
X1514958Y361634D01*
G01X1512649Y354501D02*
Y359325D01*
G01X1515077Y352073D02*
X1512649Y354501D01*
G01X1515077Y351445D02*
Y352073D01*
G01X1515076Y351444D02*
X1515077Y351445D01*
G01X1515076Y348986D02*
Y351444D01*
G01X1519541Y344521D02*
X1515076Y348986D01*
G01X1521803Y344521D02*
X1519541D01*
G01X1523009Y343315D02*
X1521803Y344521D01*
G01X1526778Y343315D02*
X1523009D01*
G01X1527959Y342134D02*
X1526778Y343315D01*
G01X1470418Y374200D02*
X1466918Y370700D01*
G01X1470418Y377392D02*
Y374200D01*
G01X1467989Y379821D02*
X1470418Y377392D01*
G01X1467989Y386300D02*
Y379821D01*
G01X1470469Y388780D02*
X1467989Y386300D01*
G01X1473143Y388780D02*
X1470469D01*
G01X1473144Y388781D02*
X1473143Y388780D01*
G01X1473462Y388781D02*
X1473144D01*
G01X1479057Y394376D02*
X1473462Y388781D01*
G01X1479057Y399563D02*
Y394376D01*
G01X1482852Y403358D02*
X1479057Y399563D01*
G01X1486209Y402763D02*
X1485614Y403358D01*
G01X1491853Y402763D02*
X1486209D01*
G01X1492074Y402984D02*
X1491853Y402763D01*
G01X1492995Y403903D02*
X1492076Y402984D01*
G01X1470505Y347426D02*
X1476596Y341335D01*
G01X1499847Y353304D02*
X1498246Y354905D01*
G01X1499847Y347533D02*
Y353304D01*
G01X1502300Y345080D02*
X1499847Y347533D01*
G01X1506079Y345080D02*
X1502300D01*
G01X1509100Y342059D02*
X1506079Y345080D01*
G01X1496488Y402539D02*
X1497074Y403125D01*
G01X1487423Y387530D02*
X1487953Y388060D01*
G01X1484430Y387530D02*
X1487423D01*
G01X1483297Y388663D02*
X1484430Y387530D01*
G01X1483217Y388663D02*
X1483297D01*
G01X1482990Y388890D02*
X1483217Y388663D01*
G01X1481200Y388890D02*
X1482990D01*
G01X1479100Y386790D02*
X1481200Y388890D01*
G01X1478354Y386790D02*
X1479100D01*
G01X1477916Y386352D02*
X1478354Y386790D01*
G01X1471977Y386352D02*
X1477916D01*
G01X1470617Y384992D02*
X1471977Y386352D01*
G01X1470617Y380472D02*
Y384992D01*
G01X1472269Y378820D02*
X1470617Y380472D01*
G01X1475210Y378820D02*
X1472269D01*
G01X1476360Y377670D02*
X1475210Y378820D01*
G01X1476360Y371771D02*
Y377670D01*
G01X1467597Y363000D02*
X1476360Y371771D01*
G01X1521419Y342576D02*
X1522342Y341653D01*
G01X1520415Y342576D02*
X1521419D01*
G01X1520414Y342575D02*
X1520415Y342576D01*
G01X1519792Y342575D02*
X1520414D01*
G01X1519791Y342576D02*
X1519792Y342575D01*
G01X1519213Y342576D02*
X1519791D01*
G01X1513572Y348217D02*
X1519213Y342576D01*
G01X1513572Y351438D02*
Y348217D01*
G01X1511123Y353887D02*
X1513572Y351438D01*
G01X1511123Y360287D02*
Y353887D01*
G01X1512050Y361214D02*
X1511123Y360287D01*
G01X1512050Y373259D02*
Y361214D01*
G01X1510925Y374384D02*
X1512050Y373259D01*
G01X1510925Y377514D02*
Y374384D01*
G01X1511901Y394414D02*
X1512875D01*
G01X1511190Y393703D02*
X1511901Y394414D01*
G01X1501800Y369465D02*
Y376184D01*
G01X1502112Y355023D02*
Y360152D01*
G01X1508600Y351700D02*
Y349734D01*
G01X1508789Y351889D02*
X1508600Y351700D01*
G01X1508789Y362650D02*
Y351889D01*
G01X1509652Y363513D02*
X1508789Y362650D01*
G01X1509652Y363823D02*
Y363513D01*
G01X1509653Y363824D02*
X1509652Y363823D01*
G01X1509653Y364134D02*
Y363824D01*
G01X1509654Y364135D02*
X1509653Y364134D01*
G01X1509654Y367546D02*
Y364135D01*
G01X1507215Y369985D02*
X1509654Y367546D01*
G01X1507215Y373735D02*
Y369985D01*
G01X1505450Y375500D02*
X1507215Y373735D01*
G01X1511155Y371593D02*
X1509355Y373393D01*
G01X1511155Y361383D02*
Y371593D01*
G01X1510371Y360599D02*
X1511155Y361383D01*
G01X1510371Y353559D02*
Y360599D01*
G01X1512820Y351110D02*
X1510371Y353559D01*
G01X1512820Y347905D02*
Y351110D01*
G01X1519190Y341535D02*
X1512820Y347905D01*
G01X1492995Y380514D02*
X1493375Y380894D01*
G01X1492995Y373506D02*
Y380514D01*
G01X1492663Y373174D02*
X1492995Y373506D01*
G01X1492663Y363881D02*
Y373174D01*
G01X1492662Y363880D02*
X1492663Y363881D01*
G01X1510388Y402870D02*
X1512558D01*
G01X1509355Y403903D02*
X1510388Y402870D01*
G01X1502745Y401825D02*
X1501555Y403015D01*
G01X1502745Y399635D02*
Y401825D01*
G01X1501555Y398445D02*
X1502745Y399635D01*
G01X1501555Y397775D02*
Y398445D01*
G01X1499585Y395805D02*
X1501555Y397775D01*
G01X1499585Y393615D02*
Y395805D01*
G01X1497655Y391685D02*
X1499585Y393615D01*
G01X1497655Y390255D02*
Y391685D01*
G01X1495705Y388305D02*
X1497655Y390255D01*
G01X1495705Y386875D02*
Y388305D01*
G01X1492995Y384165D02*
X1495705Y386875D01*
G01X1492995Y383623D02*
Y384165D01*
G01X1492076Y382704D02*
X1492995Y383623D01*
G01X1489064Y382704D02*
X1492076D01*
G01X1487940Y381580D02*
X1489064Y382704D01*
G01X1478250Y381580D02*
X1487940D01*
G01X1475800Y384030D02*
X1478250Y381580D01*
G01X1472940Y384030D02*
X1475800D01*
G01X1517155Y380514D02*
X1516775Y380894D01*
G01X1517155Y370509D02*
Y380514D01*
G01X1521196Y366468D02*
X1517155Y370509D01*
G01X1521196Y365166D02*
Y366468D01*
G01X1519246Y363216D02*
X1521196Y365166D01*
G01X1519246Y362936D02*
Y363216D01*
G01X1519200Y362890D02*
X1519246Y362936D01*
G01X1519200Y362889D02*
Y362890D01*
G01X1519154Y362843D02*
X1519200Y362889D01*
G01X1519154Y361133D02*
Y362843D01*
G01X1518756Y360735D02*
X1519154Y361133D01*
G01X1518756Y357741D02*
Y360735D01*
G01X1518737Y357722D02*
X1518756Y357741D01*
G01X1518737Y356416D02*
Y357722D01*
G01X1518756Y356397D02*
X1518737Y356416D01*
G01X1518756Y353515D02*
Y356397D01*
G01X1520823Y351448D02*
X1518756Y353515D01*
G01X1520823Y351417D02*
Y351448D01*
G01X1520824Y351416D02*
X1520823Y351417D01*
G01X1520824Y350633D02*
Y351416D01*
G01X1525316Y346141D02*
X1520824Y350633D01*
G01X1529048Y346141D02*
X1525316D01*
G01X1509350Y408350D02*
X1511926Y405774D01*
G01X1508613Y408350D02*
X1509350D01*
G01X1506224Y410739D02*
X1508613Y408350D01*
G01X1501759Y410739D02*
X1506224D01*
G01X1499605Y408585D02*
X1501759Y410739D01*
G01X1499605Y407155D02*
Y408585D01*
G01X1500795Y405965D02*
X1499605Y407155D01*
G01X1500795Y403903D02*
Y405965D01*
G01X1505075Y403880D02*
Y407934D01*
G01X1486669Y463094D02*
Y469248D01*
G01X1485038Y461463D02*
X1486669Y463094D01*
G01X1485038Y458394D02*
Y461463D01*
G01X1489095Y454337D02*
X1485038Y458394D01*
G01X1489095Y452722D02*
Y454337D01*
G01X1487905Y451532D02*
X1489095Y452722D01*
G01X1487905Y448225D02*
Y451532D01*
G01X1491514Y444616D02*
X1487905Y448225D01*
G01X1491514Y442842D02*
Y444616D01*
G01X1493046Y441310D02*
X1491514Y442842D01*
G01X1493046Y439336D02*
Y441310D01*
G01X1494945Y437437D02*
X1493046Y439336D01*
G01X1494945Y435909D02*
Y437437D01*
G01X1493755Y434719D02*
X1494945Y435909D01*
G01X1493755Y432343D02*
Y434719D01*
G01X1494945Y431153D02*
X1493755Y432343D01*
G01X1494945Y427563D02*
Y431153D01*
G01X1493302Y425920D02*
X1494945Y427563D01*
G01X1493302Y423602D02*
Y425920D01*
G01X1491805Y422105D02*
X1493302Y423602D01*
G01X1491805Y419915D02*
Y422105D01*
G01X1492995Y418725D02*
X1491805Y419915D01*
G01X1492995Y417678D02*
Y418725D01*
G01X1494945Y415728D02*
X1492995Y417678D01*
G01X1494945Y413915D02*
Y415728D01*
G01X1496895Y411965D02*
X1494945Y413915D01*
G01X1496895Y410663D02*
Y411965D01*
G01X1495697Y409465D02*
X1496895Y410663D01*
G01X1495697Y404351D02*
Y409465D01*
G01X1495409Y404063D02*
X1495697Y404351D01*
G01X1495409Y403740D02*
Y404063D01*
G01X1476097Y451037D02*
Y404787D01*
G01X1470664Y456470D02*
X1476097Y451037D01*
G01X1470664Y464136D02*
Y456470D01*
G01X1485614Y403358D02*
X1482852D01*
G01X1492076Y402984D02*
X1492074D01*
G01X1492995Y404927D02*
Y403903D01*
G01X1493600Y405532D02*
X1492995Y404927D01*
G01X1493600Y405938D02*
Y405532D01*
G01X1494945Y407283D02*
X1493600Y405938D01*
G01X1494945Y408585D02*
Y407283D01*
G01X1492995Y410535D02*
X1494945Y408585D01*
G01X1492995Y411965D02*
Y410535D01*
G01X1491045Y413915D02*
X1492995Y411965D01*
G01X1491045Y415345D02*
Y413915D01*
G01X1489855Y416535D02*
X1491045Y415345D01*
G01X1489855Y417965D02*
Y416535D01*
G01X1486732Y421088D02*
X1489855Y417965D01*
G01X1479191Y421088D02*
X1486732D01*
G01X1477601Y422678D02*
X1479191Y421088D01*
G01X1477601Y451661D02*
Y422678D01*
G01X1477600Y451662D02*
X1477601Y451661D01*
G01X1477600Y452936D02*
Y451662D01*
G01X1472700Y457836D02*
X1477600Y452936D01*
G01X1472700Y464732D02*
Y457836D01*
G01X1487606Y462748D02*
Y471664D01*
G01X1485955Y461097D02*
X1487606Y462748D01*
G01X1485955Y459795D02*
Y461097D01*
G01X1486874Y458876D02*
X1485955Y459795D01*
G01X1489886Y458876D02*
X1486874D01*
G01X1491045Y457717D02*
X1489886Y458876D01*
G01X1491045Y455905D02*
Y457717D01*
G01X1489855Y454715D02*
X1491045Y455905D01*
G01X1489855Y453035D02*
Y454715D01*
G01X1491805Y451085D02*
X1489855Y453035D01*
G01X1491805Y449655D02*
Y451085D01*
G01X1492995Y448465D02*
X1491805Y449655D01*
G01X1492995Y446609D02*
Y448465D01*
G01X1495110Y444494D02*
X1492995Y446609D01*
G01X1495110Y442991D02*
Y444494D01*
G01X1496895Y441206D02*
X1495110Y442991D01*
G01X1496895Y439515D02*
Y441206D01*
G01X1495705Y438325D02*
X1496895Y439515D01*
G01X1495705Y436135D02*
Y438325D01*
G01X1496895Y434945D02*
X1495705Y436135D01*
G01X1496895Y432755D02*
Y434945D01*
G01X1495705Y431565D02*
X1496895Y432755D01*
G01X1495705Y427562D02*
Y431565D01*
G01X1496895Y426372D02*
X1495705Y427562D01*
G01X1496895Y424183D02*
Y426372D01*
G01X1495630Y422918D02*
X1496895Y424183D01*
G01X1495630Y420549D02*
Y422918D01*
G01X1498845Y417334D02*
X1495630Y420549D01*
G01X1498845Y414043D02*
Y417334D01*
G01X1497655Y412853D02*
X1498845Y414043D01*
G01X1497655Y409460D02*
Y412853D01*
G01X1498853Y408262D02*
X1497655Y409460D01*
G01X1498853Y406958D02*
Y408262D01*
G01X1497074Y405179D02*
X1498853Y406958D01*
G01X1497074Y403125D02*
Y405179D01*
G01X1483225Y458375D02*
X1483375D01*
G01X1479650Y461950D02*
X1483225Y458375D01*
G01X1479650Y470250D02*
Y461950D01*
G01X1509355Y405875D02*
Y403903D01*
G01X1505726Y409504D02*
X1509355Y405875D01*
G01X1503666Y409504D02*
X1505726D01*
G01X1503168Y409006D02*
X1503666Y409504D01*
G01X1503168Y406818D02*
Y409006D01*
G01X1501555Y405205D02*
X1503168Y406818D01*
G01X1501555Y403015D02*
Y405205D01*
G01X1484000Y471000D02*
X1485100Y469900D01*
G01X1484000Y478221D02*
Y471000D01*
G01X1482851Y479370D02*
X1484000Y478221D01*
G01X1474248Y479370D02*
X1482851D01*
G01X1466851Y486767D02*
X1474248Y479370D01*
G01X1466851Y493104D02*
Y486767D01*
G01X1467808Y487321D02*
Y493211D01*
G01X1475007Y480122D02*
X1467808Y487321D01*
G01X1483163Y480122D02*
X1475007D01*
G01X1484752Y478533D02*
X1483163Y480122D01*
G01X1484752Y478532D02*
Y478533D01*
G01X1485004Y478280D02*
X1484752Y478532D01*
G01X1485004Y472438D02*
Y478280D01*
G01X1486669Y470773D02*
X1485004Y472438D01*
G01X1486669Y470552D02*
Y470773D01*
G01X1486670Y470551D02*
X1486669Y470552D01*
G01X1486670Y469249D02*
Y470551D01*
G01X1486669Y469248D02*
X1486670Y469249D01*
G01X1483721Y484530D02*
X1487525Y480726D01*
G01X1476170Y484530D02*
X1483721D01*
G01X1471938Y488762D02*
X1476170Y484530D01*
G01X1471849Y488762D02*
X1471938D01*
G01X1470807Y489804D02*
X1471849Y488762D01*
G01X1470807Y489805D02*
Y489804D01*
G01X1469438Y491174D02*
X1470807Y489805D01*
G01X1469438Y494054D02*
Y491174D01*
G01X1467190Y496302D02*
X1469438Y494054D01*
G01X1467190Y513610D02*
Y496302D01*
G01X1466430Y495998D02*
Y512708D01*
G01X1468686Y493742D02*
X1466430Y495998D01*
G01X1468686Y490862D02*
Y493742D01*
G01X1470055Y489493D02*
X1468686Y490862D01*
G01X1470055Y489492D02*
Y489493D01*
G01X1471537Y488010D02*
X1470055Y489492D01*
G01X1471561Y488010D02*
X1471537D01*
G01X1476193Y483378D02*
X1471561Y488010D01*
G01X1482556Y483378D02*
X1476193D01*
G01X1485955Y479979D02*
X1482556Y483378D01*
G01X1485955Y473315D02*
Y479979D01*
G01X1487606Y471664D02*
X1485955Y473315D01*
G01X1474200Y477800D02*
X1482200D01*
G01X1466099Y485901D02*
X1474200Y477800D01*
G01X1466099Y492792D02*
Y485901D01*
G01X1465346Y492481D02*
Y484554D01*
G01X1499064Y581435D02*
X1506100Y588471D01*
G01X1466864Y581435D02*
X1499064D01*
G01X1506212Y587519D02*
X1539616D01*
G01X1499376Y580683D02*
X1506212Y587519D01*
G01X1467459Y580683D02*
X1499376D01*
G01X1500470Y578573D02*
X1468370D01*
G01X1507295Y585398D02*
X1500470Y578573D01*
G01X1542274Y585398D02*
X1507295D01*
G01X1465840Y570360D02*
Y559240D01*
G01X1465700Y570500D02*
X1465840Y570360D01*
G01X1506900Y586350D02*
X1539850D01*
G01X1500075Y579525D02*
X1506900Y586350D01*
G01X1467975Y579525D02*
X1500075D01*
G01X1466431Y572230D02*
X1468649Y570012D01*
G01X1506100Y588471D02*
X1539221D01*
G01X1466598Y622898D02*
X1544932D01*
G01X1465650Y623650D02*
X1545244D01*
G01X1548410Y-9152D02*
X1546758Y-10804D01*
G01X1574558Y-9152D02*
X1548410D01*
G01X1579930Y-14524D02*
X1574558Y-9152D01*
G01X1587600Y-14524D02*
X1579930D01*
G01X1588776Y-15700D02*
X1587600Y-14524D01*
G01X1546400Y-8400D02*
X1545900Y-8900D01*
G01X1546400Y-8300D02*
Y-8400D01*
G01X1547500Y-7200D02*
X1546400Y-8300D01*
G01X1575400Y-7200D02*
X1547500D01*
G01X1580600Y-12400D02*
X1575400Y-7200D01*
G01X1588300Y-12400D02*
X1580600D01*
G01X1589600Y-13700D02*
X1588300Y-12400D01*
G01X1547600Y-8898D02*
X1546446Y-10052D01*
G01X1547600Y-8800D02*
Y-8898D01*
G01X1548000Y-8400D02*
X1547600Y-8800D01*
G01X1574900Y-8400D02*
X1548000D01*
G01X1580100Y-13600D02*
X1574900Y-8400D01*
G01X1587800Y-13600D02*
X1580100D01*
G01X1589100Y-14900D02*
X1587800Y-13600D01*
G01X1562613Y90316D02*
Y123100D01*
G01X1566697Y86232D02*
X1562613Y90316D01*
G01X1566751Y86232D02*
X1566697D01*
G01X1567208Y85775D02*
X1566751Y86232D01*
G01X1578468Y85775D02*
X1567208D01*
G01X1582280Y89587D02*
X1578468Y85775D01*
G01X1584926Y89587D02*
X1582280D01*
G01X1585459Y89054D02*
X1584926Y89587D01*
G01X1608117Y89054D02*
X1585459D01*
G01X1546386Y84164D02*
X1546370Y84180D01*
G01X1557226Y84164D02*
X1546386D01*
G01X1568390Y73000D02*
X1557226Y84164D01*
G01X1583049Y73000D02*
X1568390D01*
G01X1584249Y74200D02*
X1583049Y73000D01*
G01X1590100Y74200D02*
X1584249D01*
G01X1567176Y78901D02*
X1550947Y95130D01*
G01X1585462Y78901D02*
X1567176D01*
G01X1589098Y82537D02*
X1585462Y78901D01*
G01X1583080Y94365D02*
X1585673Y96958D01*
G01X1582830Y94365D02*
X1583080D01*
G01X1582828Y94367D02*
X1582830Y94365D01*
G01X1580958Y94367D02*
X1582828D01*
G01X1580957Y94366D02*
X1580958Y94367D01*
G01X1580335Y94366D02*
X1580957D01*
G01X1578985Y93016D02*
X1580335Y94366D01*
G01X1576304Y93016D02*
X1578985D01*
G01X1576000Y93320D02*
X1576304Y93016D01*
G01X1569644Y93320D02*
X1576000D01*
G01X1567337Y95627D02*
X1569644Y93320D01*
G01X1578673Y93768D02*
X1580023Y95118D01*
G01X1576616Y93768D02*
X1578673D01*
G01X1575693Y94691D02*
X1576616Y93768D01*
G01X1533797Y89614D02*
Y112701D01*
G01X1532147Y87964D02*
X1533797Y89614D01*
G01X1586243Y90731D02*
X1616192D01*
G01X1585769Y91205D02*
X1586243Y90731D01*
G01X1581580Y91205D02*
X1585769D01*
G01X1577834Y87459D02*
X1581580Y91205D01*
G01X1569260Y87459D02*
X1577834D01*
G01X1564119Y92600D02*
X1569260Y87459D01*
G01X1564119Y95835D02*
Y92600D01*
G01X1587148Y91483D02*
X1620484D01*
G01X1586522Y92109D02*
X1587148Y91483D01*
G01X1581270Y92109D02*
X1586522D01*
G01X1577825Y88664D02*
X1581270Y92109D01*
G01X1571108Y88664D02*
X1577825D01*
G01X1564871Y94901D02*
X1571108Y88664D01*
G01X1587460Y92235D02*
X1620796D01*
G01X1586834Y92861D02*
X1587460Y92235D01*
G01X1582206Y92861D02*
X1586834D01*
G01X1582204Y92863D02*
X1582206Y92861D01*
G01X1581582Y92863D02*
X1582204D01*
G01X1581581Y92862D02*
X1581582Y92863D01*
G01X1580959Y92862D02*
X1581581D01*
G01X1577513Y89416D02*
X1580959Y92862D01*
G01X1571420Y89416D02*
X1577513D01*
G01X1565624Y95212D02*
X1571420Y89416D01*
G01X1546674Y93910D02*
X1544323Y96261D01*
G01X1546674Y89166D02*
Y93910D01*
G01X1546830Y89010D02*
X1546674Y89166D01*
G01X1546830Y87710D02*
Y89010D01*
G01X1545900Y86780D02*
X1546830Y87710D01*
G01X1545668Y86780D02*
X1545900D01*
G01X1543985Y85097D02*
X1545668Y86780D01*
G01X1543985Y82200D02*
Y85097D01*
G01X1546350Y79835D02*
X1543985Y82200D01*
G01X1555693Y79835D02*
X1546350D01*
G01X1561886Y73642D02*
X1555693Y79835D01*
G01X1562850Y73642D02*
X1561886D01*
G01X1560563Y76231D02*
X1562575D01*
G01X1556073Y80721D02*
X1560563Y76231D01*
G01X1546528Y80721D02*
X1556073D01*
G01X1544737Y82512D02*
X1546528Y80721D01*
G01X1544737Y84777D02*
Y82512D01*
G01X1545980Y86020D02*
X1544737Y84777D01*
G01X1546210Y86020D02*
X1545980D01*
G01X1547590Y87400D02*
X1546210Y86020D01*
G01X1547590Y89320D02*
Y87400D01*
G01X1547430Y89480D02*
X1547590Y89320D01*
G01X1547430Y94230D02*
Y89480D01*
G01X1546990Y94670D02*
X1547430Y94230D01*
G01X1569526Y73752D02*
X1546226Y97052D01*
G01X1582704Y73752D02*
X1569526D01*
G01X1583935Y74983D02*
X1582704Y73752D01*
G01X1584238Y74983D02*
X1583935D01*
G01X1588971Y79716D02*
X1584238Y74983D01*
G01X1567731Y81040D02*
X1552851Y95920D01*
G01X1579885Y81040D02*
X1567731D01*
G01X1582504Y83659D02*
X1579885Y81040D01*
G01X1584354Y83659D02*
X1582504D01*
G01X1586771Y86076D02*
X1584354Y83659D01*
G01X1602653Y86076D02*
X1586771D01*
G01X1585049Y88302D02*
X1607232D01*
G01X1584562Y88789D02*
X1585049Y88302D01*
G01X1582842Y88789D02*
X1584562D01*
G01X1576597Y82544D02*
X1582842Y88789D01*
G01X1569321Y82544D02*
X1576597D01*
G01X1561581Y90284D02*
X1569321Y82544D01*
G01X1561581Y122776D02*
Y90284D01*
G01X1538260Y88792D02*
Y99185D01*
G01X1535496Y86028D02*
X1538260Y88792D01*
G01X1545887Y93621D02*
X1543541Y95967D01*
G01X1545887Y89332D02*
Y93621D01*
G01X1545250Y88695D02*
X1545887Y89332D01*
G01X1545250Y88360D02*
Y88695D01*
G01X1585771Y89806D02*
X1612057D01*
G01X1585238Y90339D02*
X1585771Y89806D01*
G01X1582592Y90339D02*
X1585238D01*
G01X1582591Y90340D02*
X1582592Y90339D01*
G01X1581969Y90340D02*
X1582591D01*
G01X1578156Y86527D02*
X1581969Y90340D01*
G01X1567520Y86527D02*
X1578156D01*
G01X1567063Y86984D02*
X1567520Y86527D01*
G01X1567009Y86984D02*
X1567063D01*
G01X1563365Y90628D02*
X1567009Y86984D01*
G01X1563365Y123000D02*
Y90628D01*
G01X1560828Y89973D02*
Y122465D01*
G01X1569009Y81792D02*
X1560828Y89973D01*
G01X1578908Y81792D02*
X1569009D01*
G01X1582107Y84991D02*
X1578908Y81792D01*
G01X1583883Y84991D02*
X1582107D01*
G01X1585880Y86988D02*
X1583883Y84991D01*
G01X1602959Y86988D02*
X1585880D01*
G01X1587359Y81862D02*
Y84348D01*
G01X1585150Y79653D02*
X1587359Y81862D01*
G01X1567488Y79653D02*
X1585150D01*
G01X1551699Y95442D02*
X1567488Y79653D01*
G01X1566942Y77966D02*
X1547379Y97529D01*
G01X1585591Y77966D02*
X1566942D01*
G01X1589367Y81742D02*
X1585591Y77966D01*
G01X1584748Y68948D02*
Y70840D01*
G01X1582100Y66300D02*
X1584748Y68948D01*
G01X1580427Y66300D02*
X1582100D01*
G01X1576456Y67144D02*
X1580427Y66300D01*
G01X1574864Y68736D02*
X1576456Y67144D01*
G01X1569960Y68736D02*
X1574864D01*
G01X1568029Y70667D02*
X1569960Y68736D01*
G01X1561382Y70667D02*
X1568029D01*
G01X1559270Y72779D02*
X1561382Y70667D01*
G01X1559270Y72780D02*
Y72779D01*
G01X1554280Y77770D02*
X1559270Y72780D01*
G01X1545721Y77770D02*
X1554280D01*
G01X1538967Y84524D02*
X1545721Y77770D01*
G01X1583392Y93613D02*
X1585985Y96206D01*
G01X1582518Y93613D02*
X1583392D01*
G01X1582516Y93615D02*
X1582518Y93613D01*
G01X1581270Y93615D02*
X1582516D01*
G01X1581269Y93614D02*
X1581270Y93615D01*
G01X1580647Y93614D02*
X1581269D01*
G01X1579297Y92264D02*
X1580647Y93614D01*
G01X1575992Y92264D02*
X1579297D01*
G01X1575688Y92568D02*
X1575992Y92264D01*
G01X1573872Y92568D02*
X1575688D01*
G01X1573863Y92559D02*
X1573872Y92568D01*
G01X1571309Y92559D02*
X1573863D01*
G01X1571300Y92568D02*
X1571309Y92559D01*
G01X1569332Y92568D02*
X1571300D01*
G01X1566376Y95524D02*
X1569332Y92568D01*
G01X1584554Y72875D02*
X1590657D01*
G01X1583172Y71493D02*
X1584554Y72875D01*
G01X1583172Y68473D02*
Y71493D01*
G01X1581751Y67052D02*
X1583172Y68473D01*
G01X1580507Y67052D02*
X1581751D01*
G01X1576830Y67834D02*
X1580507Y67052D01*
G01X1575176Y69488D02*
X1576830Y67834D01*
G01X1570272Y69488D02*
X1575176D01*
G01X1568281Y71479D02*
X1570272Y69488D01*
G01X1561780Y71479D02*
X1568281D01*
G01X1554661Y78598D02*
X1561780Y71479D01*
G01X1545957Y78598D02*
X1554661D01*
G01X1539279Y85276D02*
X1545957Y78598D01*
G01X1529752Y118411D02*
X1541421Y106742D01*
G01X1529752Y121878D02*
Y118411D01*
G01X1529061Y122569D02*
X1529752Y121878D01*
G01X1529061Y125193D02*
Y122569D01*
G01X1535037Y131169D02*
X1529061Y125193D01*
G01X1535037Y148743D02*
Y131169D01*
G01X1537562Y151268D02*
X1535037Y148743D01*
G01X1537562Y160083D02*
Y151268D01*
G01X1559482Y152539D02*
Y161577D01*
G01X1555433Y148490D02*
X1559482Y152539D01*
G01X1555433Y141170D02*
Y148490D01*
G01X1556709Y139894D02*
X1555433Y141170D01*
G01X1558839Y139894D02*
X1556709D01*
G01X1561380Y137353D02*
X1558839Y139894D01*
G01X1561380Y132166D02*
Y137353D01*
G01X1561370Y132156D02*
X1561380Y132166D01*
G01X1561370Y130296D02*
Y132156D01*
G01X1561380Y130286D02*
X1561370Y130296D01*
G01X1561380Y124333D02*
Y130286D01*
G01X1562613Y123100D02*
X1561380Y124333D01*
G01X1572424Y146772D02*
Y160603D01*
G01X1573098Y146098D02*
X1572424Y146772D01*
G01X1573098Y128342D02*
Y146098D01*
G01X1573525Y127915D02*
X1573098Y128342D01*
G01X1574197Y127915D02*
X1573525D01*
G01X1580241Y133312D02*
X1590109Y123444D01*
G01X1576512Y133312D02*
X1580241D01*
G01X1575540Y132340D02*
X1576512Y133312D01*
G01X1575540Y128636D02*
Y132340D01*
G01X1574819Y127915D02*
X1575540Y128636D01*
G01X1574197Y127915D02*
X1574819D01*
G01X1539400Y138488D02*
X1541390Y136498D01*
G01X1539400Y140612D02*
Y138488D01*
G01X1546226Y147438D02*
X1539400Y140612D01*
G01X1546226Y158833D02*
Y147438D01*
G01X1579213Y156537D02*
X1602916Y132834D01*
G01X1574384Y97437D02*
X1572586Y95639D01*
G01X1574384Y99038D02*
Y97437D01*
G01X1569599Y103823D02*
X1574384Y99038D01*
G01X1569599Y103880D02*
Y103823D01*
G01X1569115Y104364D02*
X1569599Y103880D01*
G01X1569115Y112114D02*
Y104364D01*
G01X1569428Y112427D02*
X1569115Y112114D01*
G01X1569428Y120532D02*
Y112427D01*
G01X1571594Y122698D02*
X1569428Y120532D01*
G01X1571594Y145474D02*
Y122698D01*
G01X1570920Y146148D02*
X1571594Y145474D01*
G01X1570920Y163197D02*
Y146148D01*
G01X1536410Y151425D02*
Y159605D01*
G01X1531985Y147000D02*
X1536410Y151425D01*
G01X1555322Y156071D02*
Y163303D01*
G01X1551421Y152170D02*
X1555322Y156071D01*
G01X1551421Y150364D02*
Y152170D01*
G01X1551273Y150216D02*
X1551421Y150364D01*
G01X1551273Y142896D02*
Y150216D01*
G01X1550438Y142061D02*
X1551273Y142896D01*
G01X1550438Y141970D02*
Y142061D01*
G01X1547521Y139053D02*
X1550438Y141970D01*
G01X1547521Y135401D02*
Y139053D01*
G01X1547187Y135067D02*
X1547521Y135401D01*
G01X1547187Y130537D02*
Y135067D01*
G01X1547521Y130203D02*
X1547187Y130537D01*
G01X1547521Y120270D02*
Y130203D01*
G01X1550947Y116844D02*
X1547521Y120270D01*
G01X1550947Y95130D02*
Y116844D01*
G01X1585673Y96958D02*
X1589612D01*
G01X1567337Y120760D02*
Y95627D01*
G01X1569527Y122950D02*
X1567337Y120760D01*
G01X1569527Y129118D02*
Y122950D01*
G01X1565944Y132701D02*
X1569527Y129118D01*
G01X1565944Y137330D02*
Y132701D01*
G01X1566383Y137769D02*
X1565944Y137330D01*
G01X1566881Y137769D02*
X1566383D01*
G01X1567968Y136682D02*
X1566881Y137769D01*
G01X1538072Y130146D02*
X1531726Y123800D01*
G01X1538072Y141154D02*
Y130146D01*
G01X1545074Y148156D02*
X1538072Y141154D01*
G01X1545074Y159311D02*
Y148156D01*
G01X1587516Y97710D02*
X1590268Y100462D01*
G01X1585361Y97710D02*
X1587516D01*
G01X1582770Y95119D02*
X1585361Y97710D01*
G01X1580646Y95119D02*
X1582770D01*
G01X1580645Y95118D02*
X1580646Y95119D01*
G01X1580023Y95118D02*
X1580645D01*
G01X1575693Y95997D02*
Y94691D01*
G01X1575696Y96000D02*
X1575693Y95997D01*
G01X1575696Y98790D02*
Y96000D01*
G01X1570351Y104135D02*
X1575696Y98790D01*
G01X1570351Y109222D02*
Y104135D01*
G01X1569867Y109706D02*
X1570351Y109222D01*
G01X1569867Y111802D02*
Y109706D01*
G01X1570351Y112286D02*
X1569867Y111802D01*
G01X1570351Y120391D02*
Y112286D01*
G01X1572346Y122386D02*
X1570351Y120391D01*
G01X1572346Y145786D02*
Y122386D01*
G01X1571672Y146460D02*
X1572346Y145786D01*
G01X1571672Y162172D02*
Y146460D01*
G01X1531182Y144518D02*
X1532923D01*
G01X1530409Y145291D02*
X1531182Y144518D01*
G01X1530409Y148221D02*
Y145291D01*
G01X1534708Y152520D02*
X1530409Y148221D01*
G01X1534708Y158900D02*
Y152520D01*
G01X1528340Y118158D02*
Y121660D01*
G01X1533797Y112701D02*
X1528340Y118158D01*
G01X1581905Y133344D02*
X1590310Y124939D01*
G01X1581905Y142614D02*
Y133344D01*
G01X1575897Y148622D02*
X1581905Y142614D01*
G01X1575897Y171187D02*
Y148622D01*
G01X1587553Y155071D02*
X1585470Y157154D01*
G01X1592436Y155071D02*
X1587553D01*
G01X1564120Y95836D02*
X1564119Y95835D01*
G01X1564120Y122512D02*
Y95836D01*
G01X1565943Y124335D02*
X1564120Y122512D01*
G01X1565943Y128123D02*
Y124335D01*
G01X1562936Y131130D02*
X1565943Y128123D01*
G01X1562936Y138032D02*
Y131130D01*
G01X1562184Y138784D02*
X1562936Y138032D01*
G01X1562184Y158505D02*
Y138784D01*
G01X1564871Y95523D02*
Y94901D01*
G01X1564872Y95524D02*
X1564871Y95523D01*
G01X1564872Y121487D02*
Y95524D01*
G01X1567271Y123886D02*
X1564872Y121487D01*
G01X1567271Y128182D02*
Y123886D01*
G01X1563688Y131765D02*
X1567271Y128182D01*
G01X1563688Y138266D02*
Y131765D01*
G01X1564519Y139097D02*
X1563688Y138266D01*
G01X1564519Y156980D02*
Y139097D01*
G01X1565624Y121175D02*
Y95212D01*
G01X1568023Y123574D02*
X1565624Y121175D01*
G01X1568023Y128494D02*
Y123574D01*
G01X1564440Y132077D02*
X1568023Y128494D01*
G01X1564440Y137954D02*
Y132077D01*
G01X1565271Y138785D02*
X1564440Y137954D01*
G01X1565271Y156668D02*
Y138785D01*
G01X1539513Y153738D02*
X1541351Y151900D01*
G01X1539513Y163137D02*
Y153738D01*
G01X1587865Y155823D02*
X1586222Y157466D01*
G01X1592436Y155823D02*
X1587865D01*
G01X1532912Y139998D02*
X1528727D01*
G01X1534285Y138625D02*
X1532912Y139998D01*
G01X1534285Y131743D02*
Y138625D01*
G01X1528981Y126439D02*
X1534285Y131743D01*
G01X1543386Y117914D02*
X1542100Y119200D01*
G01X1543386Y109495D02*
Y117914D01*
G01X1544501Y108380D02*
X1543386Y109495D01*
G01X1544501Y105465D02*
Y108380D01*
G01X1544323Y105287D02*
X1544501Y105465D01*
G01X1544323Y96261D02*
Y105287D01*
G01X1578441Y128604D02*
X1579310D01*
G01X1577898Y128061D02*
X1578441Y128604D01*
G01X1577898Y115256D02*
Y128061D01*
G01X1575642Y113000D02*
X1577898Y115256D01*
G01X1575642Y105356D02*
Y113000D01*
G01X1576606Y104392D02*
X1575642Y105356D01*
G01X1546978Y94670D02*
X1546990D01*
G01X1545075Y96573D02*
X1546978Y94670D01*
G01X1545075Y104975D02*
Y96573D01*
G01X1545253Y105153D02*
X1545075Y104975D01*
G01X1545253Y109078D02*
Y105153D01*
G01X1544360Y109971D02*
X1545253Y109078D01*
G01X1544360Y119516D02*
Y109971D01*
G01X1542900Y120976D02*
X1544360Y119516D01*
G01X1542900Y121700D02*
Y120976D01*
G01X1548482Y145794D02*
Y157719D01*
G01X1544531Y141843D02*
X1548482Y145794D01*
G01X1544531Y132138D02*
Y141843D01*
G01X1540235Y127842D02*
X1544531Y132138D01*
G01X1540235Y115530D02*
Y127842D01*
G01X1541765Y114000D02*
X1540235Y115530D01*
G01X1549462Y151099D02*
Y157507D01*
G01X1549369Y151006D02*
X1549462Y151099D01*
G01X1549369Y145107D02*
Y151006D01*
G01X1545283Y141021D02*
X1549369Y145107D01*
G01X1545283Y129747D02*
Y141021D01*
G01X1545603Y129427D02*
X1545283Y129747D01*
G01X1545603Y110358D02*
Y129427D01*
G01X1546405Y109556D02*
X1545603Y110358D01*
G01X1546405Y104675D02*
Y109556D01*
G01X1546227Y104497D02*
X1546405Y104675D01*
G01X1546227Y98007D02*
Y104497D01*
G01X1546226Y98006D02*
X1546227Y98007D01*
G01X1546226Y97052D02*
Y98006D01*
G01X1583593Y156903D02*
X1590193Y150303D01*
G01X1557226Y153475D02*
Y162513D01*
G01X1553177Y149426D02*
X1557226Y153475D01*
G01X1553177Y142015D02*
Y149426D01*
G01X1549508Y138346D02*
X1553177Y142015D01*
G01X1549508Y134694D02*
Y138346D01*
G01X1549091Y134277D02*
X1549508Y134694D01*
G01X1549091Y131327D02*
Y134277D01*
G01X1549508Y130910D02*
X1549091Y131327D01*
G01X1549508Y120977D02*
Y130910D01*
G01X1552851Y117634D02*
X1549508Y120977D01*
G01X1552851Y95920D02*
Y117634D01*
G01X1556929Y94800D02*
X1556200D01*
G01X1559912Y97783D02*
X1556929Y94800D01*
G01X1559912Y101613D02*
Y97783D01*
G01X1555676Y105849D02*
X1559912Y101613D01*
G01X1555676Y123283D02*
Y105849D01*
G01X1560628Y123729D02*
X1561581Y122776D01*
G01X1560628Y129974D02*
Y123729D01*
G01X1559148Y131454D02*
X1560628Y129974D01*
G01X1552854Y131454D02*
X1559148D01*
G01X1552824Y131424D02*
X1552854Y131454D01*
G01X1551518Y131424D02*
X1552824D01*
G01X1550595Y132347D02*
X1551518Y131424D01*
G01X1550595Y133653D02*
Y132347D01*
G01X1553424Y136482D02*
X1550595Y133653D01*
G01X1553424Y139653D02*
Y136482D01*
G01X1554681Y140910D02*
X1553424Y139653D01*
G01X1554681Y148802D02*
Y140910D01*
G01X1558730Y152851D02*
X1554681Y148802D01*
G01X1558730Y161889D02*
Y152851D01*
G01X1573320Y103721D02*
X1573153D01*
G01X1574690Y105091D02*
X1573320Y103721D01*
G01X1574690Y113395D02*
Y105091D01*
G01X1576946Y115651D02*
X1574690Y113395D01*
G01X1576946Y128760D02*
Y115651D01*
G01X1579290Y131104D02*
X1576946Y128760D01*
G01X1543071Y150270D02*
X1541831Y149030D01*
G01X1543071Y158437D02*
Y150270D01*
G01X1543856Y148679D02*
Y158716D01*
G01X1536681Y141504D02*
X1543856Y148679D01*
G01X1536681Y131437D02*
Y141504D01*
G01X1530000Y124756D02*
X1536681Y131437D01*
G01X1530000Y123100D02*
Y124756D01*
G01X1530851Y122249D02*
X1530000Y123100D01*
G01X1530851Y119541D02*
Y122249D01*
G01X1542997Y107395D02*
X1530851Y119541D01*
G01X1542997Y106089D02*
Y107395D01*
G01X1542819Y105911D02*
X1542997Y106089D01*
G01X1542819Y103744D02*
Y105911D01*
G01X1538260Y99185D02*
X1542819Y103744D01*
G01X1582669Y156763D02*
X1594033Y145399D01*
G01X1546978Y146418D02*
Y158521D01*
G01X1543027Y142467D02*
X1546978Y146418D01*
G01X1543027Y135667D02*
Y142467D01*
G01X1542400Y135040D02*
X1543027Y135667D01*
G01X1542020Y135040D02*
X1542400D01*
G01X1540615Y133635D02*
X1542020Y135040D01*
G01X1540615Y129422D02*
Y133635D01*
G01X1539483Y128290D02*
X1540615Y129422D01*
G01X1539483Y111973D02*
Y128290D01*
G01X1543749Y107707D02*
X1539483Y111973D01*
G01X1543749Y105777D02*
Y107707D01*
G01X1543571Y105599D02*
X1543749Y105777D01*
G01X1543571Y103432D02*
Y105599D01*
G01X1543541Y103402D02*
X1543571Y103432D01*
G01X1543541Y95967D02*
Y103402D01*
G01X1564684Y124319D02*
X1563365Y123000D01*
G01X1564684Y127119D02*
Y124319D01*
G01X1562184Y129619D02*
X1564684Y127119D01*
G01X1562184Y137720D02*
Y129619D01*
G01X1558434Y141470D02*
X1562184Y137720D01*
G01X1557981Y141470D02*
X1558434D01*
G01X1557978Y153163D02*
Y162201D01*
G01X1553929Y149114D02*
X1557978Y153163D01*
G01X1553929Y141222D02*
Y149114D01*
G01X1552672Y139965D02*
X1553929Y141222D01*
G01X1552672Y136794D02*
Y139965D01*
G01X1549843Y133965D02*
X1552672Y136794D01*
G01X1549843Y132035D02*
Y133965D01*
G01X1551206Y130672D02*
X1549843Y132035D01*
G01X1553136Y130672D02*
X1551206D01*
G01X1553166Y130702D02*
X1553136Y130672D01*
G01X1558836Y130702D02*
X1553166D01*
G01X1559876Y129662D02*
X1558836Y130702D01*
G01X1559876Y123417D02*
Y129662D01*
G01X1560828Y122465D02*
X1559876Y123417D01*
G01X1543779Y134415D02*
X1542685Y133321D01*
G01X1543779Y142155D02*
Y134415D01*
G01X1547730Y146106D02*
X1543779Y142155D01*
G01X1547730Y158209D02*
Y146106D01*
G01X1551699Y117156D02*
Y95442D01*
G01X1548346Y120509D02*
X1551699Y117156D01*
G01X1548346Y130442D02*
Y120509D01*
G01X1547939Y130849D02*
X1548346Y130442D01*
G01X1547939Y134755D02*
Y130849D01*
G01X1548346Y135162D02*
X1547939Y134755D01*
G01X1548346Y138814D02*
Y135162D01*
G01X1551190Y141658D02*
X1548346Y138814D01*
G01X1551190Y141749D02*
Y141658D01*
G01X1552025Y142584D02*
X1551190Y141749D01*
G01X1552025Y149904D02*
Y142584D01*
G01X1552342Y150221D02*
X1552025Y149904D01*
G01X1552342Y151961D02*
Y150221D01*
G01X1556074Y155693D02*
X1552342Y151961D01*
G01X1556074Y162991D02*
Y155693D01*
G01X1550669Y150676D02*
Y157084D01*
G01X1550521Y150528D02*
X1550669Y150676D01*
G01X1550521Y144549D02*
Y150528D01*
G01X1546761Y140789D02*
X1550521Y144549D01*
G01X1546761Y135705D02*
Y140789D01*
G01X1546435Y135379D02*
X1546761Y135705D01*
G01X1546435Y130225D02*
Y135379D01*
G01X1546761Y129899D02*
X1546435Y130225D01*
G01X1546761Y110830D02*
Y129899D01*
G01X1547557Y110034D02*
X1546761Y110830D01*
G01X1547557Y104197D02*
Y110034D01*
G01X1547379Y104019D02*
X1547557Y104197D01*
G01X1547379Y97529D02*
Y104019D01*
G01X1587453Y154107D02*
X1584346Y157214D01*
G01X1603038Y154107D02*
X1587453D01*
G01X1572497Y98546D02*
X1572634D01*
G01X1568363Y102680D02*
X1572497Y98546D01*
G01X1568363Y112426D02*
Y102680D01*
G01X1568657Y112720D02*
X1568363Y112426D01*
G01X1568657Y120825D02*
Y112720D01*
G01X1570279Y122447D02*
X1568657Y120825D01*
G01X1570279Y144285D02*
Y122447D01*
G01X1566912Y147652D02*
X1570279Y144285D01*
G01X1566912Y168438D02*
Y147652D01*
G01X1585985Y96206D02*
X1589300D01*
G01X1566376Y120863D02*
Y95524D01*
G01X1568775Y123262D02*
X1566376Y120863D01*
G01X1568775Y128806D02*
Y123262D01*
G01X1565192Y132389D02*
X1568775Y128806D01*
G01X1565192Y137642D02*
Y132389D01*
G01X1566106Y138556D02*
X1565192Y137642D01*
G01X1566930Y138556D02*
X1566106D01*
G01X1567981Y139607D02*
X1566930Y138556D01*
G01X1597006Y140647D02*
X1581450Y156203D01*
G01X1535308Y162337D02*
X1537562Y160083D01*
G01X1535308Y164057D02*
Y162337D01*
G01X1535065Y164300D02*
X1535308Y164057D01*
G01X1538067Y212496D02*
Y231612D01*
G01X1533424Y207853D02*
X1538067Y212496D01*
G01X1533424Y204093D02*
Y207853D01*
G01X1532420Y203089D02*
X1533424Y204093D01*
G01X1532420Y179650D02*
Y203089D01*
G01X1535065Y177005D02*
X1532420Y179650D01*
G01X1535065Y164300D02*
Y177005D01*
G01X1553488Y214808D02*
Y246268D01*
G01X1553489Y214807D02*
X1553488Y214808D01*
G01X1553489Y214185D02*
Y214807D01*
G01X1553490Y214184D02*
X1553489Y214185D01*
G01X1553490Y210442D02*
Y214184D01*
G01X1550487Y207439D02*
X1553490Y210442D01*
G01X1550487Y201378D02*
Y207439D01*
G01X1553917Y197948D02*
X1550487Y201378D01*
G01X1553917Y194851D02*
Y197948D01*
G01X1553203Y194137D02*
X1553917Y194851D01*
G01X1553203Y175159D02*
Y194137D01*
G01X1555011Y173351D02*
X1553203Y175159D01*
G01X1555011Y172070D02*
Y173351D01*
G01X1559483Y167598D02*
X1555011Y172070D01*
G01X1559483Y161578D02*
Y167598D01*
G01X1559482Y161577D02*
X1559483Y161578D01*
G01X1576760Y189321D02*
Y218532D01*
G01X1586487Y179594D02*
X1576760Y189321D01*
G01X1586487Y176134D02*
Y179594D01*
G01X1590024Y172597D02*
X1586487Y176134D01*
G01X1565205Y191315D02*
Y230459D01*
G01X1564158Y190268D02*
X1565205Y191315D01*
G01X1564158Y180305D02*
Y190268D01*
G01X1567304Y177159D02*
X1564158Y180305D01*
G01X1568861Y177159D02*
X1567304D01*
G01X1575145Y170875D02*
X1568861Y177159D01*
G01X1575145Y163324D02*
Y170875D01*
G01X1572424Y160603D02*
X1575145Y163324D01*
G01X1547751Y160358D02*
X1546226Y158833D01*
G01X1547751Y163212D02*
Y160358D01*
G01X1542859Y168104D02*
X1547751Y163212D01*
G01X1542859Y177144D02*
Y168104D01*
G01X1542860Y177145D02*
X1542859Y177144D01*
G01X1542860Y179055D02*
Y177145D01*
G01X1540772Y181143D02*
X1542860Y179055D01*
G01X1540772Y185093D02*
Y181143D01*
G01X1541736Y186057D02*
X1540772Y185093D01*
G01X1541736Y203757D02*
Y186057D01*
G01X1544471Y206492D02*
X1541736Y203757D01*
G01X1544471Y209935D02*
Y206492D01*
G01X1547378Y212842D02*
X1544471Y209935D01*
G01X1547378Y235841D02*
Y212842D01*
G01X1579213Y170294D02*
Y156537D01*
G01X1573479Y176028D02*
X1579213Y170294D01*
G01X1573479Y180898D02*
Y176028D01*
G01X1568213Y186164D02*
X1573479Y180898D01*
G01X1568213Y228645D02*
Y186164D01*
G01X1571870Y164147D02*
X1570920Y163197D01*
G01X1571870Y168037D02*
Y164147D01*
G01X1569775Y170132D02*
X1571870Y168037D01*
G01X1568342Y170132D02*
X1569775D01*
G01X1564136Y174338D02*
X1568342Y170132D01*
G01X1564136Y176195D02*
Y174338D01*
G01X1561316Y179015D02*
X1564136Y176195D01*
G01X1561316Y189554D02*
Y179015D01*
G01X1563501Y191739D02*
X1561316Y189554D01*
G01X1563501Y230909D02*
Y191739D01*
G01X1536915Y212974D02*
Y231700D01*
G01X1532272Y208331D02*
X1536915Y212974D01*
G01X1532272Y204571D02*
Y208331D01*
G01X1531268Y203567D02*
X1532272Y204571D01*
G01X1531268Y179171D02*
Y203567D01*
G01X1533141Y177298D02*
X1531268Y179171D01*
G01X1533141Y163775D02*
Y177298D01*
G01X1534156Y162760D02*
X1533141Y163775D01*
G01X1534156Y161859D02*
Y162760D01*
G01X1536410Y159605D02*
X1534156Y161859D01*
G01X1549043Y190015D02*
X1548178Y190880D01*
G01X1549043Y181147D02*
Y190015D01*
G01X1547819Y179923D02*
X1549043Y181147D01*
G01X1547819Y170298D02*
Y179923D01*
G01X1550296Y167821D02*
X1547819Y170298D01*
G01X1553374Y167821D02*
X1550296D01*
G01X1555323Y165872D02*
X1553374Y167821D01*
G01X1555323Y163304D02*
Y165872D01*
G01X1555322Y163303D02*
X1555323Y163304D01*
G01X1540555Y166143D02*
X1545023Y161675D01*
G01X1540555Y167148D02*
Y166143D01*
G01X1540554Y167149D02*
X1540555Y167148D01*
G01X1540554Y169059D02*
Y167149D01*
G01X1540555Y169060D02*
X1540554Y169059D01*
G01X1540555Y178100D02*
Y169060D01*
G01X1538468Y180187D02*
X1540555Y178100D01*
G01X1538468Y186049D02*
Y180187D01*
G01X1539432Y187013D02*
X1538468Y186049D01*
G01X1539432Y204713D02*
Y187013D01*
G01X1542167Y207448D02*
X1539432Y204713D01*
G01X1542167Y233188D02*
Y207448D01*
G01X1579768Y197040D02*
X1579921Y196887D01*
G01X1579768Y219780D02*
Y197040D01*
G01X1533511Y214384D02*
Y230289D01*
G01X1528868Y209741D02*
X1533511Y214384D01*
G01X1528868Y206076D02*
Y209741D01*
G01X1527844Y205052D02*
X1528868Y206076D01*
G01X1527844Y180300D02*
Y205052D01*
G01X1546599Y160836D02*
X1545074Y159311D01*
G01X1546599Y162496D02*
Y160836D01*
G01X1541707Y167388D02*
X1546599Y162496D01*
G01X1541707Y167626D02*
Y167388D01*
G01X1541706Y167627D02*
X1541707Y167626D01*
G01X1541706Y168581D02*
Y167627D01*
G01X1541707Y168582D02*
X1541706Y168581D01*
G01X1541707Y177622D02*
Y168582D01*
G01X1541708Y177623D02*
X1541707Y177622D01*
G01X1541708Y178577D02*
Y177623D01*
G01X1539620Y180665D02*
X1541708Y178577D01*
G01X1539620Y185571D02*
Y180665D01*
G01X1540584Y186535D02*
X1539620Y185571D01*
G01X1540584Y204235D02*
Y186535D01*
G01X1543319Y206970D02*
X1540584Y204235D01*
G01X1543319Y231046D02*
Y206970D01*
G01X1577512Y189633D02*
Y218844D01*
G01X1587239Y179906D02*
X1577512Y189633D01*
G01X1587239Y176470D02*
Y179906D01*
G01X1590955Y172754D02*
X1587239Y176470D01*
G01X1574393Y164893D02*
X1571672Y162172D01*
G01X1574393Y170563D02*
Y164893D01*
G01X1573470Y171486D02*
X1574393Y170563D01*
G01X1568052Y171486D02*
X1573470D01*
G01X1564888Y174650D02*
X1568052Y171486D01*
G01X1564888Y176507D02*
Y174650D01*
G01X1562068Y179327D02*
X1564888Y176507D01*
G01X1562068Y189242D02*
Y179327D01*
G01X1564453Y191627D02*
X1562068Y189242D01*
G01X1564453Y230797D02*
Y191627D01*
G01X1587991Y176782D02*
X1591890Y172883D01*
G01X1587991Y180218D02*
Y176782D01*
G01X1578264Y189945D02*
X1587991Y180218D01*
G01X1578264Y219156D02*
Y189945D01*
G01X1532454Y161154D02*
X1534708Y158900D01*
G01X1532454Y162055D02*
Y161154D01*
G01X1529546Y164963D02*
X1532454Y162055D01*
G01X1529546Y204347D02*
Y164963D01*
G01X1530570Y205371D02*
X1529546Y204347D01*
G01X1530570Y209036D02*
Y205371D01*
G01X1535213Y213679D02*
X1530570Y209036D01*
G01X1535213Y230994D02*
Y213679D01*
G01X1567601Y182385D02*
X1566486Y181270D01*
G01X1567601Y184648D02*
Y182385D01*
G01X1566709Y185540D02*
X1567601Y184648D01*
G01X1566709Y229835D02*
Y185540D01*
G01X1580673Y190727D02*
X1590224Y181176D01*
G01X1580673Y197199D02*
Y190727D01*
G01X1580520Y197352D02*
X1580673Y197199D01*
G01X1580520Y220092D02*
Y197352D01*
G01X1567970Y179114D02*
X1575897Y171187D01*
G01X1566413Y179114D02*
X1567970D01*
G01X1564910Y180617D02*
X1566413Y179114D01*
G01X1564910Y183824D02*
Y180617D01*
G01X1565957Y184871D02*
X1564910Y183824D01*
G01X1565957Y230147D02*
Y184871D01*
G01X1560448Y194816D02*
Y229984D01*
G01X1559597Y193965D02*
X1560448Y194816D01*
G01X1559597Y178606D02*
Y193965D01*
G01X1561538Y176665D02*
X1559597Y178606D01*
G01X1561538Y174649D02*
Y176665D01*
G01X1572247Y216661D02*
Y224147D01*
G01X1572248Y216660D02*
X1572247Y216661D01*
G01X1572248Y187449D02*
Y216660D01*
G01X1581975Y177722D02*
X1572248Y187449D01*
G01X1581975Y173724D02*
Y177722D01*
G01X1585470Y170229D02*
X1581975Y173724D01*
G01X1585470Y157154D02*
Y170229D01*
G01X1563767Y160088D02*
X1562184Y158505D01*
G01X1563767Y165734D02*
Y160088D01*
G01X1559355Y170146D02*
X1563767Y165734D01*
G01X1557999Y170146D02*
X1559355D01*
G01X1555763Y172382D02*
X1557999Y170146D01*
G01X1555763Y173663D02*
Y172382D01*
G01X1553955Y175471D02*
X1555763Y173663D01*
G01X1553955Y193825D02*
Y175471D01*
G01X1554669Y194539D02*
X1553955Y193825D01*
G01X1554669Y195017D02*
Y194539D01*
G01X1554672Y195020D02*
X1554669Y195017D01*
G01X1554672Y196266D02*
Y195020D01*
G01X1554671Y196267D02*
X1554672Y196266D01*
G01X1554671Y196703D02*
Y196267D01*
G01X1554672Y196704D02*
X1554671Y196703D01*
G01X1554672Y202990D02*
Y196704D01*
G01X1554168Y203494D02*
X1554672Y202990D01*
G01X1554168Y207120D02*
Y203494D01*
G01X1554167Y207121D02*
X1554168Y207120D01*
G01X1554167Y208991D02*
Y207121D01*
G01X1554994Y209818D02*
X1554167Y208991D01*
G01X1554994Y214808D02*
Y209818D01*
G01X1554993Y214809D02*
X1554994Y214808D01*
G01X1554993Y246891D02*
Y214809D01*
G01X1587726Y162474D02*
X1591950Y158250D01*
G01X1587726Y171333D02*
Y162474D01*
G01X1584231Y174828D02*
X1587726Y171333D01*
G01X1584231Y178658D02*
Y174828D01*
G01X1574504Y188385D02*
X1584231Y178658D01*
G01X1574504Y217596D02*
Y188385D01*
G01X1574503Y217597D02*
X1574504Y217596D01*
G01X1574503Y223211D02*
Y217597D01*
G01X1565230Y157691D02*
X1564519Y156980D01*
G01X1565230Y167577D02*
Y157691D01*
G01X1559210Y173597D02*
X1565230Y167577D01*
G01X1559210Y176865D02*
Y173597D01*
G01X1556657Y179418D02*
X1559210Y176865D01*
G01X1556657Y186873D02*
Y179418D01*
G01X1555459Y188071D02*
X1556657Y186873D01*
G01X1555459Y193201D02*
Y188071D01*
G01X1556176Y193918D02*
X1555459Y193201D01*
G01X1556176Y202366D02*
Y193918D01*
G01X1556177Y202367D02*
X1556176Y202366D01*
G01X1556177Y203613D02*
Y202367D01*
G01X1556176Y203614D02*
X1556177Y203613D01*
G01X1556176Y203631D02*
Y203614D01*
G01X1555672Y204135D02*
X1556176Y203631D01*
G01X1555672Y207744D02*
Y204135D01*
G01X1555671Y207745D02*
X1555672Y207744D01*
G01X1555671Y208367D02*
Y207745D01*
G01X1556498Y209194D02*
X1555671Y208367D01*
G01X1556498Y215432D02*
Y209194D01*
G01X1556497Y215433D02*
X1556498Y215432D01*
G01X1556497Y247515D02*
Y215433D01*
G01X1585735Y175760D02*
X1589272Y172223D01*
G01X1585735Y179282D02*
Y175760D01*
G01X1576008Y189009D02*
X1585735Y179282D01*
G01X1576008Y218220D02*
Y189009D01*
G01X1565983Y157380D02*
X1565271Y156668D01*
G01X1565983Y158002D02*
Y157380D01*
G01X1565982Y158003D02*
X1565983Y158002D01*
G01X1565982Y167889D02*
Y158003D01*
G01X1559962Y173909D02*
X1565982Y167889D01*
G01X1559962Y177177D02*
Y173909D01*
G01X1557409Y179730D02*
X1559962Y177177D01*
G01X1557409Y187185D02*
Y179730D01*
G01X1556211Y188383D02*
X1557409Y187185D01*
G01X1556211Y192889D02*
Y188383D01*
G01X1556928Y193606D02*
X1556211Y192889D01*
G01X1556928Y202054D02*
Y193606D01*
G01X1556929Y202055D02*
X1556928Y202054D01*
G01X1556929Y203925D02*
Y202055D01*
G01X1556928Y203926D02*
X1556929Y203925D01*
G01X1556928Y203943D02*
Y203926D01*
G01X1556424Y204447D02*
X1556928Y203943D01*
G01X1556424Y208056D02*
Y204447D01*
G01X1557250Y208882D02*
X1556424Y208056D01*
G01X1557250Y215744D02*
Y208882D01*
G01X1557249Y215745D02*
X1557250Y215744D01*
G01X1557249Y247827D02*
Y215745D01*
G01X1537258Y165392D02*
X1539513Y163137D01*
G01X1537258Y177242D02*
Y165392D01*
G01X1533572Y180928D02*
X1537258Y177242D01*
G01X1533572Y202611D02*
Y180928D01*
G01X1539511Y208550D02*
X1533572Y202611D01*
G01X1539511Y231798D02*
Y208550D01*
G01X1567461Y185852D02*
Y229388D01*
G01X1568601Y184712D02*
X1567461Y185852D01*
G01X1568601Y182931D02*
Y184712D01*
G01X1571501Y180031D02*
X1568601Y182931D01*
G01X1585973Y189016D02*
X1592629Y182360D01*
G01X1585973Y194027D02*
Y189016D01*
G01X1582024Y197976D02*
X1585973Y194027D01*
G01X1582024Y208148D02*
Y197976D01*
G01X1582298Y208422D02*
X1582024Y208148D01*
G01X1582298Y220366D02*
Y208422D01*
G01X1572999Y216973D02*
Y223835D01*
G01X1573000Y216972D02*
X1572999Y216973D01*
G01X1573000Y187761D02*
Y216972D01*
G01X1582727Y178034D02*
X1573000Y187761D01*
G01X1582727Y174108D02*
Y178034D01*
G01X1586222Y170613D02*
X1582727Y174108D01*
G01X1586222Y157466D02*
Y170613D01*
G01X1587549Y189652D02*
X1593381Y183820D01*
G01X1587549Y192000D02*
Y189652D01*
G01X1588478Y163251D02*
X1590395Y161334D01*
G01X1588478Y171889D02*
Y163251D01*
G01X1584983Y175384D02*
X1588478Y171889D01*
G01X1584983Y178970D02*
Y175384D01*
G01X1575256Y188697D02*
X1584983Y178970D01*
G01X1575256Y217908D02*
Y188697D01*
G01X1528131Y213539D02*
Y221861D01*
G01X1527146Y220169D02*
Y213618D01*
G01X1586974Y161140D02*
X1590474Y157640D01*
G01X1586974Y171021D02*
Y161140D01*
G01X1583479Y174516D02*
X1586974Y171021D01*
G01X1583479Y178346D02*
Y174516D01*
G01X1573752Y188073D02*
X1583479Y178346D01*
G01X1573752Y217284D02*
Y188073D01*
G01X1573751Y217285D02*
X1573752Y217284D01*
G01X1573751Y223523D02*
Y217285D01*
G01X1548976Y212312D02*
Y237291D01*
G01X1545975Y209311D02*
X1548976Y212312D01*
G01X1545975Y205868D02*
Y209311D01*
G01X1543446Y203339D02*
X1545975Y205868D01*
G01X1543446Y202082D02*
Y203339D01*
G01X1543447Y202081D02*
X1543446Y202082D01*
G01X1543447Y189538D02*
Y202081D01*
G01X1546387Y186598D02*
X1543447Y189538D01*
G01X1546387Y182249D02*
Y186598D01*
G01X1545163Y181025D02*
X1546387Y182249D01*
G01X1545163Y169196D02*
Y181025D01*
G01X1549177Y165180D02*
X1545163Y169196D01*
G01X1550007Y164350D02*
X1549177Y165180D01*
G01X1550007Y159244D02*
Y164350D01*
G01X1548482Y157719D02*
X1550007Y159244D01*
G01X1549728Y212000D02*
Y237603D01*
G01X1546727Y208999D02*
X1549728Y212000D01*
G01X1546727Y205556D02*
Y208999D01*
G01X1544199Y203028D02*
X1546727Y205556D01*
G01X1544199Y189850D02*
Y203028D01*
G01X1547139Y186910D02*
X1544199Y189850D01*
G01X1547139Y181937D02*
Y186910D01*
G01X1545915Y180713D02*
X1547139Y181937D01*
G01X1545915Y169508D02*
Y180713D01*
G01X1549506Y165916D02*
X1545915Y169508D01*
G01X1550772Y164650D02*
X1549506Y165916D01*
G01X1550772Y158817D02*
Y164650D01*
G01X1549462Y157507D02*
X1550772Y158817D01*
G01X1583593Y169978D02*
Y156903D01*
G01X1580471Y173100D02*
X1583593Y169978D01*
G01X1580471Y177098D02*
Y173100D01*
G01X1570744Y186825D02*
X1580471Y177098D01*
G01X1570744Y216036D02*
Y186825D01*
G01X1570743Y216037D02*
X1570744Y216036D01*
G01X1570743Y224771D02*
Y216037D01*
G01X1551232Y211376D02*
Y245332D01*
G01X1548231Y208375D02*
X1551232Y211376D01*
G01X1548231Y200442D02*
Y208375D01*
G01X1551269Y197404D02*
X1548231Y200442D01*
G01X1551269Y195395D02*
Y197404D01*
G01X1550947Y195073D02*
X1551269Y195395D01*
G01X1550947Y177102D02*
Y195073D01*
G01X1549723Y175878D02*
X1550947Y177102D01*
G01X1549723Y171088D02*
Y175878D01*
G01X1551086Y169725D02*
X1549723Y171088D01*
G01X1554164Y169725D02*
X1551086D01*
G01X1557227Y166662D02*
X1554164Y169725D01*
G01X1557227Y162514D02*
Y166662D01*
G01X1557226Y162513D02*
X1557227Y162514D01*
G01X1557787Y193219D02*
Y192236D01*
G01X1559600Y195032D02*
X1557787Y193219D01*
G01X1559600Y230200D02*
Y195032D01*
G01X1558731Y161890D02*
X1558730Y161889D01*
G01X1558731Y167286D02*
Y161890D01*
G01X1554259Y171758D02*
X1558731Y167286D01*
G01X1554259Y173039D02*
Y171758D01*
G01X1552451Y174847D02*
X1554259Y173039D01*
G01X1552451Y194449D02*
Y174847D01*
G01X1553092Y195090D02*
X1552451Y194449D01*
G01X1553092Y197709D02*
Y195090D01*
G01X1549735Y201066D02*
X1553092Y197709D01*
G01X1549735Y207751D02*
Y201066D01*
G01X1552736Y210752D02*
X1549735Y207751D01*
G01X1552736Y245956D02*
Y210752D01*
G01X1579016Y190257D02*
Y219468D01*
G01X1589125Y180148D02*
X1579016Y190257D01*
G01X1541260Y160248D02*
X1543071Y158437D01*
G01X1541260Y163020D02*
Y160248D01*
G01X1538411Y165869D02*
X1541260Y163020D01*
G01X1538411Y166493D02*
Y165869D01*
G01X1538410Y166494D02*
X1538411Y166493D01*
G01X1538410Y167740D02*
Y166494D01*
G01X1538412Y167742D02*
X1538410Y167740D01*
G01X1538412Y177718D02*
Y167742D01*
G01X1536964Y179166D02*
X1538412Y177718D01*
G01X1536964Y186673D02*
Y179166D01*
G01X1537001Y186710D02*
X1536964Y186673D01*
G01X1537001Y195599D02*
Y186710D01*
G01X1534724Y197876D02*
X1537001Y195599D01*
G01X1534724Y202133D02*
Y197876D01*
G01X1540663Y208072D02*
X1534724Y202133D01*
G01X1540663Y234784D02*
Y208072D01*
G01X1555745Y215121D02*
Y247203D01*
G01X1555746Y215120D02*
X1555745Y215121D01*
G01X1555746Y209506D02*
Y215120D01*
G01X1554919Y208679D02*
X1555746Y209506D01*
G01X1554919Y207433D02*
Y208679D01*
G01X1554920Y207432D02*
X1554919Y207433D01*
G01X1554920Y203806D02*
Y207432D01*
G01X1555425Y203301D02*
X1554920Y203806D01*
G01X1555425Y202679D02*
Y203301D01*
G01X1555424Y202678D02*
X1555425Y202679D01*
G01X1555424Y194230D02*
Y202678D01*
G01X1554707Y193513D02*
X1555424Y194230D01*
G01X1554707Y175783D02*
Y193513D01*
G01X1558042Y172448D02*
X1554707Y175783D01*
G01X1541415Y207760D02*
Y235096D01*
G01X1538680Y205025D02*
X1541415Y207760D01*
G01X1538680Y187325D02*
Y205025D01*
G01X1537716Y186361D02*
X1538680Y187325D01*
G01X1537716Y179478D02*
Y186361D01*
G01X1539164Y178030D02*
X1537716Y179478D01*
G01X1539164Y166180D02*
Y178030D01*
G01X1542012Y163332D02*
X1539164Y166180D01*
G01X1542012Y160560D02*
Y163332D01*
G01X1543856Y158716D02*
X1542012Y160560D01*
G01X1582669Y169838D02*
Y156763D01*
G01X1579719Y172788D02*
X1582669Y169838D01*
G01X1579719Y176786D02*
Y172788D01*
G01X1569992Y186513D02*
X1579719Y176786D01*
G01X1569992Y215724D02*
Y186513D01*
G01X1569991Y215725D02*
X1569992Y215724D01*
G01X1569991Y225083D02*
Y215725D01*
G01X1552063Y207951D02*
Y202031D01*
G01X1554242Y210130D02*
X1552063Y207951D01*
G01X1554242Y214496D02*
Y210130D01*
G01X1554241Y214497D02*
X1554242Y214496D01*
G01X1554241Y246579D02*
Y214497D01*
G01X1587511Y211691D02*
X1595022Y204180D01*
G01X1587511Y217045D02*
Y211691D01*
G01X1592950Y222484D02*
X1587511Y217045D01*
G01X1530285Y213565D02*
Y229701D01*
G01X1527166Y210446D02*
X1530285Y213565D01*
G01X1527166Y206781D02*
Y210446D01*
G01X1548224Y212624D02*
Y236979D01*
G01X1545223Y209623D02*
X1548224Y212624D01*
G01X1545223Y206180D02*
Y209623D01*
G01X1542488Y203445D02*
X1545223Y206180D01*
G01X1542488Y185745D02*
Y203445D01*
G01X1541524Y184781D02*
X1542488Y185745D01*
G01X1541524Y182686D02*
Y184781D01*
G01X1543659Y180551D02*
X1541524Y182686D01*
G01X1543659Y168572D02*
Y180551D01*
G01X1548503Y163725D02*
X1543659Y168572D01*
G01X1548503Y160046D02*
Y163725D01*
G01X1546978Y158521D02*
X1548503Y160046D01*
G01X1549693Y197916D02*
Y196707D01*
G01X1547479Y200130D02*
X1549693Y197916D01*
G01X1547479Y208687D02*
Y200130D01*
G01X1550480Y211688D02*
X1547479Y208687D01*
G01X1550480Y245020D02*
Y211688D01*
G01X1551984Y211064D02*
Y245644D01*
G01X1548983Y208063D02*
X1551984Y211064D01*
G01X1548983Y200754D02*
Y208063D01*
G01X1552340Y197397D02*
X1548983Y200754D01*
G01X1552340Y195402D02*
Y197397D01*
G01X1551699Y194761D02*
X1552340Y195402D01*
G01X1551699Y176790D02*
Y194761D01*
G01X1550475Y175566D02*
X1551699Y176790D01*
G01X1550475Y171400D02*
Y175566D01*
G01X1551398Y170477D02*
X1550475Y171400D01*
G01X1554476Y170477D02*
X1551398D01*
G01X1557979Y166974D02*
X1554476Y170477D01*
G01X1557979Y162202D02*
Y166974D01*
G01X1557978Y162201D02*
X1557979Y162202D01*
G01X1549255Y159734D02*
X1547730Y158209D01*
G01X1549255Y164037D02*
Y159734D01*
G01X1548848Y164444D02*
X1549255Y164037D01*
G01X1544411Y168884D02*
X1548848Y164444D01*
G01X1544411Y182817D02*
Y168884D01*
G01X1543100Y184128D02*
X1544411Y182817D01*
G01X1556075Y162992D02*
X1556074Y162991D01*
G01X1556075Y166184D02*
Y162992D01*
G01X1553686Y168573D02*
X1556075Y166184D01*
G01X1550608Y168573D02*
X1553686D01*
G01X1548571Y170610D02*
X1550608Y168573D01*
G01X1548571Y179611D02*
Y170610D01*
G01X1549795Y180835D02*
X1548571Y179611D01*
G01X1549795Y192707D02*
Y180835D01*
G01X1547576Y194926D02*
X1549795Y192707D01*
G01X1547576Y198311D02*
Y194926D01*
G01X1545910Y199977D02*
X1547576Y198311D01*
G01X1546000Y189679D02*
Y197400D01*
G01X1548291Y187388D02*
X1546000Y189679D01*
G01X1548291Y181459D02*
Y187388D01*
G01X1547067Y180235D02*
X1548291Y181459D01*
G01X1547067Y169986D02*
Y180235D01*
G01X1550669Y166384D02*
X1547067Y169986D01*
G01X1550669Y166383D02*
Y166384D01*
G01X1551924Y165128D02*
X1550669Y166383D01*
G01X1551924Y158339D02*
Y165128D01*
G01X1550669Y157084D02*
X1551924Y158339D01*
G01X1571495Y216349D02*
Y224459D01*
G01X1571496Y216348D02*
X1571495Y216349D01*
G01X1571496Y187137D02*
Y216348D01*
G01X1581223Y177410D02*
X1571496Y187137D01*
G01X1581223Y173412D02*
Y177410D01*
G01X1584346Y170289D02*
X1581223Y173412D01*
G01X1584346Y157214D02*
Y170289D01*
G01X1563384Y171966D02*
X1566912Y168438D01*
G01X1563384Y175883D02*
Y171966D01*
G01X1560349Y178918D02*
X1563384Y175883D01*
G01X1560349Y193653D02*
Y178918D01*
G01X1561200Y194504D02*
X1560349Y193653D01*
G01X1561200Y229672D02*
Y194504D01*
G01X1585020Y188112D02*
X1590224Y182908D01*
G01X1585020Y193916D02*
Y188112D01*
G01X1581272Y197664D02*
X1585020Y193916D01*
G01X1581272Y220404D02*
Y197664D01*
G01X1569239Y186202D02*
Y226411D01*
G01X1578567Y176874D02*
X1569239Y186202D01*
G01X1578567Y172622D02*
Y176874D01*
G01X1581450Y169739D02*
X1578567Y172622D01*
G01X1581450Y156203D02*
Y169739D01*
G01X1558001Y216057D02*
Y248280D01*
G01X1558002Y216056D02*
X1558001Y216057D01*
G01X1558002Y208570D02*
Y216056D01*
G01X1558000Y208568D02*
X1558002Y208570D01*
G01X1558000Y205100D02*
Y208568D01*
G01X1529600Y276253D02*
Y279624D01*
G01X1528868Y275521D02*
X1529600Y276253D01*
G01X1528868Y261229D02*
Y275521D01*
G01X1535189Y254908D02*
X1528868Y261229D01*
G01X1535189Y234490D02*
Y254908D01*
G01X1538067Y231612D02*
X1535189Y234490D01*
G01X1542596Y278912D02*
Y283282D01*
G01X1550087Y271421D02*
X1542596Y278912D01*
G01X1550087Y250917D02*
Y271421D01*
G01X1550086Y250916D02*
X1550087Y250917D01*
G01X1550086Y249670D02*
Y250916D01*
G01X1553488Y246268D02*
X1550086Y249670D01*
G01X1569270Y272027D02*
Y280039D01*
G01X1569269Y272026D02*
X1569270Y272027D01*
G01X1569269Y269532D02*
Y272026D01*
G01X1577964Y260837D02*
X1569269Y269532D01*
G01X1577964Y249641D02*
Y260837D01*
G01X1583246Y244359D02*
X1577964Y249641D01*
G01X1583246Y241241D02*
Y244359D01*
G01X1583245Y241240D02*
X1583246Y241241D01*
G01X1583245Y239370D02*
Y241240D01*
G01X1583244Y239369D02*
X1583245Y239370D01*
G01X1583244Y229210D02*
Y239369D01*
G01X1576760Y222726D02*
X1583244Y229210D01*
G01X1576760Y222276D02*
Y222726D01*
G01X1576759Y222275D02*
X1576760Y222276D01*
G01X1576759Y218533D02*
Y222275D01*
G01X1576760Y218532D02*
X1576759Y218533D01*
G01X1554476Y279031D02*
Y282353D01*
G01X1559969Y273538D02*
X1554476Y279031D01*
G01X1559969Y256439D02*
Y273538D01*
G01X1562513Y253895D02*
X1559969Y256439D01*
G01X1562660Y253895D02*
X1562513D01*
G01X1562668Y253887D02*
X1562660Y253895D01*
G01X1563290Y253887D02*
X1562668D01*
G01X1563291Y253888D02*
X1563290Y253887D01*
G01X1563913Y253888D02*
X1563291D01*
G01X1563921Y253896D02*
X1563913Y253888D01*
G01X1563942Y253896D02*
X1563921D01*
G01X1565028Y252810D02*
X1563942Y253896D01*
G01X1565028Y244246D02*
Y252810D01*
G01X1566440Y242834D02*
X1565028Y244246D01*
G01X1566440Y242555D02*
Y242834D01*
G01X1566441Y242554D02*
X1566440Y242555D01*
G01X1566441Y239436D02*
Y242554D01*
G01X1566440Y239435D02*
X1566441Y239436D01*
G01X1566440Y231694D02*
Y239435D01*
G01X1565205Y230459D02*
X1566440Y231694D01*
G01X1545391Y237828D02*
X1547378Y235841D01*
G01X1545391Y241152D02*
Y237828D01*
G01X1543846Y242697D02*
X1545391Y241152D01*
G01X1543846Y253869D02*
Y242697D01*
G01X1534231Y263484D02*
X1543846Y253869D01*
G01X1534231Y269238D02*
Y263484D01*
G01X1537332Y272339D02*
X1534231Y269238D01*
G01X1537332Y281098D02*
Y272339D01*
G01X1570272Y230704D02*
X1568213Y228645D01*
G01X1570272Y234889D02*
Y230704D01*
G01X1564936Y232344D02*
X1563501Y230909D01*
G01X1564936Y240059D02*
Y232344D01*
G01X1564937Y240060D02*
X1564936Y240059D01*
G01X1564937Y241930D02*
Y240060D01*
G01X1561009Y245858D02*
X1564937Y241930D01*
G01X1561009Y252691D02*
Y245858D01*
G01X1558465Y255235D02*
X1561009Y252691D01*
G01X1558465Y272842D02*
Y255235D01*
G01X1550572Y280735D02*
X1558465Y272842D01*
G01X1527062Y257314D02*
Y276135D01*
G01X1534076Y234539D02*
Y250300D01*
G01X1536915Y231700D02*
X1534076Y234539D01*
G01X1542690Y238309D02*
Y236050D01*
G01X1539749Y241250D02*
X1542690Y238309D01*
G01X1539749Y255838D02*
Y241250D01*
G01X1532727Y262860D02*
X1539749Y255838D01*
G01X1532727Y270026D02*
Y262860D01*
G01X1535828Y273127D02*
X1532727Y270026D01*
G01X1535828Y279172D02*
Y273127D01*
G01X1528900Y286100D02*
X1535828Y279172D01*
G01X1544630Y235651D02*
X1542167Y233188D01*
G01X1544630Y240829D02*
Y235651D01*
G01X1543056Y242403D02*
X1544630Y240829D01*
G01X1543056Y253595D02*
Y242403D01*
G01X1533479Y263172D02*
X1543056Y253595D01*
G01X1533479Y269550D02*
Y263172D01*
G01X1536580Y272651D02*
X1533479Y269550D01*
G01X1536580Y280786D02*
Y272651D01*
G01X1586344Y271202D02*
Y282075D01*
G01X1595849Y261697D02*
X1586344Y271202D01*
G01X1579767Y219781D02*
X1579768Y219780D01*
G01X1579767Y221027D02*
Y219781D01*
G01X1586252Y227512D02*
X1579767Y221027D01*
G01X1586252Y237807D02*
Y227512D01*
G01X1586253Y237808D02*
X1586252Y237807D01*
G01X1586253Y239992D02*
Y237808D01*
G01X1586254Y239993D02*
X1586253Y239992D01*
G01X1586254Y245607D02*
Y239993D01*
G01X1580972Y250889D02*
X1586254Y245607D01*
G01X1580972Y262085D02*
Y250889D01*
G01X1572278Y270779D02*
X1580972Y262085D01*
G01X1572278Y281287D02*
Y270779D01*
G01X1528017Y247209D02*
Y251545D01*
G01X1530585Y244641D02*
X1528017Y247209D01*
G01X1530585Y233215D02*
Y244641D01*
G01X1533511Y230289D02*
X1530585Y233215D01*
G01X1545802Y233529D02*
X1543319Y231046D01*
G01X1570022Y271715D02*
Y280351D01*
G01X1570021Y271714D02*
X1570022Y271715D01*
G01X1570021Y269844D02*
Y271714D01*
G01X1578716Y261149D02*
X1570021Y269844D01*
G01X1578716Y249953D02*
Y261149D01*
G01X1583998Y244671D02*
X1578716Y249953D01*
G01X1583998Y240929D02*
Y244671D01*
G01X1583997Y240928D02*
X1583998Y240929D01*
G01X1583997Y239058D02*
Y240928D01*
G01X1583996Y239057D02*
X1583997Y239058D01*
G01X1583996Y228898D02*
Y239057D01*
G01X1577512Y222414D02*
X1583996Y228898D01*
G01X1577512Y221964D02*
Y222414D01*
G01X1577511Y221963D02*
X1577512Y221964D01*
G01X1577511Y218845D02*
Y221963D01*
G01X1577512Y218844D02*
X1577511Y218845D01*
G01X1565688Y232032D02*
X1564453Y230797D01*
G01X1565688Y239747D02*
Y232032D01*
G01X1565689Y239748D02*
X1565688Y239747D01*
G01X1565689Y242242D02*
Y239748D01*
G01X1561761Y246170D02*
X1565689Y242242D01*
G01X1561761Y253583D02*
Y246170D01*
G01X1559217Y256127D02*
X1561761Y253583D01*
G01X1559217Y273154D02*
Y256127D01*
G01X1551324Y281047D02*
X1559217Y273154D01*
G01X1578263Y219157D02*
X1578264Y219156D01*
G01X1578263Y221651D02*
Y219157D01*
G01X1584748Y228136D02*
X1578263Y221651D01*
G01X1584748Y238745D02*
Y228136D01*
G01X1584749Y238746D02*
X1584748Y238745D01*
G01X1584749Y240616D02*
Y238746D01*
G01X1584750Y240617D02*
X1584749Y240616D01*
G01X1584750Y244983D02*
Y240617D01*
G01X1579468Y250265D02*
X1584750Y244983D01*
G01X1579468Y261461D02*
Y250265D01*
G01X1570773Y270156D02*
X1579468Y261461D01*
G01X1570773Y271402D02*
Y270156D01*
G01X1570774Y271403D02*
X1570773Y271402D01*
G01X1570774Y280663D02*
Y271403D01*
G01X1532287Y233920D02*
X1535213Y230994D01*
G01X1532287Y245347D02*
Y233920D01*
G01X1529719Y247915D02*
X1532287Y245347D01*
G01X1529719Y252250D02*
Y247915D01*
G01X1567944Y231070D02*
X1566709Y229835D01*
G01X1567944Y238811D02*
Y231070D01*
G01X1567945Y238812D02*
X1567944Y238811D01*
G01X1567945Y243178D02*
Y238812D01*
G01X1567944Y243179D02*
X1567945Y243178D01*
G01X1567944Y243458D02*
Y243179D01*
G01X1566540Y244862D02*
X1567944Y243458D01*
G01X1566540Y253426D02*
Y244862D01*
G01X1564566Y255400D02*
X1566540Y253426D01*
G01X1563136Y255400D02*
X1564566D01*
G01X1561473Y257063D02*
X1563136Y255400D01*
G01X1561473Y274301D02*
Y257063D01*
G01X1556376Y279398D02*
X1561473Y274301D01*
G01X1556376Y299748D02*
Y279398D01*
G01X1580519Y220093D02*
X1580520Y220092D01*
G01X1580519Y220715D02*
Y220093D01*
G01X1587086Y227282D02*
X1580519Y220715D01*
G01X1587086Y248571D02*
Y227282D01*
G01X1584701Y250959D02*
X1587086Y248571D01*
G01X1584701Y256405D02*
Y250959D01*
G01X1584723Y256427D02*
X1584701Y256405D01*
G01X1584723Y257794D02*
Y256427D01*
G01X1584754Y257825D02*
X1584723Y257794D01*
G01X1584754Y260817D02*
Y257825D01*
G01X1584701Y260870D02*
X1584754Y260817D01*
G01X1584701Y264957D02*
Y260870D01*
G01X1573790Y275868D02*
X1584701Y264957D01*
G01X1573790Y284895D02*
Y275868D01*
G01X1567192Y231382D02*
X1565957Y230147D01*
G01X1567192Y239123D02*
Y231382D01*
G01X1567193Y239124D02*
X1567192Y239123D01*
G01X1567193Y242866D02*
Y239124D01*
G01X1567192Y242867D02*
X1567193Y242866D01*
G01X1567192Y243146D02*
Y242867D01*
G01X1565780Y244558D02*
X1567192Y243146D01*
G01X1565780Y253122D02*
Y244558D01*
G01X1564254Y254648D02*
X1565780Y253122D01*
G01X1563609Y254648D02*
X1564254D01*
G01X1563601Y254640D02*
X1563609Y254648D01*
G01X1562979Y254640D02*
X1563601D01*
G01X1562971Y254648D02*
X1562979Y254640D01*
G01X1562824Y254648D02*
X1562971D01*
G01X1560721Y256751D02*
X1562824Y254648D01*
G01X1560721Y273850D02*
Y256751D01*
G01X1555300Y279271D02*
X1560721Y273850D01*
G01X1555300Y282729D02*
Y279271D01*
G01X1556521Y273722D02*
X1549819Y280424D01*
G01X1556521Y251888D02*
Y273722D01*
G01X1559505Y248904D02*
X1556521Y251888D01*
G01X1559505Y245234D02*
Y248904D01*
G01X1563433Y241306D02*
X1559505Y245234D01*
G01X1563433Y240684D02*
Y241306D01*
G01X1563432Y240683D02*
X1563433Y240684D01*
G01X1563432Y232968D02*
Y240683D01*
G01X1560448Y229984D02*
X1563432Y232968D01*
G01X1564584Y278341D02*
X1562197Y280728D01*
G01X1564584Y269705D02*
Y278341D01*
G01X1564583Y269704D02*
X1564584Y269705D01*
G01X1564583Y267834D02*
Y269704D01*
G01X1573452Y258965D02*
X1564583Y267834D01*
G01X1573452Y247769D02*
Y258965D01*
G01X1578733Y242488D02*
X1573452Y247769D01*
G01X1578733Y241242D02*
Y242488D01*
G01X1578732Y241241D02*
X1578733Y241242D01*
G01X1578732Y231082D02*
Y241241D01*
G01X1572248Y224598D02*
X1578732Y231082D01*
G01X1572248Y224148D02*
Y224598D01*
G01X1572247Y224147D02*
X1572248Y224148D01*
G01X1551591Y250293D02*
X1554993Y246891D01*
G01X1551591Y272045D02*
Y250293D01*
G01X1544100Y279536D02*
X1551591Y272045D01*
G01X1574504Y223212D02*
X1574503Y223211D01*
G01X1574504Y223662D02*
Y223212D01*
G01X1580988Y230146D02*
X1574504Y223662D01*
G01X1580988Y240305D02*
Y230146D01*
G01X1580989Y240306D02*
X1580988Y240305D01*
G01X1580989Y242176D02*
Y240306D01*
G01X1580990Y242177D02*
X1580989Y242176D01*
G01X1580990Y243423D02*
Y242177D01*
G01X1575708Y248705D02*
X1580990Y243423D01*
G01X1575708Y259901D02*
Y248705D01*
G01X1566840Y268769D02*
X1575708Y259901D01*
G01X1566840Y279277D02*
Y268769D01*
G01X1564453Y281664D02*
X1566840Y279277D01*
G01X1556496Y247516D02*
X1556497Y247515D01*
G01X1556496Y247657D02*
Y247516D01*
G01X1553511Y250642D02*
X1556496Y247657D01*
G01X1553511Y251264D02*
Y250642D01*
G01X1553512Y251265D02*
X1553511Y251264D01*
G01X1553512Y255308D02*
Y251265D01*
G01X1553511Y255309D02*
X1553512Y255308D01*
G01X1553511Y257179D02*
Y255309D01*
G01X1553512Y257180D02*
X1553511Y257179D01*
G01X1553512Y272322D02*
Y257180D01*
G01X1545744Y280090D02*
X1553512Y272322D01*
G01X1576007Y218221D02*
X1576008Y218220D01*
G01X1576007Y222587D02*
Y218221D01*
G01X1576008Y222588D02*
X1576007Y222587D01*
G01X1576008Y223038D02*
Y222588D01*
G01X1582492Y229522D02*
X1576008Y223038D01*
G01X1582492Y239681D02*
Y229522D01*
G01X1582493Y239682D02*
X1582492Y239681D01*
G01X1582493Y241552D02*
Y239682D01*
G01X1582494Y241553D02*
X1582493Y241552D01*
G01X1582494Y244047D02*
Y241553D01*
G01X1577212Y249329D02*
X1582494Y244047D01*
G01X1577212Y260525D02*
Y249329D01*
G01X1568517Y269220D02*
X1577212Y260525D01*
G01X1568517Y272338D02*
Y269220D01*
G01X1568518Y272339D02*
X1568517Y272338D01*
G01X1568518Y279727D02*
Y272339D01*
G01X1557248Y247828D02*
X1557249Y247827D01*
G01X1557248Y247969D02*
Y247828D01*
G01X1554264Y250953D02*
X1557248Y247969D01*
G01X1554264Y255620D02*
Y250953D01*
G01X1554263Y255621D02*
X1554264Y255620D01*
G01X1554263Y256867D02*
Y255621D01*
G01X1554264Y256868D02*
X1554263Y256867D01*
G01X1554264Y272634D02*
Y256868D01*
G01X1546498Y280400D02*
X1554264Y272634D01*
G01X1536341Y234968D02*
X1539511Y231798D01*
G01X1536341Y255386D02*
Y234968D01*
G01X1530020Y261707D02*
X1536341Y255386D01*
G01X1530020Y275043D02*
Y261707D01*
G01X1531624Y276647D02*
X1530020Y275043D01*
G01X1531624Y279230D02*
Y276647D01*
G01X1567524Y259036D02*
X1567000Y259560D01*
G01X1567524Y254607D02*
Y259036D01*
G01X1570071Y252060D02*
X1567524Y254607D01*
G01X1570071Y246163D02*
Y252060D01*
G01X1568696Y244788D02*
X1570071Y246163D01*
G01X1568696Y243491D02*
Y244788D01*
G01X1568697Y243490D02*
X1568696Y243491D01*
G01X1568697Y238500D02*
Y243490D01*
G01X1568696Y238499D02*
X1568697Y238500D01*
G01X1568696Y230623D02*
Y238499D01*
G01X1567461Y229388D02*
X1568696Y230623D01*
G01X1588590Y226658D02*
X1582298Y220366D01*
G01X1588590Y248859D02*
Y226658D01*
G01X1591360Y251629D02*
X1588590Y248859D01*
G01X1575393Y278531D02*
X1593289Y260635D01*
G01X1575393Y288104D02*
Y278531D01*
G01X1565336Y278653D02*
X1562949Y281040D01*
G01X1565336Y269393D02*
Y278653D01*
G01X1565335Y269392D02*
X1565336Y269393D01*
G01X1565335Y268146D02*
Y269392D01*
G01X1574204Y259277D02*
X1565335Y268146D01*
G01X1574204Y248081D02*
Y259277D01*
G01X1579485Y242800D02*
X1574204Y248081D01*
G01X1579485Y240930D02*
Y242800D01*
G01X1579484Y240929D02*
X1579485Y240930D01*
G01X1579484Y230770D02*
Y240929D01*
G01X1573000Y224286D02*
X1579484Y230770D01*
G01X1573000Y223836D02*
Y224286D01*
G01X1572999Y223835D02*
X1573000Y223836D01*
G01X1575255Y217909D02*
X1575256Y217908D01*
G01X1575255Y222899D02*
Y217909D01*
G01X1575256Y222900D02*
X1575255Y222899D01*
G01X1575256Y223350D02*
Y222900D01*
G01X1581740Y229834D02*
X1575256Y223350D01*
G01X1581740Y239993D02*
Y229834D01*
G01X1581741Y239994D02*
X1581740Y239993D01*
G01X1581741Y241864D02*
Y239994D01*
G01X1581742Y241865D02*
X1581741Y241864D01*
G01X1581742Y243735D02*
Y241865D01*
G01X1576460Y249017D02*
X1581742Y243735D01*
G01X1576460Y260213D02*
Y249017D01*
G01X1567765Y268908D02*
X1576460Y260213D01*
G01X1567765Y272650D02*
Y268908D01*
G01X1567766Y272651D02*
X1567765Y272650D01*
G01X1567766Y279415D02*
Y272651D01*
G01X1565205Y281976D02*
X1567766Y279415D01*
G01X1584568Y270986D02*
Y281339D01*
G01X1594441Y261113D02*
X1584568Y270986D01*
G01X1528131Y229185D02*
Y238270D01*
G01X1527019Y222973D02*
Y228073D01*
G01X1573752Y223524D02*
X1573751Y223523D01*
G01X1573752Y223974D02*
Y223524D01*
G01X1580236Y230458D02*
X1573752Y223974D01*
G01X1580236Y240617D02*
Y230458D01*
G01X1580237Y240618D02*
X1580236Y240617D01*
G01X1580237Y242488D02*
Y240618D01*
G01X1580238Y242489D02*
X1580237Y242488D01*
G01X1580238Y243111D02*
Y242489D01*
G01X1574956Y248393D02*
X1580238Y243111D01*
G01X1574956Y259589D02*
Y248393D01*
G01X1566087Y268458D02*
X1574956Y259589D01*
G01X1566087Y269080D02*
Y268458D01*
G01X1566088Y269081D02*
X1566087Y269080D01*
G01X1566088Y278965D02*
Y269081D01*
G01X1563701Y281352D02*
X1566088Y278965D01*
G01X1538836Y271715D02*
Y281722D01*
G01X1535735Y268614D02*
X1538836Y271715D01*
G01X1535735Y264108D02*
Y268614D01*
G01X1545351Y254492D02*
X1535735Y264108D01*
G01X1545351Y243320D02*
Y254492D01*
G01X1546977Y241694D02*
X1545351Y243320D01*
G01X1546977Y239290D02*
Y241694D01*
G01X1548976Y237291D02*
X1546977Y239290D01*
G01X1547869Y239462D02*
Y243356D01*
G01X1549728Y237603D02*
X1547869Y239462D01*
G01X1570744Y224772D02*
X1570743Y224771D01*
G01X1570744Y225222D02*
Y224772D01*
G01X1577228Y231706D02*
X1570744Y225222D01*
G01X1577228Y241865D02*
Y231706D01*
G01X1571788Y247305D02*
X1577228Y241865D01*
G01X1571788Y252545D02*
Y247305D01*
G01X1569526Y254807D02*
X1571788Y252545D01*
G01X1569526Y258723D02*
Y254807D01*
G01X1569527Y258724D02*
X1569526Y258723D01*
G01X1569527Y259346D02*
Y258724D01*
G01X1569526Y259347D02*
X1569527Y259346D01*
G01X1569526Y260503D02*
Y259347D01*
G01X1563080Y266949D02*
X1569526Y260503D01*
G01X1563080Y267209D02*
Y266949D01*
G01X1563079Y267210D02*
X1563080Y267209D01*
G01X1563079Y270328D02*
Y267210D01*
G01X1563080Y270329D02*
X1563079Y270328D01*
G01X1563080Y277717D02*
Y270329D01*
G01X1557924Y282873D02*
X1563080Y277717D01*
G01X1540340Y271091D02*
Y282346D01*
G01X1539424Y270175D02*
X1540340Y271091D01*
G01X1539424Y262547D02*
Y270175D01*
G01X1547484Y254487D02*
X1539424Y262547D01*
G01X1547484Y249080D02*
Y254487D01*
G01X1551232Y245332D02*
X1547484Y249080D01*
G01X1562680Y233280D02*
X1559600Y230200D01*
G01X1562680Y240995D02*
Y233280D01*
G01X1558753Y244922D02*
X1562680Y240995D01*
G01X1558753Y248592D02*
Y244922D01*
G01X1555769Y251576D02*
X1558753Y248592D01*
G01X1555769Y254997D02*
Y251576D01*
G01X1555768Y254998D02*
X1555769Y254997D01*
G01X1555768Y256244D02*
Y254998D01*
G01X1555769Y256245D02*
X1555768Y256244D01*
G01X1555769Y273410D02*
Y256245D01*
G01X1549067Y280112D02*
X1555769Y273410D01*
G01X1549334Y249358D02*
X1552736Y245956D01*
G01X1549334Y271110D02*
Y249358D01*
G01X1541844Y278600D02*
X1549334Y271110D01*
G01X1541844Y282970D02*
Y278600D01*
G01X1571526Y271091D02*
Y280975D01*
G01X1571525Y271090D02*
X1571526Y271091D01*
G01X1571525Y270468D02*
Y271090D01*
G01X1580220Y261773D02*
X1571525Y270468D01*
G01X1580220Y250577D02*
Y261773D01*
G01X1585502Y245295D02*
X1580220Y250577D01*
G01X1585502Y240305D02*
Y245295D01*
G01X1585501Y240304D02*
X1585502Y240305D01*
G01X1585501Y238120D02*
Y240304D01*
G01X1585500Y238119D02*
X1585501Y238120D01*
G01X1585500Y227824D02*
Y238119D01*
G01X1579015Y221339D02*
X1585500Y227824D01*
G01X1579015Y219469D02*
Y221339D01*
G01X1579016Y219468D02*
X1579015Y219469D01*
G01X1540362Y235085D02*
X1540663Y234784D01*
G01X1540362Y238509D02*
Y235085D01*
G01X1537493Y241378D02*
X1540362Y238509D01*
G01X1537493Y253952D02*
Y241378D01*
G01X1537494Y253953D02*
X1537493Y253952D01*
G01X1537494Y255863D02*
Y253953D01*
G01X1531172Y262185D02*
X1537494Y255863D01*
G01X1531172Y274565D02*
Y262185D01*
G01X1532776Y276169D02*
X1531172Y274565D01*
G01X1532776Y279708D02*
Y276169D01*
G01X1552485Y272252D02*
X1544852Y279885D01*
G01X1552485Y250463D02*
Y272252D01*
G01X1555745Y247203D02*
X1552485Y250463D01*
G01X1533528Y275857D02*
Y280020D01*
G01X1531924Y274253D02*
X1533528Y275857D01*
G01X1531924Y262497D02*
Y274253D01*
G01X1538246Y256175D02*
X1531924Y262497D01*
G01X1538246Y253641D02*
Y256175D01*
G01X1538245Y253640D02*
X1538246Y253641D01*
G01X1538245Y241690D02*
Y253640D01*
G01X1541114Y238821D02*
X1538245Y241690D01*
G01X1541114Y235397D02*
Y238821D01*
G01X1541415Y235096D02*
X1541114Y235397D01*
G01X1569992Y225084D02*
X1569991Y225083D01*
G01X1569992Y225534D02*
Y225084D01*
G01X1576476Y232018D02*
X1569992Y225534D01*
G01X1576476Y241553D02*
Y232018D01*
G01X1571036Y246993D02*
X1576476Y241553D01*
G01X1571036Y252233D02*
Y246993D01*
G01X1568774Y254495D02*
X1571036Y252233D01*
G01X1568774Y260067D02*
Y254495D01*
G01X1562309Y266532D02*
X1568774Y260067D01*
G01X1562309Y277424D02*
Y266532D01*
G01X1557172Y282561D02*
X1562309Y277424D01*
G01X1550838Y249982D02*
X1554241Y246579D01*
G01X1550838Y250604D02*
Y249982D01*
G01X1550839Y250605D02*
X1550838Y250604D01*
G01X1550839Y271733D02*
Y250605D01*
G01X1543348Y279224D02*
X1550839Y271733D01*
G01X1543348Y283594D02*
Y279224D01*
G01X1528883Y231103D02*
Y239118D01*
G01X1530285Y229701D02*
X1528883Y231103D01*
G01X1538084Y272027D02*
Y281410D01*
G01X1534983Y268926D02*
X1538084Y272027D01*
G01X1534983Y263796D02*
Y268926D01*
G01X1544599Y254180D02*
X1534983Y263796D01*
G01X1544599Y243008D02*
Y254180D01*
G01X1546169Y241438D02*
X1544599Y243008D01*
G01X1546169Y239034D02*
Y241438D01*
G01X1548224Y236979D02*
X1546169Y239034D01*
G01X1546732Y248768D02*
X1550480Y245020D01*
G01X1546732Y254175D02*
Y248768D01*
G01X1536487Y264420D02*
X1546732Y254175D01*
G01X1536487Y268302D02*
Y264420D01*
G01X1539588Y271403D02*
X1536487Y268302D01*
G01X1539588Y282034D02*
Y271403D01*
G01X1541092Y278288D02*
Y282658D01*
G01X1548582Y270798D02*
X1541092Y278288D01*
G01X1548582Y249046D02*
Y270798D01*
G01X1551984Y245644D02*
X1548582Y249046D01*
G01X1563832Y278029D02*
X1561376Y280485D01*
G01X1563832Y270017D02*
Y278029D01*
G01X1563831Y270016D02*
X1563832Y270017D01*
G01X1563831Y267522D02*
Y270016D01*
G01X1563832Y267521D02*
X1563831Y267522D01*
G01X1563832Y267277D02*
Y267521D01*
G01X1570278Y260831D02*
X1563832Y267277D01*
G01X1570278Y259659D02*
Y260831D01*
G01X1570280Y259657D02*
X1570278Y259659D01*
G01X1570280Y259035D02*
Y259657D01*
G01X1570279Y259034D02*
X1570280Y259035D01*
G01X1570279Y258412D02*
Y259034D01*
G01X1570278Y258411D02*
X1570279Y258412D01*
G01X1570278Y255119D02*
Y258411D01*
G01X1572540Y252857D02*
X1570278Y255119D01*
G01X1572540Y247617D02*
Y252857D01*
G01X1577981Y242176D02*
X1572540Y247617D01*
G01X1577981Y241554D02*
Y242176D01*
G01X1577980Y241553D02*
X1577981Y241554D01*
G01X1577980Y231394D02*
Y241553D01*
G01X1571496Y224910D02*
X1577980Y231394D01*
G01X1571496Y224460D02*
Y224910D01*
G01X1571495Y224459D02*
X1571496Y224460D01*
G01X1564184Y232656D02*
X1561200Y229672D01*
G01X1564184Y240371D02*
Y232656D01*
G01X1564185Y240372D02*
X1564184Y240371D01*
G01X1564185Y241618D02*
Y240372D01*
G01X1560257Y245546D02*
X1564185Y241618D01*
G01X1560257Y250443D02*
Y245546D01*
G01X1558700Y252000D02*
X1560257Y250443D01*
G01X1587838Y226970D02*
X1581272Y220404D01*
G01X1587838Y249171D02*
Y226970D01*
G01X1589592Y250925D02*
X1587838Y249171D01*
G01X1572730Y229902D02*
Y235931D01*
G01X1569239Y226411D02*
X1572730Y229902D01*
G01X1555017Y273098D02*
X1548200Y279915D01*
G01X1555017Y256557D02*
Y273098D01*
G01X1555015Y256555D02*
X1555017Y256557D01*
G01X1555015Y255933D02*
Y256555D01*
G01X1555016Y255932D02*
X1555015Y255933D01*
G01X1555016Y254686D02*
Y255932D01*
G01X1555017Y254685D02*
X1555016Y254686D01*
G01X1555017Y251264D02*
Y254685D01*
G01X1558001Y248280D02*
X1555017Y251264D01*
G01X1538206Y299792D02*
Y303741D01*
G01X1541680Y296318D02*
X1538206Y299792D01*
G01X1541680Y290894D02*
Y296318D01*
G01X1541043Y290257D02*
X1541680Y290894D01*
G01X1541043Y284835D02*
Y290257D01*
G01X1542596Y283282D02*
X1541043Y284835D01*
G01X1551720Y339823D02*
Y341980D01*
G01X1557670Y333873D02*
X1551720Y339823D01*
G01X1557670Y326600D02*
Y333873D01*
G01X1561082Y323188D02*
X1557670Y326600D01*
G01X1561082Y313714D02*
Y323188D01*
G01X1558421Y311053D02*
X1561082Y313714D01*
G01X1558421Y307279D02*
Y311053D01*
G01X1563668Y302032D02*
X1558421Y307279D01*
G01X1563668Y297582D02*
Y302032D01*
G01X1568405Y292845D02*
X1563668Y297582D01*
G01X1568405Y289134D02*
Y292845D01*
G01X1566709Y287438D02*
X1568405Y289134D01*
G01X1566709Y282600D02*
Y287438D01*
G01X1569270Y280039D02*
X1566709Y282600D01*
G01X1583881Y292914D02*
X1601170Y275625D01*
G01X1583881Y296775D02*
Y292914D01*
G01X1580415Y300241D02*
X1583881Y296775D01*
G01X1580415Y307021D02*
Y300241D01*
G01X1577425Y310011D02*
X1580415Y307021D01*
G01X1577425Y312664D02*
Y310011D01*
G01X1566198Y323891D02*
X1577425Y312664D01*
G01X1566198Y334509D02*
Y323891D01*
G01X1560672Y340035D02*
X1566198Y334509D01*
G01X1560672Y340207D02*
Y340035D01*
G01X1557179Y343700D02*
X1560672Y340207D01*
G01X1578874Y284799D02*
X1578577D01*
G01X1580424Y283249D02*
X1578874Y284799D01*
G01X1581974Y283249D02*
X1580424D01*
G01X1583248Y284523D02*
X1581974Y283249D01*
G01X1585888Y284523D02*
X1583248D01*
G01X1595511Y274900D02*
X1585888Y284523D01*
G01X1542576Y337939D02*
X1532390Y348125D01*
G01X1542576Y332472D02*
Y337939D01*
G01X1542990Y332058D02*
X1542576Y332472D01*
G01X1542990Y331202D02*
Y332058D01*
G01X1546306Y327886D02*
X1542990Y331202D01*
G01X1546306Y311327D02*
Y327886D01*
G01X1547572Y310061D02*
X1546306Y311327D01*
G01X1547572Y307740D02*
Y310061D01*
G01X1548291Y307021D02*
X1547572Y307740D01*
G01X1548291Y302035D02*
Y307021D01*
G01X1552447Y297879D02*
X1548291Y302035D01*
G01X1552447Y289568D02*
Y297879D01*
G01X1553535Y288480D02*
X1552447Y289568D01*
G01X1553535Y283294D02*
Y288480D01*
G01X1554476Y282353D02*
X1553535Y283294D01*
G01X1535550Y282880D02*
X1537332Y281098D01*
G01X1535550Y283616D02*
Y282880D01*
G01X1535548Y283618D02*
X1535550Y283616D01*
G01X1535548Y284864D02*
Y283618D01*
G01X1535549Y284865D02*
X1535548Y284864D01*
G01X1535549Y285487D02*
Y284865D01*
G01X1535550Y285488D02*
X1535549Y285487D01*
G01X1535550Y289223D02*
Y285488D01*
G01X1531320Y293453D02*
X1535550Y289223D01*
G01X1531320Y298274D02*
Y293453D01*
G01X1529113Y330701D02*
Y329395D01*
G01X1550572Y282735D02*
Y280735D01*
G01X1552031Y284194D02*
X1550572Y282735D01*
G01X1552031Y287856D02*
Y284194D01*
G01X1548448Y291439D02*
X1552031Y287856D01*
G01X1548448Y299750D02*
Y291439D01*
G01X1546787Y301411D02*
X1548448Y299750D01*
G01X1546787Y306232D02*
Y301411D01*
G01X1542282Y310737D02*
X1546787Y306232D01*
G01X1542282Y312106D02*
Y310737D01*
G01X1543564Y313388D02*
X1542282Y312106D01*
G01X1543564Y320400D02*
Y313388D01*
G01X1540624Y323340D02*
X1543564Y320400D01*
G01X1540624Y325253D02*
Y323340D01*
G01X1541486Y326115D02*
X1540624Y325253D01*
G01X1541486Y331434D02*
Y326115D01*
G01X1541072Y331848D02*
X1541486Y331434D01*
G01X1541072Y337315D02*
Y331848D01*
G01X1530188Y348199D02*
X1541072Y337315D01*
G01X1528900Y291573D02*
Y286100D01*
G01X1529633Y292306D02*
X1528900Y291573D01*
G01X1529633Y297833D02*
Y292306D01*
G01X1534798Y282568D02*
X1536580Y280786D01*
G01X1534798Y282672D02*
Y282568D01*
G01X1532238Y285232D02*
X1534798Y282672D01*
G01X1532238Y290361D02*
Y285232D01*
G01X1530568Y292031D02*
X1532238Y290361D01*
G01X1530568Y297962D02*
Y292031D01*
G01X1527537Y330048D02*
Y329484D01*
G01X1571263Y306727D02*
X1569926Y308064D01*
G01X1571263Y306269D02*
Y306727D01*
G01X1575646Y301886D02*
X1571263Y306269D01*
G01X1575646Y289843D02*
Y301886D01*
G01X1576801Y288688D02*
X1575646Y289843D01*
G01X1576801Y284063D02*
Y288688D01*
G01X1579023Y281841D02*
X1576801Y284063D01*
G01X1582558Y281841D02*
X1579023D01*
G01X1583832Y283115D02*
X1582558Y281841D01*
G01X1585304Y283115D02*
X1583832D01*
G01X1586344Y282075D02*
X1585304Y283115D01*
G01X1569717Y283848D02*
X1572278Y281287D01*
G01X1569717Y285989D02*
Y283848D01*
G01X1570791Y287063D02*
X1569717Y285989D01*
G01X1572336Y287063D02*
X1570791D01*
G01X1582854Y294906D02*
X1581940Y295820D01*
G01X1582854Y292877D02*
Y294906D01*
G01X1600192Y275539D02*
X1582854Y292877D01*
G01X1552472Y340135D02*
Y342328D01*
G01X1558448Y334159D02*
X1552472Y340135D01*
G01X1558448Y327452D02*
Y334159D01*
G01X1561976Y323924D02*
X1558448Y327452D01*
G01X1561976Y307514D02*
Y323924D01*
G01X1563609Y305881D02*
X1561976Y307514D01*
G01X1565317Y305881D02*
X1563609D01*
G01X1567461Y303737D02*
X1565317Y305881D01*
G01X1567461Y295169D02*
Y303737D01*
G01X1569362Y293268D02*
X1567461Y295169D01*
G01X1569362Y289027D02*
Y293268D01*
G01X1567461Y287126D02*
X1569362Y289027D01*
G01X1567461Y282912D02*
Y287126D01*
G01X1570022Y280351D02*
X1567461Y282912D01*
G01X1551324Y282423D02*
Y281047D01*
G01X1552783Y283882D02*
X1551324Y282423D01*
G01X1552783Y288168D02*
Y283882D01*
G01X1549200Y291751D02*
X1552783Y288168D01*
G01X1549200Y300062D02*
Y291751D01*
G01X1547539Y301723D02*
X1549200Y300062D01*
G01X1547539Y306709D02*
Y301723D01*
G01X1546820Y307428D02*
X1547539Y306709D01*
G01X1546820Y309675D02*
Y307428D01*
G01X1545440Y311055D02*
X1546820Y309675D01*
G01X1545440Y327688D02*
Y311055D01*
G01X1542238Y330890D02*
X1545440Y327688D01*
G01X1542238Y331746D02*
Y330890D01*
G01X1541824Y332160D02*
X1542238Y331746D01*
G01X1541824Y337627D02*
Y332160D01*
G01X1531638Y347813D02*
X1541824Y337627D01*
G01X1568213Y283224D02*
X1570774Y280663D01*
G01X1568213Y286814D02*
Y283224D01*
G01X1571800Y290401D02*
X1568213Y286814D01*
G01X1571800Y299162D02*
Y290401D01*
G01X1568806Y302156D02*
X1571800Y299162D01*
G01X1568806Y303456D02*
Y302156D01*
G01X1565629Y306633D02*
X1568806Y303456D01*
G01X1563921Y306633D02*
X1565629D01*
G01X1562801Y307753D02*
X1563921Y306633D01*
G01X1562801Y331252D02*
Y307753D01*
G01X1555501Y338552D02*
X1562801Y331252D01*
G01X1555119Y338552D02*
X1555501D01*
G01X1553224Y340447D02*
X1555119Y338552D01*
G01X1553224Y342676D02*
Y340447D01*
G01X1551192Y304932D02*
X1556376Y299748D01*
G01X1551192Y306248D02*
Y304932D01*
G01X1549076Y308364D02*
X1551192Y306248D01*
G01X1549076Y310594D02*
Y308364D01*
G01X1551398Y312916D02*
X1549076Y310594D01*
G01X1551398Y317953D02*
Y312916D01*
G01X1552826Y319381D02*
X1551398Y317953D01*
G01X1552826Y321603D02*
Y319381D01*
G01X1550428Y324001D02*
X1552826Y321603D01*
G01X1550428Y325632D02*
Y324001D01*
G01X1547839Y328221D02*
X1550428Y325632D01*
G01X1547605Y328221D02*
X1547839D01*
G01X1543742Y332084D02*
X1547605Y328221D01*
G01X1543742Y332941D02*
Y332084D01*
G01X1543328Y333355D02*
X1543742Y332941D01*
G01X1543328Y338251D02*
Y333355D01*
G01X1533142Y348437D02*
X1543328Y338251D01*
G01X1554287Y283742D02*
X1555300Y282729D01*
G01X1554287Y288792D02*
Y283742D01*
G01X1553199Y289880D02*
X1554287Y288792D01*
G01X1553199Y298211D02*
Y289880D01*
G01X1549043Y302367D02*
X1553199Y298211D01*
G01X1549043Y304283D02*
Y302367D01*
G01X1549044Y304284D02*
X1549043Y304283D01*
G01X1549044Y307332D02*
Y304284D01*
G01X1548324Y308052D02*
X1549044Y307332D01*
G01X1548324Y310906D02*
Y308052D01*
G01X1550600Y313182D02*
X1548324Y310906D01*
G01X1550600Y319653D02*
Y313182D01*
G01X1551250Y320303D02*
X1550600Y319653D01*
G01X1584633Y293226D02*
X1601922Y275937D01*
G01X1584633Y297087D02*
Y293226D01*
G01X1581294Y300426D02*
X1584633Y297087D01*
G01X1581294Y307206D02*
Y300426D01*
G01X1579258Y309242D02*
X1581294Y307206D01*
G01X1579258Y314682D02*
Y309242D01*
G01X1577250Y316690D02*
X1579258Y314682D01*
G01X1577250Y321288D02*
Y316690D01*
G01X1568572Y329966D02*
X1577250Y321288D01*
G01X1568558Y329966D02*
X1568572D01*
G01X1566950Y331574D02*
X1568558Y329966D01*
G01X1566950Y334821D02*
Y331574D01*
G01X1561424Y340347D02*
X1566950Y334821D01*
G01X1561424Y341699D02*
Y340347D01*
G01X1585370Y340830D02*
X1583331Y342869D01*
G01X1585370Y332582D02*
Y340830D01*
G01X1594686Y323266D02*
X1585370Y332582D01*
G01X1540320Y336997D02*
X1529672Y347645D01*
G01X1540320Y331536D02*
Y336997D01*
G01X1540734Y331122D02*
X1540320Y331536D01*
G01X1540734Y326427D02*
Y331122D01*
G01X1539872Y325565D02*
X1540734Y326427D01*
G01X1539872Y323021D02*
Y325565D01*
G01X1542812Y320081D02*
X1539872Y323021D01*
G01X1542812Y313700D02*
Y320081D01*
G01X1541530Y312418D02*
X1542812Y313700D01*
G01X1541530Y310425D02*
Y312418D01*
G01X1546035Y305920D02*
X1541530Y310425D01*
G01X1546035Y301099D02*
Y305920D01*
G01X1547696Y299438D02*
X1546035Y301099D01*
G01X1547696Y291127D02*
Y299438D01*
G01X1551279Y287544D02*
X1547696Y291127D01*
G01X1551279Y284506D02*
Y287544D01*
G01X1549820Y283047D02*
X1551279Y284506D01*
G01X1549820Y281047D02*
Y283047D01*
G01X1549819Y281046D02*
X1549820Y281047D01*
G01X1549819Y280424D02*
Y281046D01*
G01X1547087Y336664D02*
X1534646Y349105D01*
G01X1547850Y336664D02*
X1547087D01*
G01X1550348Y334166D02*
X1547850Y336664D01*
G01X1550348Y330214D02*
Y334166D01*
G01X1552684Y327878D02*
X1550348Y330214D01*
G01X1552684Y325202D02*
Y327878D01*
G01X1555082Y322804D02*
X1552684Y325202D01*
G01X1555082Y317982D02*
Y322804D01*
G01X1553909Y316809D02*
X1555082Y317982D01*
G01X1553909Y305407D02*
Y316809D01*
G01X1559156Y300160D02*
X1553909Y305407D01*
G01X1559156Y293373D02*
Y300160D01*
G01X1561144Y291385D02*
X1559156Y293373D01*
G01X1561144Y287856D02*
Y291385D01*
G01X1562197Y286803D02*
X1561144Y287856D01*
G01X1562197Y280728D02*
Y286803D01*
G01X1587721Y320428D02*
X1589374D01*
G01X1586310Y321839D02*
X1587721Y320428D01*
G01X1586310Y329640D02*
Y321839D01*
G01X1578589Y337372D02*
X1586310Y329640D01*
G01X1578589Y340521D02*
Y337372D01*
G01X1558980Y360130D02*
X1578589Y340521D01*
G01X1544100Y283906D02*
Y279536D01*
G01X1542547Y285459D02*
X1544100Y283906D01*
G01X1542547Y289633D02*
Y285459D01*
G01X1543184Y290270D02*
X1542547Y289633D01*
G01X1543184Y296942D02*
Y290270D01*
G01X1540652Y299474D02*
X1543184Y296942D01*
G01X1540652Y304839D02*
Y299474D01*
G01X1537934Y307557D02*
X1540652Y304839D01*
G01X1534845Y307557D02*
X1537934D01*
G01X1533257Y309145D02*
X1534845Y307557D01*
G01X1533257Y310451D02*
Y309145D01*
G01X1534414Y311608D02*
X1533257Y310451D01*
G01X1534414Y323957D02*
Y311608D01*
G01X1534804Y324347D02*
X1534414Y323957D01*
G01X1534804Y325653D02*
Y324347D01*
G01X1533693Y326764D02*
X1534804Y325653D01*
G01X1533693Y333695D02*
Y326764D01*
G01X1528091Y339297D02*
X1533693Y333695D01*
G01X1581619Y290920D02*
X1597351Y275188D01*
G01X1578790Y290920D02*
X1581619D01*
G01X1564453Y287800D02*
Y281664D01*
G01X1563400Y288853D02*
X1564453Y287800D01*
G01X1563400Y293401D02*
Y288853D01*
G01X1561412Y295389D02*
X1563400Y293401D01*
G01X1561412Y301096D02*
Y295389D01*
G01X1556165Y306343D02*
X1561412Y301096D01*
G01X1556165Y312033D02*
Y306343D01*
G01X1558826Y314694D02*
X1556165Y312033D01*
G01X1558826Y322252D02*
Y314694D01*
G01X1554941Y326137D02*
X1558826Y322252D01*
G01X1554941Y328869D02*
Y326137D01*
G01X1552604Y331206D02*
X1554941Y328869D01*
G01X1552604Y335102D02*
Y331206D01*
G01X1548786Y338920D02*
X1552604Y335102D01*
G01X1548023Y338920D02*
X1548786D01*
G01X1536902Y350041D02*
X1548023Y338920D01*
G01X1545744Y284390D02*
Y280090D01*
G01X1544051Y286083D02*
X1545744Y284390D01*
G01X1544051Y289009D02*
Y286083D01*
G01X1544688Y289646D02*
X1544051Y289009D01*
G01X1544688Y297922D02*
Y289646D01*
G01X1543012Y299598D02*
X1544688Y297922D01*
G01X1543012Y304687D02*
Y299598D01*
G01X1538400Y309299D02*
X1543012Y304687D01*
G01X1538400Y310779D02*
Y309299D01*
G01X1536074Y313105D02*
X1538400Y310779D01*
G01X1536074Y321483D02*
Y313105D01*
G01X1536518Y321927D02*
X1536074Y321483D01*
G01X1536518Y326273D02*
Y321927D01*
G01X1535326Y327465D02*
X1536518Y326273D01*
G01X1535326Y337735D02*
Y327465D01*
G01X1528425Y344636D02*
X1535326Y337735D01*
G01X1565957Y282288D02*
X1568518Y279727D01*
G01X1565957Y287750D02*
Y282288D01*
G01X1567622Y289415D02*
X1565957Y287750D01*
G01X1567622Y292139D02*
Y289415D01*
G01X1562916Y296845D02*
X1567622Y292139D01*
G01X1562916Y301720D02*
Y296845D01*
G01X1557669Y306967D02*
X1562916Y301720D01*
G01X1557669Y311409D02*
Y306967D01*
G01X1560330Y314070D02*
X1557669Y311409D01*
G01X1560330Y322876D02*
Y314070D01*
G01X1556900Y326306D02*
X1560330Y322876D01*
G01X1556900Y333434D02*
Y326306D01*
G01X1550932Y339402D02*
X1556900Y333434D01*
G01X1550932Y341668D02*
Y339402D01*
G01X1546498Y284700D02*
Y280400D01*
G01X1544803Y286395D02*
X1546498Y284700D01*
G01X1544803Y288697D02*
Y286395D01*
G01X1545440Y289334D02*
X1544803Y288697D01*
G01X1545440Y298234D02*
Y289334D01*
G01X1543764Y299910D02*
X1545440Y298234D01*
G01X1543764Y304999D02*
Y299910D01*
G01X1539200Y309563D02*
X1543764Y304999D01*
G01X1539200Y311043D02*
Y309563D01*
G01X1536874Y313369D02*
X1539200Y311043D01*
G01X1536874Y321219D02*
Y313369D01*
G01X1537418Y321763D02*
X1536874Y321219D01*
G01X1537418Y326437D02*
Y321763D01*
G01X1536078Y327777D02*
X1537418Y326437D01*
G01X1536078Y338047D02*
Y327777D01*
G01X1528737Y345388D02*
X1536078Y338047D01*
G01X1574080Y289417D02*
X1575393Y288104D01*
G01X1574080Y299520D02*
Y289417D01*
G01X1571040Y302560D02*
X1574080Y299520D01*
G01X1571040Y304500D02*
Y302560D01*
G01X1569252Y306288D02*
X1571040Y304500D01*
G01X1569190Y306288D02*
X1569252D01*
G01X1566830Y308648D02*
X1569190Y306288D01*
G01X1566830Y315037D02*
Y308648D01*
G01X1566910Y315117D02*
X1566830Y315037D01*
G01X1547399Y337416D02*
X1535398Y349417D01*
G01X1548162Y337416D02*
X1547399D01*
G01X1551100Y334478D02*
X1548162Y337416D01*
G01X1551100Y330526D02*
Y334478D01*
G01X1553436Y328190D02*
X1551100Y330526D01*
G01X1553436Y325514D02*
Y328190D01*
G01X1555834Y323116D02*
X1553436Y325514D01*
G01X1555834Y317670D02*
Y323116D01*
G01X1554661Y316497D02*
X1555834Y317670D01*
G01X1554661Y305719D02*
Y316497D01*
G01X1559908Y300472D02*
X1554661Y305719D01*
G01X1559908Y294138D02*
Y300472D01*
G01X1561896Y292150D02*
X1559908Y294138D01*
G01X1561896Y288229D02*
Y292150D01*
G01X1562949Y287176D02*
X1561896Y288229D01*
G01X1562949Y281040D02*
Y287176D01*
G01X1565205Y288062D02*
Y281976D01*
G01X1566870Y289727D02*
X1565205Y288062D01*
G01X1566870Y291391D02*
Y289727D01*
G01X1562164Y296097D02*
X1566870Y291391D01*
G01X1562164Y301408D02*
Y296097D01*
G01X1556917Y306655D02*
X1562164Y301408D01*
G01X1556917Y311721D02*
Y306655D01*
G01X1559578Y314382D02*
X1556917Y311721D01*
G01X1559578Y322564D02*
Y314382D01*
G01X1555693Y326449D02*
X1559578Y322564D01*
G01X1555693Y329181D02*
Y326449D01*
G01X1553356Y331518D02*
X1555693Y329181D01*
G01X1553356Y335914D02*
Y331518D01*
G01X1548646Y340624D02*
X1553356Y335914D01*
G01X1547447Y340624D02*
X1548646D01*
G01X1538478Y349593D02*
X1547447Y340624D01*
G01X1581076Y284825D02*
X1581077D01*
G01X1578878Y287023D02*
X1581076Y284825D01*
G01X1578878Y288603D02*
Y287023D01*
G01X1577054Y290427D02*
X1578878Y288603D01*
G01X1577054Y294083D02*
Y290427D01*
G01X1577648Y294677D02*
X1577054Y294083D01*
G01X1577648Y301876D02*
Y294677D01*
G01X1572742Y306782D02*
X1577648Y301876D01*
G01X1572742Y308667D02*
Y306782D01*
G01X1568524Y312885D02*
X1572742Y308667D01*
G01X1581527Y285275D02*
X1581077Y284825D01*
G01X1586200Y285275D02*
X1581527D01*
G01X1596263Y275212D02*
X1586200Y285275D01*
G01X1563878Y332022D02*
X1554800Y341100D01*
G01X1563882Y332022D02*
X1563878D01*
G01X1564322Y331582D02*
X1563882Y332022D01*
G01X1564322Y322492D02*
Y331582D01*
G01X1574073Y312741D02*
X1564322Y322492D01*
G01X1574073Y306688D02*
Y312741D01*
G01X1578410Y302351D02*
X1574073Y306688D01*
G01X1578410Y296057D02*
Y302351D01*
G01X1580600Y293867D02*
X1578410Y296057D01*
G01X1580600Y293003D02*
Y293867D01*
G01X1598151Y275452D02*
X1580600Y293003D01*
G01X1586162Y341102D02*
X1569159Y358105D01*
G01X1586162Y332854D02*
Y341102D01*
G01X1595438Y323578D02*
X1586162Y332854D01*
G01X1563701Y287488D02*
Y281352D01*
G01X1562648Y288541D02*
X1563701Y287488D01*
G01X1562648Y292921D02*
Y288541D01*
G01X1560660Y294909D02*
X1562648Y292921D01*
G01X1560660Y300784D02*
Y294909D01*
G01X1555413Y306031D02*
X1560660Y300784D01*
G01X1555413Y316185D02*
Y306031D01*
G01X1556586Y317358D02*
X1555413Y316185D01*
G01X1556586Y323428D02*
Y317358D01*
G01X1554188Y325826D02*
X1556586Y323428D01*
G01X1554188Y328502D02*
Y325826D01*
G01X1551852Y330838D02*
X1554188Y328502D01*
G01X1551852Y334790D02*
Y330838D01*
G01X1548474Y338168D02*
X1551852Y334790D01*
G01X1547711Y338168D02*
X1548474D01*
G01X1536150Y349729D02*
X1547711Y338168D01*
G01X1529734Y318121D02*
Y319714D01*
G01X1532824Y294130D02*
Y298898D01*
G01X1537054Y289900D02*
X1532824Y294130D01*
G01X1537054Y284864D02*
Y289900D01*
G01X1537053Y284863D02*
X1537054Y284864D01*
G01X1537053Y284241D02*
Y284863D01*
G01X1537054Y284240D02*
X1537053Y284241D01*
G01X1537054Y283504D02*
Y284240D01*
G01X1538836Y281722D02*
X1537054Y283504D01*
G01X1557924Y300328D02*
Y282873D01*
G01X1553157Y305095D02*
X1557924Y300328D01*
G01X1553157Y317121D02*
Y305095D01*
G01X1554330Y318294D02*
X1553157Y317121D01*
G01X1554330Y322492D02*
Y318294D01*
G01X1551932Y324890D02*
X1554330Y322492D01*
G01X1551932Y327566D02*
Y324890D01*
G01X1549596Y329902D02*
X1551932Y327566D01*
G01X1549596Y333854D02*
Y329902D01*
G01X1547538Y335912D02*
X1549596Y333854D01*
G01X1546775Y335912D02*
X1547538D01*
G01X1533894Y348793D02*
X1546775Y335912D01*
G01X1531369Y328459D02*
Y331637D01*
G01X1529281Y326371D02*
X1531369Y328459D01*
G01X1529281Y323527D02*
Y326371D01*
G01X1532100Y320708D02*
X1529281Y323527D01*
G01X1532100Y312486D02*
Y320708D01*
G01X1531001Y311387D02*
X1532100Y312486D01*
G01X1531001Y303423D02*
Y311387D01*
G01X1539076Y295348D02*
X1531001Y303423D01*
G01X1539076Y291482D02*
Y295348D01*
G01X1538787Y291193D02*
X1539076Y291482D01*
G01X1538787Y283899D02*
Y291193D01*
G01X1540340Y282346D02*
X1538787Y283899D01*
G01X1582263Y319020D02*
X1581834Y318591D01*
G01X1588790Y319020D02*
X1582263D01*
G01X1590809Y317001D02*
X1588790Y319020D01*
G01X1549067Y281358D02*
Y280112D01*
G01X1549068Y281359D02*
X1549067Y281358D01*
G01X1549068Y283359D02*
Y281359D01*
G01X1550527Y284818D02*
X1549068Y283359D01*
G01X1550527Y287232D02*
Y284818D01*
G01X1546944Y290815D02*
X1550527Y287232D01*
G01X1546944Y299080D02*
Y290815D01*
G01X1545268Y300756D02*
X1546944Y299080D01*
G01X1545268Y305623D02*
Y300756D01*
G01X1540778Y310113D02*
X1545268Y305623D01*
G01X1540778Y312730D02*
Y310113D01*
G01X1542060Y314012D02*
X1540778Y312730D01*
G01X1542060Y319769D02*
Y314012D01*
G01X1539120Y322709D02*
X1542060Y319769D01*
G01X1539120Y325877D02*
Y322709D01*
G01X1539982Y326739D02*
X1539120Y325877D01*
G01X1539982Y330810D02*
Y326739D01*
G01X1538384Y332408D02*
X1539982Y330810D01*
G01X1538384Y337869D02*
Y332408D01*
G01X1529360Y346893D02*
X1538384Y337869D01*
G01X1540291Y284523D02*
X1541844Y282970D01*
G01X1540291Y290569D02*
Y284523D01*
G01X1540928Y291206D02*
X1540291Y290569D01*
G01X1540928Y296006D02*
Y291206D01*
G01X1536027Y300907D02*
X1540928Y296006D01*
G01X1536027Y305048D02*
Y300907D01*
G01X1586914Y340800D02*
X1596190Y331524D01*
G01X1586914Y341918D02*
Y340800D01*
G01X1587450Y313687D02*
X1590164Y310973D01*
G01X1587450Y316868D02*
Y313687D01*
G01X1586132Y318186D02*
X1587450Y316868D01*
G01X1584826Y318186D02*
X1586132D01*
G01X1583655Y317015D02*
X1584826Y318186D01*
G01X1581181Y317015D02*
X1583655D01*
G01X1580258Y317938D02*
X1581181Y317015D01*
G01X1580258Y319244D02*
Y317938D01*
G01X1580296Y319282D02*
X1580258Y319244D01*
G01X1580296Y326694D02*
Y319282D01*
G01X1576320Y330670D02*
X1580296Y326694D01*
G01X1576320Y340387D02*
Y330670D01*
G01X1558177Y358530D02*
X1576320Y340387D01*
G01X1564411Y313685D02*
Y315210D01*
G01X1566078Y312018D02*
X1564411Y313685D01*
G01X1566078Y308336D02*
Y312018D01*
G01X1569855Y304559D02*
X1566078Y308336D01*
G01X1569855Y302480D02*
Y304559D01*
G01X1572750Y299585D02*
X1569855Y302480D01*
G01X1572750Y290287D02*
Y299585D01*
G01X1568965Y286502D02*
X1572750Y290287D01*
G01X1568965Y283536D02*
Y286502D01*
G01X1571526Y280975D02*
X1568965Y283536D01*
G01X1527147Y285337D02*
X1532776Y279708D01*
G01X1527147Y289558D02*
Y285337D01*
G01X1575567Y340076D02*
X1558013Y357630D01*
G01X1575567Y330173D02*
Y340076D01*
G01X1579544Y326196D02*
X1575567Y330173D01*
G01X1579544Y319594D02*
Y326196D01*
G01X1579506Y319556D02*
X1579544Y319594D01*
G01X1579506Y317626D02*
Y319556D01*
G01X1581494Y315638D02*
X1579506Y317626D01*
G01X1583691Y315638D02*
X1581494D01*
G01X1589412Y309917D02*
X1583691Y315638D01*
G01X1527959Y340576D02*
Y342134D01*
G01X1534574Y333961D02*
X1527959Y340576D01*
G01X1534574Y327153D02*
Y333961D01*
G01X1535560Y326167D02*
X1534574Y327153D01*
G01X1535560Y322823D02*
Y326167D01*
G01X1535322Y322585D02*
X1535560Y322823D01*
G01X1535322Y312779D02*
Y322585D01*
G01X1537640Y310461D02*
X1535322Y312779D01*
G01X1537640Y308933D02*
Y310461D01*
G01X1541434Y305139D02*
X1537640Y308933D01*
G01X1541434Y299837D02*
Y305139D01*
G01X1543936Y297335D02*
X1541434Y299837D01*
G01X1543936Y289958D02*
Y297335D01*
G01X1543299Y289321D02*
X1543936Y289958D01*
G01X1543299Y285771D02*
Y289321D01*
G01X1544852Y284218D02*
X1543299Y285771D01*
G01X1544852Y279885D02*
Y284218D01*
G01X1528476Y292213D02*
Y297105D01*
G01X1527899Y291636D02*
X1528476Y292213D01*
G01X1527899Y285649D02*
Y291636D01*
G01X1533528Y280020D02*
X1527899Y285649D01*
G01X1557172Y300016D02*
Y282561D01*
G01X1552280Y304908D02*
X1557172Y300016D01*
G01X1552280Y306224D02*
Y304908D01*
G01X1549828Y308676D02*
X1552280Y306224D01*
G01X1549828Y310115D02*
Y308676D01*
G01X1552150Y312437D02*
X1549828Y310115D01*
G01X1552150Y317178D02*
Y312437D01*
G01X1553578Y318606D02*
X1552150Y317178D01*
G01X1553578Y321915D02*
Y318606D01*
G01X1551180Y324313D02*
X1553578Y321915D01*
G01X1551180Y325949D02*
Y324313D01*
G01X1546424Y330705D02*
X1551180Y325949D01*
G01X1546424Y332849D02*
Y330705D01*
G01X1547398Y333823D02*
X1546424Y332849D01*
G01X1541795Y285147D02*
X1543348Y283594D01*
G01X1541795Y289945D02*
Y285147D01*
G01X1542432Y290582D02*
X1541795Y289945D01*
G01X1542432Y296630D02*
Y290582D01*
G01X1539899Y299163D02*
X1542432Y296630D01*
G01X1539899Y299785D02*
Y299163D01*
G01X1539900Y299786D02*
X1539899Y299785D01*
G01X1539900Y304527D02*
Y299786D01*
G01X1537622Y306805D02*
X1539900Y304527D01*
G01X1534533Y306805D02*
X1537622D01*
G01X1532505Y308833D02*
X1534533Y306805D01*
G01X1532505Y310763D02*
Y308833D01*
G01X1533604Y311862D02*
X1532505Y310763D01*
G01X1533604Y321332D02*
Y311862D01*
G01X1530785Y324151D02*
X1533604Y321332D01*
G01X1530785Y325747D02*
Y324151D01*
G01X1532910Y327872D02*
X1530785Y325747D01*
G01X1532910Y333414D02*
Y327872D01*
G01X1527779Y338545D02*
X1532910Y333414D01*
G01X1529865Y329083D02*
Y331013D01*
G01X1532072Y293765D02*
Y298586D01*
G01X1536302Y289535D02*
X1532072Y293765D01*
G01X1536302Y285176D02*
Y289535D01*
G01X1536301Y285175D02*
X1536302Y285176D01*
G01X1536301Y284553D02*
Y285175D01*
G01X1536300Y284552D02*
X1536301Y284553D01*
G01X1536300Y283930D02*
Y284552D01*
G01X1536302Y283928D02*
X1536300Y283930D01*
G01X1536302Y283192D02*
Y283928D01*
G01X1538084Y281410D02*
X1536302Y283192D01*
G01X1537806Y283816D02*
X1539588Y282034D01*
G01X1537806Y290265D02*
Y283816D01*
G01X1535924Y292147D02*
X1537806Y290265D01*
G01X1535924Y294053D02*
Y292147D01*
G01X1536300Y294429D02*
X1535924Y294053D01*
G01X1536300Y296971D02*
Y294429D01*
G01X1530249Y303022D02*
X1536300Y296971D01*
G01X1530249Y311699D02*
Y303022D01*
G01X1531348Y312798D02*
X1530249Y311699D01*
G01X1531348Y320396D02*
Y312798D01*
G01X1528529Y323215D02*
X1531348Y320396D01*
G01X1528529Y326683D02*
Y323215D01*
G01X1530617Y328771D02*
X1528529Y326683D01*
G01X1530617Y331325D02*
Y328771D01*
G01X1532121Y328147D02*
Y331949D01*
G01X1530033Y326059D02*
X1532121Y328147D01*
G01X1530033Y323839D02*
Y326059D01*
G01X1532852Y321020D02*
X1530033Y323839D01*
G01X1532852Y312174D02*
Y321020D01*
G01X1531753Y311075D02*
X1532852Y312174D01*
G01X1531753Y308521D02*
Y311075D01*
G01X1534451Y305823D02*
X1531753Y308521D01*
G01X1534451Y301419D02*
Y305823D01*
G01X1540176Y295694D02*
X1534451Y301419D01*
G01X1540176Y291518D02*
Y295694D01*
G01X1539539Y290881D02*
X1540176Y291518D01*
G01X1539539Y284211D02*
Y290881D01*
G01X1541092Y282658D02*
X1539539Y284211D01*
G01X1582800Y308000D02*
Y312100D01*
G01X1585828Y304972D02*
X1582800Y308000D01*
G01X1585828Y293095D02*
Y304972D01*
G01X1602674Y276249D02*
X1585828Y293095D01*
G01X1588330Y292721D02*
X1604178Y276873D01*
G01X1588330Y305189D02*
Y292721D01*
G01X1585250Y308269D02*
X1588330Y305189D01*
G01X1585250Y312946D02*
Y308269D01*
G01X1583310Y314886D02*
X1585250Y312946D01*
G01X1581182Y314886D02*
X1583310D01*
G01X1578754Y317314D02*
X1581182Y314886D01*
G01X1578754Y319868D02*
Y317314D01*
G01X1578792Y319906D02*
X1578754Y319868D01*
G01X1578792Y325884D02*
Y319906D01*
G01X1574152Y330524D02*
X1578792Y325884D01*
G01X1574152Y335196D02*
Y330524D01*
G01X1572374Y336974D02*
X1574152Y335196D01*
G01X1572374Y342205D02*
Y336974D01*
G01X1557550Y339697D02*
Y341100D01*
G01X1564505Y332742D02*
X1557550Y339697D01*
G01X1565074Y332172D02*
X1564505Y332742D01*
G01X1565074Y323087D02*
Y332172D01*
G01X1575120Y313041D02*
X1565074Y323087D01*
G01X1575120Y307069D02*
Y313041D01*
G01X1579362Y302827D02*
X1575120Y307069D01*
G01X1579362Y296169D02*
Y302827D01*
G01X1581500Y294031D02*
X1579362Y296169D01*
G01X1581500Y293167D02*
Y294031D01*
G01X1598999Y275668D02*
X1581500Y293167D01*
G01X1559500Y288144D02*
Y290300D01*
G01X1561376Y286268D02*
X1559500Y288144D01*
G01X1561376Y280485D02*
Y286268D01*
G01X1569000Y340229D02*
X1564129Y345100D01*
G01X1569000Y338500D02*
Y340229D01*
G01X1573000Y334500D02*
X1569000Y338500D01*
G01X1573000Y329300D02*
Y334500D01*
G01X1578002Y324298D02*
X1573000Y329300D01*
G01X1578002Y317002D02*
Y324298D01*
G01X1580870Y314134D02*
X1578002Y317002D01*
G01X1582995Y314134D02*
X1580870D01*
G01X1584376Y312753D02*
X1582995Y314134D01*
G01X1584376Y308024D02*
Y312753D01*
G01X1587550Y304850D02*
X1584376Y308024D01*
G01X1587550Y292437D02*
Y304850D01*
G01X1603426Y276561D02*
X1587550Y292437D01*
G01X1536830Y338359D02*
X1529048Y346141D01*
G01X1536830Y328089D02*
Y338359D01*
G01X1538343Y326576D02*
X1536830Y328089D01*
G01X1538343Y322872D02*
Y326576D01*
G01X1538344Y322871D02*
X1538343Y322872D01*
G01X1538344Y321625D02*
Y322871D01*
G01X1537759Y321040D02*
X1538344Y321625D01*
G01X1537759Y318746D02*
Y321040D01*
G01X1541308Y315197D02*
X1537759Y318746D01*
G01X1541308Y314324D02*
Y315197D01*
G01X1540026Y313042D02*
X1541308Y314324D01*
G01X1540026Y309801D02*
Y313042D01*
G01X1544516Y305311D02*
X1540026Y309801D01*
G01X1544516Y300444D02*
Y305311D01*
G01X1546192Y298768D02*
X1544516Y300444D01*
G01X1546192Y290503D02*
Y298768D01*
G01X1549775Y286920D02*
X1546192Y290503D01*
G01X1549775Y285130D02*
Y286920D01*
G01X1548316Y283671D02*
X1549775Y285130D01*
G01X1548316Y283015D02*
Y283671D01*
G01X1548200Y282899D02*
X1548316Y283015D01*
G01X1548200Y279915D02*
Y282899D01*
G01X1528855Y387274D02*
X1528475Y387654D01*
G01X1528855Y383373D02*
Y387274D01*
G01X1530045Y382183D02*
X1528855Y383373D01*
G01X1530045Y379355D02*
Y382183D01*
G01X1528855Y378165D02*
X1530045Y379355D01*
G01X1528855Y376266D02*
Y378165D01*
G01X1540900Y364221D02*
X1528855Y376266D01*
G01X1540900Y349500D02*
Y364221D01*
G01X1542712Y347688D02*
X1540900Y349500D01*
G01X1546012Y347688D02*
X1542712D01*
G01X1551720Y341980D02*
X1546012Y347688D01*
G01X1553600Y343700D02*
X1557179D01*
G01X1547900Y349400D02*
X1553600Y343700D01*
G01X1547900Y352100D02*
Y349400D01*
G01X1549881Y354081D02*
X1547900Y352100D01*
G01X1549881Y357326D02*
Y354081D01*
G01X1546448Y360759D02*
X1549881Y357326D01*
G01X1546448Y365578D02*
Y360759D01*
G01X1540180Y371846D02*
X1546448Y365578D01*
G01X1537772Y371846D02*
X1540180D01*
G01X1532755Y376863D02*
X1537772Y371846D01*
G01X1532755Y379053D02*
Y376863D01*
G01X1533945Y380243D02*
X1532755Y379053D01*
G01X1533945Y381545D02*
Y380243D01*
G01X1532755Y382735D02*
X1533945Y381545D01*
G01X1532755Y385813D02*
Y382735D01*
G01X1534325Y387383D02*
X1532755Y385813D01*
G01X1534325Y391034D02*
Y387383D01*
G01X1528104Y380523D02*
X1528475Y380894D01*
G01X1528104Y357784D02*
Y380523D01*
G01X1532390Y353498D02*
X1528104Y357784D01*
G01X1532390Y348125D02*
Y353498D01*
G01X1530188Y351365D02*
Y348199D01*
G01X1579088Y354804D02*
X1596227Y337665D01*
G01X1579088Y362871D02*
Y354804D01*
G01X1570991Y370968D02*
X1579088Y362871D01*
G01X1564119Y370968D02*
X1570991D01*
G01X1559304Y375783D02*
X1564119Y370968D01*
G01X1559304Y378477D02*
Y375783D01*
G01X1559321Y378494D02*
X1559304Y378477D01*
G01X1557971Y379844D02*
X1559321Y378494D01*
G01X1557971Y381568D02*
Y379844D01*
G01X1559304Y382901D02*
X1557971Y381568D01*
G01X1559304Y385634D02*
Y382901D01*
G01X1558096Y386842D02*
X1559304Y385634D01*
G01X1558096Y390663D02*
Y386842D01*
G01X1557725Y391034D02*
X1558096Y390663D01*
G01X1543668Y360900D02*
X1543300D01*
G01X1547800Y356768D02*
X1543668Y360900D01*
G01X1547800Y354700D02*
Y356768D01*
G01X1545900Y352800D02*
X1547800Y354700D01*
G01X1545900Y348900D02*
Y352800D01*
G01X1552472Y342328D02*
X1545900Y348900D01*
G01X1531638Y352591D02*
Y347813D01*
G01X1527074Y361406D02*
Y357155D01*
G01X1528095Y385103D02*
Y383623D01*
G01Y391879D02*
Y389641D01*
G01X1546700Y349200D02*
X1553224Y342676D01*
G01X1546700Y352300D02*
Y349200D01*
G01X1549106Y354706D02*
X1546700Y352300D01*
G01X1549106Y357037D02*
Y354706D01*
G01X1545696Y360447D02*
X1549106Y357037D01*
G01X1545696Y365073D02*
Y360447D01*
G01X1540554Y370215D02*
X1545696Y365073D01*
G01X1538340Y370215D02*
X1540554D01*
G01X1531995Y376560D02*
X1538340Y370215D01*
G01X1531995Y378165D02*
Y376560D01*
G01X1530805Y379355D02*
X1531995Y378165D01*
G01X1530805Y381705D02*
Y379355D01*
G01X1531995Y382895D02*
X1530805Y381705D01*
G01X1531995Y384925D02*
Y382895D01*
G01X1530805Y386115D02*
X1531995Y384925D01*
G01X1530805Y389193D02*
Y386115D01*
G01X1531995Y390383D02*
X1530805Y389193D01*
G01X1531995Y390925D02*
Y390383D01*
G01X1535484Y394414D02*
X1531995Y390925D01*
G01X1536275Y394414D02*
X1535484D01*
G01X1533142Y355755D02*
Y348437D01*
G01X1532367Y356530D02*
X1533142Y355755D01*
G01X1548964Y393425D02*
X1547975Y394414D01*
G01X1550225Y393425D02*
X1548964D01*
G01X1550820Y392830D02*
X1550225Y393425D01*
G01X1554580Y392830D02*
X1550820D01*
G01X1556155Y391255D02*
X1554580Y392830D01*
G01X1556155Y390383D02*
Y391255D01*
G01X1557345Y389193D02*
X1556155Y390383D01*
G01X1557345Y386115D02*
Y389193D01*
G01X1556155Y384925D02*
X1557345Y386115D01*
G01X1556155Y383495D02*
Y384925D01*
G01X1554205Y381545D02*
X1556155Y383495D01*
G01X1554205Y380243D02*
Y381545D01*
G01X1555404Y379044D02*
X1554205Y380243D01*
G01X1555404Y376551D02*
Y379044D01*
G01X1564355Y367600D02*
X1555404Y376551D01*
G01X1567559Y367600D02*
X1564355D01*
G01X1573930Y361229D02*
X1567559Y367600D01*
G01X1573930Y356031D02*
Y361229D01*
G01X1588551Y341410D02*
X1573930Y356031D01*
G01X1596942Y333019D02*
X1588551Y341410D01*
G01X1553010Y350113D02*
X1561424Y341699D01*
G01X1550726Y350113D02*
X1553010D01*
G01X1550639Y350200D02*
X1550726Y350113D01*
G01X1547975Y383475D02*
Y387654D01*
G01X1546405Y381905D02*
X1547975Y383475D01*
G01X1546405Y380095D02*
Y381905D01*
G01X1547604Y378896D02*
X1546405Y380095D01*
G01X1547604Y377614D02*
Y378896D01*
G01X1553041Y372177D02*
X1547604Y377614D01*
G01X1554857Y372177D02*
X1553041D01*
G01X1561250Y365784D02*
X1554857Y372177D01*
G01X1561250Y362060D02*
Y365784D01*
G01X1580441Y342869D02*
X1561250Y362060D01*
G01X1583331Y342869D02*
X1580441D01*
G01X1550461Y402780D02*
X1541963D01*
G01X1551520Y403839D02*
X1550461Y402780D01*
G01X1534695Y359378D02*
X1533790Y360283D01*
G01X1534695Y355303D02*
Y359378D01*
G01X1534646Y355254D02*
X1534695Y355303D01*
G01X1534646Y349105D02*
Y355254D01*
G01X1536902Y354318D02*
Y350041D01*
G01X1538478Y355894D02*
X1536902Y354318D01*
G01X1545664Y346936D02*
X1550932Y341668D01*
G01X1542364Y346936D02*
X1545664D01*
G01X1540100Y349200D02*
X1542364Y346936D01*
G01X1540100Y351672D02*
Y349200D01*
G01X1538478Y353294D02*
X1540100Y351672D01*
G01X1536085Y359549D02*
X1538397Y361861D01*
G01X1536085Y355629D02*
Y359549D01*
G01X1535398Y354942D02*
X1536085Y355629D01*
G01X1535398Y349417D02*
Y354942D01*
G01X1538478Y350694D02*
Y349593D01*
G01X1585387Y367317D02*
X1597857Y354847D01*
G01X1585387Y368934D02*
Y367317D01*
G01X1581621Y372700D02*
X1585387Y368934D01*
G01X1578894Y372700D02*
X1581621D01*
G01X1567500Y384094D02*
X1578894Y372700D01*
G01X1567500Y384520D02*
Y384094D01*
G01X1566176Y385844D02*
X1567500Y384520D01*
G01X1563164Y385844D02*
X1566176D01*
G01X1561642Y387366D02*
X1563164Y385844D01*
G01X1561642Y388704D02*
Y387366D01*
G01X1559295Y391051D02*
X1561642Y388704D01*
G01X1559295Y392573D02*
Y391051D01*
G01X1558105Y393763D02*
X1559295Y392573D01*
G01X1558105Y395065D02*
Y393763D01*
G01X1559538Y396498D02*
X1558105Y395065D01*
G01X1559538Y397928D02*
Y396498D01*
G01X1562784Y401174D02*
X1559538Y397928D01*
G01X1563575Y401174D02*
X1562784D01*
G01X1551875Y383243D02*
Y387654D01*
G01X1550305Y381673D02*
X1551875Y383243D01*
G01X1550305Y379842D02*
Y381673D01*
G01X1551504Y378643D02*
X1550305Y379842D01*
G01X1551504Y376551D02*
Y378643D01*
G01X1552863Y375192D02*
X1551504Y376551D01*
G01X1552905Y375192D02*
X1552863D01*
G01X1563650Y364447D02*
X1552905Y375192D01*
G01X1563650Y360724D02*
Y364447D01*
G01X1566269Y358105D02*
X1563650Y360724D01*
G01X1569159Y358105D02*
X1566269D01*
G01X1536150Y354630D02*
Y349729D01*
G01X1536902Y355382D02*
X1536150Y354630D01*
G01X1536902Y357765D02*
Y355382D01*
G01X1538500Y359363D02*
X1536902Y357765D01*
G01X1533894Y355566D02*
Y348793D01*
G01X1533943Y355615D02*
X1533894Y355566D01*
G01X1533943Y357901D02*
Y355615D01*
G01X1532214Y359630D02*
X1533943Y357901D01*
G01X1532214Y361278D02*
Y359630D01*
G01X1533719Y362783D02*
X1532214Y361278D01*
G01X1567185Y361647D02*
X1586914Y341918D01*
G01X1566470Y361647D02*
X1567185D01*
G01X1565100Y363017D02*
X1566470Y361647D01*
G01X1565100Y364060D02*
Y363017D01*
G01X1553216Y375944D02*
X1565100Y364060D01*
G01X1553174Y375944D02*
X1553216D01*
G01X1552255Y376863D02*
X1553174Y375944D01*
G01X1552255Y378165D02*
Y376863D01*
G01X1553445Y379355D02*
X1552255Y378165D01*
G01X1553445Y388305D02*
Y379355D01*
G01X1552350Y389400D02*
X1553445Y388305D01*
G01X1549338Y389400D02*
X1552350D01*
G01X1548150Y390588D02*
X1549338Y389400D01*
G01X1548150Y392018D02*
Y390588D01*
G01X1546405Y393763D02*
X1548150Y392018D01*
G01X1546405Y395065D02*
Y393763D01*
G01X1547390Y396050D02*
X1546405Y395065D01*
G01X1552081Y396050D02*
X1547390D01*
G01X1553825Y397794D02*
X1552081Y396050D01*
G01X1569425Y394143D02*
Y397794D01*
G01X1570724Y392844D02*
X1569425Y394143D01*
G01X1575186Y392844D02*
X1570724D01*
G01X1584347Y383683D02*
X1575186Y392844D01*
G01X1584347Y383682D02*
Y383683D01*
G01X1587291Y380738D02*
X1584347Y383682D01*
G01X1587291Y366539D02*
Y380738D01*
G01X1601285Y352545D02*
X1587291Y366539D01*
G01X1557380Y358530D02*
X1558177D01*
G01X1555243Y360667D02*
X1557380Y358530D01*
G01X1555243Y366153D02*
Y360667D01*
G01X1544679Y376717D02*
X1555243Y366153D01*
G01X1542300Y376717D02*
X1544679D01*
G01X1545645Y397414D02*
X1546025Y397794D01*
G01X1545645Y393150D02*
Y397414D01*
G01X1544455Y391960D02*
X1545645Y393150D01*
G01X1544455Y389545D02*
Y391960D01*
G01X1545645Y388355D02*
X1544455Y389545D01*
G01X1545645Y385545D02*
Y388355D01*
G01X1542505Y382405D02*
X1545645Y385545D01*
G01X1542505Y379905D02*
Y382405D01*
G01X1540730Y378130D02*
X1542505Y379905D01*
G01X1540730Y374804D02*
Y378130D01*
G01X1546754Y368780D02*
X1540730Y374804D01*
G01X1551552Y368780D02*
X1546754D01*
G01X1554193Y366139D02*
X1551552Y368780D01*
G01X1554193Y360367D02*
Y366139D01*
G01X1556930Y357630D02*
X1554193Y360367D01*
G01X1558013Y357630D02*
X1556930D01*
G01X1565525Y379840D02*
Y384274D01*
G01X1569367Y375998D02*
X1565525Y379840D01*
G01X1572858Y375998D02*
X1569367D01*
G01X1581082Y367774D02*
X1572858Y375998D01*
G01X1582349Y367774D02*
X1581082D01*
G01X1583503Y366620D02*
X1582349Y367774D01*
G01X1583503Y358123D02*
Y366620D01*
G01X1584991Y356635D02*
X1583503Y358123D01*
G01X1590537Y356635D02*
X1584991D01*
G01X1580303Y355496D02*
X1599482Y336317D01*
G01X1580303Y362719D02*
Y355496D01*
G01X1570071Y372951D02*
X1580303Y362719D01*
G01X1563967Y372951D02*
X1570071D01*
G01X1560055Y376863D02*
X1563967Y372951D01*
G01X1560055Y378165D02*
Y376863D01*
G01X1561245Y379355D02*
X1560055Y378165D01*
G01X1561245Y382433D02*
Y379355D01*
G01X1560055Y383623D02*
X1561245Y382433D01*
G01X1560055Y387274D02*
Y383623D01*
G01X1559675Y387654D02*
X1560055Y387274D01*
G01X1558859Y355720D02*
X1572374Y342205D01*
G01X1555280Y355720D02*
X1558859D01*
G01X1552500Y358500D02*
X1555280Y355720D01*
G01X1553445Y400523D02*
Y408756D01*
G01X1552482Y399560D02*
X1553445Y400523D01*
G01X1545570Y399560D02*
X1552482D01*
G01X1544040Y398030D02*
X1545570Y399560D01*
G01X1544040Y397070D02*
Y398030D01*
G01X1541745Y394775D02*
X1544040Y397070D01*
G01X1541745Y392045D02*
Y394775D01*
G01X1537845Y388145D02*
X1541745Y392045D01*
G01X1537845Y387003D02*
Y388145D01*
G01X1536655Y385813D02*
X1537845Y387003D01*
G01X1536655Y383623D02*
Y385813D01*
G01X1537845Y382433D02*
X1536655Y383623D01*
G01X1537845Y380243D02*
Y382433D01*
G01X1536655Y379053D02*
X1537845Y380243D01*
G01X1536655Y376745D02*
Y379053D01*
G01X1547200Y366200D02*
X1536655Y376745D01*
G01X1547200Y361071D02*
Y366200D01*
G01X1563171Y345100D02*
X1547200Y361071D01*
G01X1564129Y345100D02*
X1563171D01*
G01X1560719Y394414D02*
X1559675D01*
G01X1563302Y396997D02*
X1560719Y394414D01*
G01X1563302Y398529D02*
Y396997D01*
G01X1564582Y399809D02*
X1563302Y398529D01*
G01X1566619Y399809D02*
X1564582D01*
G01X1567064Y399364D02*
X1566619Y399809D01*
G01X1570076Y399364D02*
X1567064D01*
G01X1570995Y398445D02*
X1570076Y399364D01*
G01X1570995Y397015D02*
Y398445D01*
G01X1574259Y393751D02*
X1570995Y397015D01*
G01X1575342Y393751D02*
X1574259D01*
G01X1585098Y383995D02*
X1575342Y393751D01*
G01X1585098Y383994D02*
Y383995D01*
G01X1585410Y383682D02*
X1585098Y383994D01*
G01X1585411Y383682D02*
X1585410D01*
G01X1588043Y381050D02*
X1585411Y383682D01*
G01X1588043Y366851D02*
Y381050D01*
G01X1602127Y352767D02*
X1588043Y366851D01*
G01X1588790Y452151D02*
X1588632D01*
G01X1590349Y453710D02*
X1588790Y452151D01*
G01X1574510Y461981D02*
X1580396Y467867D01*
G01X1557345Y457755D02*
X1556155Y458945D01*
G01X1557345Y456095D02*
Y457755D01*
G01X1556100Y454850D02*
X1557345Y456095D01*
G01X1556100Y446100D02*
Y454850D01*
G01X1557345Y444855D02*
X1556100Y446100D01*
G01X1557345Y442895D02*
Y444855D01*
G01X1556000Y441550D02*
X1557345Y442895D01*
G01X1556000Y439300D02*
Y441550D01*
G01X1553950Y437250D02*
X1556000Y439300D01*
G01X1553950Y434160D02*
Y437250D01*
G01X1552060Y432270D02*
X1553950Y434160D01*
G01X1552060Y431190D02*
Y432270D01*
G01X1550280Y429410D02*
X1552060Y431190D01*
G01X1550280Y427150D02*
Y429410D01*
G01X1551578Y425852D02*
X1550280Y427150D01*
G01X1551578Y424030D02*
Y425852D01*
G01X1549325Y421777D02*
X1551578Y424030D01*
G01X1549325Y420487D02*
Y421777D01*
G01X1548720Y419882D02*
X1549325Y420487D01*
G01X1548720Y414450D02*
Y419882D01*
G01X1546290Y412020D02*
X1548720Y414450D01*
G01X1540049Y412020D02*
X1546290D01*
G01X1539839Y411810D02*
X1540049Y412020D01*
G01X1531330Y411810D02*
X1539839D01*
G01X1573064Y455051D02*
X1570212D01*
G01X1573900Y455887D02*
X1573064Y455051D01*
G01X1573900Y460287D02*
Y455887D01*
G01X1580257Y466644D02*
X1573900Y460287D01*
G01X1586019Y438144D02*
X1596120D01*
G01X1580972Y443191D02*
X1586019Y438144D01*
G01X1579537Y443191D02*
X1580972D01*
G01X1551520Y405141D02*
Y403839D01*
G01X1547787Y408874D02*
X1551520Y405141D01*
G01X1547787Y412146D02*
Y408874D01*
G01X1549512Y413871D02*
X1547787Y412146D01*
G01X1549512Y417168D02*
Y413871D01*
G01X1550191Y417847D02*
X1549512Y417168D01*
G01X1550191Y421580D02*
Y417847D01*
G01X1552330Y423719D02*
X1550191Y421580D01*
G01X1552330Y424298D02*
Y423719D01*
G01X1553278Y425246D02*
X1552330Y424298D01*
G01X1553278Y425298D02*
Y425246D01*
G01X1554205Y426225D02*
X1553278Y425298D01*
G01X1554205Y429085D02*
Y426225D01*
G01X1556030Y430910D02*
X1554205Y429085D01*
G01X1556030Y432720D02*
Y430910D01*
G01X1557344Y434034D02*
X1556030Y432720D01*
G01X1557344Y435470D02*
Y434034D01*
G01X1574730Y460030D02*
X1579900Y465200D01*
G01X1574730Y455080D02*
Y460030D01*
G01X1571766Y452116D02*
X1574730Y455080D01*
G01X1564606Y452116D02*
X1571766D01*
G01X1564453Y452269D02*
X1564606Y452116D01*
G01X1561233Y452269D02*
X1564453D01*
G01X1559595Y450631D02*
X1561233Y452269D01*
G01X1571600Y460209D02*
X1580010Y468619D01*
G01X1571600Y459785D02*
Y460209D01*
G01X1576969Y443546D02*
X1571375D01*
G01X1581545Y438970D02*
X1576969Y443546D01*
G01X1583563Y438970D02*
X1581545D01*
G01X1585541Y436992D02*
X1583563Y438970D01*
G01X1596598Y436992D02*
X1585541D01*
G01X1567475Y436294D02*
Y436786D01*
G01X1568966Y434803D02*
X1567475Y436294D01*
G01X1581116Y434803D02*
X1568966D01*
G01X1581556Y434363D02*
X1581116Y434803D01*
G01X1586211Y434363D02*
X1581556D01*
G01X1586855Y435007D02*
X1586211Y434363D01*
G01X1595055Y435007D02*
X1586855D01*
G01X1580558Y448328D02*
X1584070D01*
G01X1578630Y446400D02*
X1580558Y448328D01*
G01X1571160Y446400D02*
X1578630D01*
G01X1570670Y445910D02*
X1571160Y446400D01*
G01X1569197Y445300D02*
G03X1570670Y445910I0J2083D01*
G01X1563251Y445300D02*
X1569197D01*
G01X1561625Y446926D02*
X1563251Y445300D01*
G01X1585902Y454879D02*
X1583208Y452185D01*
G01X1588258Y454879D02*
X1585902D01*
G01X1591279Y457900D02*
X1588258Y454879D01*
G01X1588736Y453727D02*
X1592085Y457076D01*
G01X1587279Y453727D02*
X1588736D01*
G01X1585920Y452368D02*
X1587279Y453727D01*
G01X1549900Y404490D02*
X1549950D01*
G01X1548090Y406300D02*
X1549900Y404490D01*
G01X1539843Y406300D02*
X1548090D01*
G01X1583961Y430939D02*
X1592139D01*
G01X1581736Y433164D02*
X1583961Y430939D01*
G01X1560974Y433164D02*
X1581736D01*
G01X1557790Y429980D02*
X1560974Y433164D01*
G01X1557790Y427990D02*
Y429980D01*
G01X1554029Y424229D02*
X1557790Y427990D01*
G01X1554029Y420538D02*
Y424229D01*
G01X1550305Y416814D02*
X1554029Y420538D01*
G01X1550305Y413565D02*
Y416814D01*
G01X1551752Y412118D02*
X1550305Y413565D01*
G01X1551752Y410449D02*
Y412118D01*
G01X1553445Y408756D02*
X1551752Y410449D01*
G01X1580396Y467867D02*
X1607883D01*
G01X1597801Y466644D02*
X1580257D01*
G01X1579900Y465200D02*
X1597800D01*
G01X1580010Y468619D02*
X1608817D01*
G01X1552266Y589350D02*
X1554358Y587258D01*
G01X1549180Y588398D02*
X1550990Y586588D01*
G01X1539616Y587519D02*
X1540495Y588398D01*
G01X1542600Y585724D02*
X1542274Y585398D01*
G01X1543424Y587500D02*
X1545200Y585724D01*
G01X1541000Y587500D02*
X1543424D01*
G01X1539850Y586350D02*
X1541000Y587500D01*
G01X1540100Y589350D02*
X1552266D01*
G01X1539221Y588471D02*
X1540100Y589350D01*
G01X1540495Y588398D02*
X1549180D01*
G01X1546179Y623779D02*
X1545556Y624402D01*
G01X1546925Y623779D02*
X1546179D01*
G01X1551640Y619064D02*
X1546925Y623779D01*
G01X1570336Y619064D02*
X1551640D01*
G01X1575144Y614256D02*
X1570336Y619064D01*
G01X1582500Y614256D02*
X1575144D01*
G01X1585322Y617078D02*
X1582500Y614256D01*
G01X1594828Y617078D02*
X1585322D01*
G01X1586700Y620100D02*
X1591002Y624402D01*
G01X1587581Y612552D02*
X1588933Y613904D01*
G01X1572448Y612552D02*
X1587581D01*
G01X1568800Y616200D02*
X1572448Y612552D01*
G01X1551630Y616200D02*
X1568800D01*
G01X1544932Y622898D02*
X1551630Y616200D01*
G01X1585717Y616126D02*
X1595223D01*
G01X1582895Y613304D02*
X1585717Y616126D01*
G01X1574749Y613304D02*
X1582895D01*
G01X1569941Y618112D02*
X1574749Y613304D01*
G01X1551130Y618112D02*
X1569941D01*
G01X1546317Y622925D02*
X1551130Y618112D01*
G01X1545969Y622925D02*
X1546317D01*
G01X1545244Y623650D02*
X1545969Y622925D01*
G01X1603358Y-15700D02*
X1588776D01*
G01X1605004Y-17346D02*
X1603358Y-15700D01*
G01X1597504Y-18496D02*
X1596658Y-19342D01*
G01X1597504Y-17346D02*
Y-18496D01*
G01X1606358Y-13700D02*
X1589600D01*
G01X1610004Y-17346D02*
X1606358Y-13700D01*
G01X1605058Y-14900D02*
X1589100D01*
G01X1607504Y-17346D02*
X1605058Y-14900D01*
G01X1619619Y77552D02*
X1608117Y89054D01*
G01X1627126Y77552D02*
X1619619D01*
G01X1629266Y75412D02*
X1627126Y77552D01*
G01X1637586Y75412D02*
X1629266D01*
G01X1640970Y72028D02*
X1637586Y75412D01*
G01X1661563Y72028D02*
X1640970D01*
G01X1591600Y75700D02*
X1590100Y74200D01*
G01X1594937Y82537D02*
X1589098D01*
G01X1596900Y84500D02*
X1594937Y82537D01*
G01X1641502Y83002D02*
X1655541D01*
G01X1639441Y80941D02*
X1641502Y83002D01*
G01X1631594Y80941D02*
X1639441D01*
G01X1630273Y82262D02*
X1631594Y80941D01*
G01X1630273Y84885D02*
Y82262D01*
G01X1628706Y86452D02*
X1630273Y84885D01*
G01X1628706Y86453D02*
Y86452D01*
G01X1622182Y92977D02*
X1628706Y86453D01*
G01X1622181Y92977D02*
X1622182D01*
G01X1621433Y93725D02*
X1622181Y92977D01*
G01X1621433Y94989D02*
Y93725D01*
G01X1631422Y84800D02*
X1654807D01*
G01X1629459Y86763D02*
X1631422Y84800D01*
G01X1629459Y86764D02*
Y86763D01*
G01X1623246Y92977D02*
X1629459Y86764D01*
G01X1623245Y92977D02*
X1623246D01*
G01X1622494Y93728D02*
X1623245Y92977D01*
G01X1622493Y93728D02*
X1622494D01*
G01X1622184Y94037D02*
X1622493Y93728D01*
G01X1622184Y94677D02*
Y94037D01*
G01X1634167Y91428D02*
X1630826Y88087D01*
G01X1634167Y107663D02*
Y91428D01*
G01X1648902Y75980D02*
X1660387D01*
G01X1647813Y77069D02*
X1648902Y75980D01*
G01X1630312Y77069D02*
X1647813D01*
G01X1626802Y80579D02*
X1630312Y77069D01*
G01X1626802Y81649D02*
Y80579D01*
G01X1626114Y82337D02*
X1626802Y81649D01*
G01X1622401Y82337D02*
X1626114D01*
G01X1618456Y86282D02*
X1622401Y82337D01*
G01X1618456Y88467D02*
Y86282D01*
G01X1616192Y90731D02*
X1618456Y88467D01*
G01X1649579Y80502D02*
X1654849D01*
G01X1649253Y80176D02*
X1649579Y80502D01*
G01X1649247Y80176D02*
X1649253D01*
G01X1648324Y79253D02*
X1649247Y80176D01*
G01X1648324Y79247D02*
Y79253D01*
G01X1646938Y77861D02*
X1648324Y79247D01*
G01X1630916Y77861D02*
X1646938D01*
G01X1629297Y79480D02*
X1630916Y77861D01*
G01X1620484Y91483D02*
X1626450Y85517D01*
G01X1640000Y90500D02*
X1659498D01*
G01X1635500Y95000D02*
X1640000Y90500D01*
G01X1649891Y81254D02*
X1654537D01*
G01X1649890Y81255D02*
X1649891Y81254D01*
G01X1649268Y81255D02*
X1649890D01*
G01X1648941Y80928D02*
X1649268Y81255D01*
G01X1648935Y80928D02*
X1648941D01*
G01X1647572Y79565D02*
X1648935Y80928D01*
G01X1647572Y79559D02*
Y79565D01*
G01X1646626Y78613D02*
X1647572Y79559D01*
G01X1631794Y78613D02*
X1646626D01*
G01X1628769Y81638D02*
X1631794Y78613D01*
G01X1628769Y84261D02*
Y81638D01*
G01X1627203Y85827D02*
X1628769Y84261D01*
G01X1627203Y85828D02*
Y85827D01*
G01X1620796Y92235D02*
X1627203Y85828D01*
G01X1593963Y79716D02*
X1588971D01*
G01X1597924Y75755D02*
X1593963Y79716D01*
G01X1597924Y74077D02*
Y75755D01*
G01X1601501Y70500D02*
X1597924Y74077D01*
G01X1607036Y70500D02*
X1601501D01*
G01X1610853Y66683D02*
X1607036Y70500D01*
G01X1610853Y63861D02*
Y66683D01*
G01X1604402Y84327D02*
X1602653Y86076D01*
G01X1604402Y83265D02*
Y84327D01*
G01X1607017Y80650D02*
X1604402Y83265D01*
G01X1608709Y80650D02*
X1607017D01*
G01X1619759Y69600D02*
X1608709Y80650D01*
G01X1621100Y69600D02*
X1619759D01*
G01X1625800Y73271D02*
X1627489Y74960D01*
G01X1620080Y73271D02*
X1625800D01*
G01X1614866Y78485D02*
X1620080Y73271D01*
G01X1614866Y80668D02*
Y78485D01*
G01X1607232Y88302D02*
X1614866Y80668D01*
G01X1642386Y68386D02*
X1640900Y66900D01*
G01X1665545Y68386D02*
X1642386D01*
G01X1648590Y75228D02*
X1659715D01*
G01X1647550Y76268D02*
X1648590Y75228D01*
G01X1629616Y76268D02*
X1647550D01*
G01X1627497Y78387D02*
X1629616Y76268D01*
G01X1620525Y78387D02*
X1627497D01*
G01X1616834Y82078D02*
X1620525Y78387D01*
G01X1616834Y85029D02*
Y82078D01*
G01X1612057Y89806D02*
X1616834Y85029D01*
G01X1605154Y84793D02*
X1602959Y86988D01*
G01X1605154Y83577D02*
Y84793D01*
G01X1607329Y81402D02*
X1605154Y83577D01*
G01X1609919Y81402D02*
X1607329D01*
G01X1619379Y71942D02*
X1609919Y81402D01*
G01X1622889Y71942D02*
X1619379D01*
G01X1624540Y70291D02*
X1622889Y71942D01*
G01X1659196Y70291D02*
X1624540D01*
G01X1599242Y81742D02*
X1589367D01*
G01X1602000Y84500D02*
X1599242Y81742D01*
G01X1641950Y82250D02*
X1655229D01*
G01X1639889Y80189D02*
X1641950Y82250D01*
G01X1631906Y80189D02*
X1639889D01*
G01X1631905Y80188D02*
X1631906Y80189D01*
G01X1631283Y80188D02*
X1631905D01*
G01X1629521Y81950D02*
X1631283Y80188D01*
G01X1629521Y84573D02*
Y81950D01*
G01X1627955Y86139D02*
X1629521Y84573D01*
G01X1627955Y86140D02*
Y86139D01*
G01X1620682Y93413D02*
X1627955Y86140D01*
G01X1620682Y95301D02*
Y93413D01*
G01X1590657Y72875D02*
X1592715Y70817D01*
G01X1641000Y103000D02*
X1652351D01*
G01X1637463Y106537D02*
X1641000Y103000D01*
G01X1637463Y110037D02*
Y106537D01*
G01X1635150Y112350D02*
X1637463Y110037D01*
G01X1635150Y115550D02*
Y112350D01*
G01X1633700Y117000D02*
X1635150Y115550D01*
G01X1631874Y117000D02*
X1633700D01*
G01X1630974Y117900D02*
X1631874Y117000D01*
G01X1630974Y119526D02*
Y117900D01*
G01X1627259Y123241D02*
X1630974Y119526D01*
G01X1616501Y123241D02*
X1627259D01*
G01X1616298Y123444D02*
X1616501Y123241D01*
G01X1590109Y123444D02*
X1616298D01*
G01X1609036Y132834D02*
X1610591Y134389D01*
G01X1602916Y132834D02*
X1609036D01*
G01X1621434Y94990D02*
X1621433Y94989D01*
G01X1621434Y95612D02*
Y94990D01*
G01X1619716Y97330D02*
X1621434Y95612D01*
G01X1612262Y97330D02*
X1619716D01*
G01X1611083Y96151D02*
X1612262Y97330D01*
G01X1599209Y96151D02*
X1611083D01*
G01X1598496Y96864D02*
X1599209Y96151D01*
G01X1596292Y96864D02*
X1598496D01*
G01X1595702Y96274D02*
X1596292Y96864D01*
G01X1590296Y96274D02*
X1595702D01*
G01X1589612Y96958D02*
X1590296Y96274D01*
G01X1632020Y97980D02*
Y97871D01*
G01X1627900Y102100D02*
X1632020Y97980D01*
G01X1627900Y116200D02*
Y102100D01*
G01X1626349Y117751D02*
X1627900Y116200D01*
G01X1626349Y118641D02*
Y117751D01*
G01X1626339Y118651D02*
X1626349Y118641D01*
G01X1608924Y156017D02*
Y157039D01*
G01X1609981Y154960D02*
X1608924Y156017D01*
G01X1611003Y154960D02*
X1609981D01*
G01X1612100Y153863D02*
X1611003Y154960D01*
G01X1612100Y148628D02*
Y153863D01*
G01X1613741Y146987D02*
X1612100Y148628D01*
G01X1622186Y94679D02*
X1622184Y94677D01*
G01X1622186Y95301D02*
Y94679D01*
G01X1622185Y95302D02*
X1622186Y95301D01*
G01X1622185Y95924D02*
Y95302D01*
G01X1620028Y98081D02*
X1622185Y95924D01*
G01X1611950Y98081D02*
X1620028D01*
G01X1610771Y96902D02*
X1611950Y98081D01*
G01X1600042Y96902D02*
X1610771D01*
G01X1596482Y100462D02*
X1600042Y96902D01*
G01X1590268Y100462D02*
X1596482D01*
G01X1615300Y151696D02*
X1613741Y150137D01*
G01X1615300Y156964D02*
Y151696D01*
G01X1612266Y126414D02*
X1613690Y124990D01*
G01X1606450Y126414D02*
X1612266D01*
G01X1604975Y124939D02*
X1606450Y126414D01*
G01X1590310Y124939D02*
X1604975D01*
G01X1632615Y109215D02*
X1634167Y107663D01*
G01X1592437Y155072D02*
X1592436Y155071D01*
G01X1592748Y155072D02*
X1592437D01*
G01X1592749Y155073D02*
X1592748Y155072D01*
G01X1593525Y155073D02*
X1592749D01*
G01X1596427Y157975D02*
X1593525Y155073D01*
G01X1635500Y108525D02*
Y95000D01*
G01X1633160Y110865D02*
X1635500Y108525D01*
G01X1632026Y110865D02*
X1633160D01*
G01X1631000Y111891D02*
X1632026Y110865D01*
G01X1631000Y116100D02*
Y111891D01*
G01X1630100Y117000D02*
X1631000Y116100D01*
G01X1628700Y117000D02*
X1630100D01*
G01X1628000Y117700D02*
X1628700Y117000D01*
G01X1628000Y119500D02*
Y117700D01*
G01X1627373Y120127D02*
X1628000Y119500D01*
G01X1601950Y120127D02*
X1627373D01*
G01X1598300Y116477D02*
X1601950Y120127D01*
G01X1649868Y148470D02*
X1655640D01*
G01X1647399Y146001D02*
X1649868Y148470D01*
G01X1647399Y132251D02*
Y146001D01*
G01X1648517Y131133D02*
X1647399Y132251D01*
G01X1648517Y125029D02*
Y131133D01*
G01X1650181Y123365D02*
X1648517Y125029D01*
G01X1668038Y123365D02*
X1650181D01*
G01X1649430Y145470D02*
X1658750D01*
G01X1648150Y144190D02*
X1649430Y145470D01*
G01X1648150Y132600D02*
Y144190D01*
G01X1649367Y131383D02*
X1648150Y132600D01*
G01X1649367Y127207D02*
Y131383D01*
G01X1650040Y126534D02*
X1649367Y127207D01*
G01X1667607Y126534D02*
X1650040D01*
G01X1592437Y155824D02*
X1592436Y155823D01*
G01X1592673Y155824D02*
X1592437D01*
G01X1592872Y156023D02*
X1592673Y155824D01*
G01X1592874Y156023D02*
X1592872D01*
G01X1594177Y157326D02*
X1592874Y156023D01*
G01X1609116Y154761D02*
X1610591Y153286D01*
G01X1607030Y154761D02*
X1609116D01*
G01X1605768Y156023D02*
X1607030Y154761D01*
G01X1605768Y156894D02*
Y156023D01*
G01X1621575Y154075D02*
X1624864Y157364D01*
G01X1621575Y152688D02*
Y154075D01*
G01X1620712Y151825D02*
X1621575Y152688D01*
G01X1619488Y151825D02*
X1620712D01*
G01X1618366Y150703D02*
X1619488Y151825D01*
G01X1618366Y149525D02*
Y150703D01*
G01X1617503Y148662D02*
X1618366Y149525D01*
G01X1615662Y148662D02*
X1617503D01*
G01X1615216Y148216D02*
X1615662Y148662D01*
G01X1615216Y140076D02*
Y148216D01*
G01X1614353Y139213D02*
X1615216Y140076D01*
G01X1609979Y139213D02*
X1614353D01*
G01X1609116Y138350D02*
X1609979Y139213D01*
G01X1609116Y135616D02*
Y138350D01*
G01X1607889Y134389D02*
X1609116Y135616D01*
G01X1607441Y134389D02*
X1607889D01*
G01X1650001Y120176D02*
X1667680D01*
G01X1647667Y122510D02*
X1650001Y120176D01*
G01X1647667Y130086D02*
Y122510D01*
G01X1646648Y131105D02*
X1647667Y130086D01*
G01X1646648Y150467D02*
Y131105D01*
G01X1647891Y151710D02*
X1646648Y150467D01*
G01X1649960Y151710D02*
X1647891D01*
G01X1654686Y156436D02*
X1649960Y151710D01*
G01X1598740Y150303D02*
X1600148Y151711D01*
G01X1590193Y150303D02*
X1598740D01*
G01X1609003Y145399D02*
X1610591Y146987D01*
G01X1594033Y145399D02*
X1609003D01*
G01X1649927Y155462D02*
Y157149D01*
G01X1649285Y154820D02*
X1649927Y155462D01*
G01X1645907Y154820D02*
X1649285D01*
G01X1644333Y153246D02*
X1645907Y154820D01*
G01X1644333Y132354D02*
Y153246D01*
G01X1646867Y129820D02*
X1644333Y132354D01*
G01X1646867Y118683D02*
Y129820D01*
G01X1648450Y117100D02*
X1646867Y118683D01*
G01X1652012Y117100D02*
X1648450D01*
G01X1624600Y101988D02*
X1628788Y97800D01*
G01X1624600Y110600D02*
Y101988D01*
G01X1626300Y112300D02*
X1624600Y110600D01*
G01X1630964Y130186D02*
Y158110D01*
G01X1637463Y123687D02*
X1630964Y130186D01*
G01X1637463Y115987D02*
Y123687D01*
G01X1639434Y114016D02*
X1637463Y115987D01*
G01X1655584Y114016D02*
X1639434D01*
G01X1603859Y153286D02*
X1603038Y154107D01*
G01X1607441Y153286D02*
X1603859D01*
G01X1619404Y96579D02*
X1620682Y95301D01*
G01X1612574Y96579D02*
X1619404D01*
G01X1611395Y95400D02*
X1612574Y96579D01*
G01X1598897Y95400D02*
X1611395D01*
G01X1598184Y96113D02*
X1598897Y95400D01*
G01X1596604Y96113D02*
X1598184D01*
G01X1596013Y95522D02*
X1596604Y96113D01*
G01X1589984Y95522D02*
X1596013D01*
G01X1589300Y96206D02*
X1589984Y95522D01*
G01X1607639Y140647D02*
X1597006D01*
G01X1609155Y142163D02*
X1607639Y140647D01*
G01X1609978Y142163D02*
X1609155D01*
G01X1609979Y142164D02*
X1609978Y142163D01*
G01X1611203Y142164D02*
X1609979D01*
G01X1611204Y142163D02*
X1611203Y142164D01*
G01X1612266Y142163D02*
X1611204D01*
G01X1613741Y140688D02*
X1612266Y142163D01*
G01X1590024Y171690D02*
Y172597D01*
G01X1595291Y166423D02*
X1590024Y171690D01*
G01X1632297Y199226D02*
X1634069Y197454D01*
G01X1626965Y199226D02*
X1632297D01*
G01X1613337Y212854D02*
X1626965Y199226D01*
G01X1613337Y217538D02*
Y212854D01*
G01X1611064Y219811D02*
X1613337Y217538D01*
G01X1634154Y197454D02*
X1634069D01*
G01X1636053Y199353D02*
X1634154Y197454D01*
G01X1638323Y199353D02*
X1636053D01*
G01X1640050Y197626D02*
X1638323Y199353D01*
G01X1640050Y197595D02*
Y197626D01*
G01X1640049Y197594D02*
X1640050Y197595D01*
G01X1640049Y196290D02*
Y197594D01*
G01X1642356Y193983D02*
X1640049Y196290D01*
G01X1647193Y193983D02*
X1642356D01*
G01X1648304Y192872D02*
X1647193Y193983D01*
G01X1648926Y192872D02*
X1648304D01*
G01X1648927Y192873D02*
X1648926Y192872D01*
G01X1650841Y192873D02*
X1648927D01*
G01X1599020Y209464D02*
Y238598D01*
G01X1603674Y204810D02*
X1599020Y209464D01*
G01X1603674Y196597D02*
Y204810D01*
G01X1604317Y195954D02*
X1603674Y196597D01*
G01X1604317Y188833D02*
Y195954D01*
G01X1601556Y186072D02*
X1604317Y188833D01*
G01X1601556Y184244D02*
Y186072D01*
G01X1602704Y183096D02*
X1601556Y184244D01*
G01X1608773Y183096D02*
X1602704D01*
G01X1610554Y184877D02*
X1608773Y183096D01*
G01X1609809Y186524D02*
X1608056Y184771D01*
G01X1616216Y186524D02*
X1609809D01*
G01X1617174Y185566D02*
X1616216Y186524D01*
G01X1617174Y184301D02*
Y185566D01*
G01X1616925Y184052D02*
X1617174Y184301D01*
G01X1616925Y181027D02*
Y184052D01*
G01X1617847Y180105D02*
X1616925Y181027D01*
G01X1624142Y180105D02*
X1617847D01*
G01X1624143Y180104D02*
X1624142Y180105D01*
G01X1624952Y180104D02*
X1624143D01*
G01X1637463Y167593D02*
X1624952Y180104D01*
G01X1637463Y166497D02*
Y167593D01*
G01X1637462Y166496D02*
X1637463Y166497D01*
G01X1637462Y165272D02*
Y166496D01*
G01X1637463Y165271D02*
X1637462Y165272D01*
G01X1637463Y165172D02*
Y165271D01*
G01X1638226Y164409D02*
X1637463Y165172D01*
G01X1638325Y164409D02*
X1638226D01*
G01X1638326Y164408D02*
X1638325Y164409D01*
G01X1643392Y164408D02*
X1638326D01*
G01X1645151Y162649D02*
X1643392Y164408D01*
G01X1597612Y208880D02*
Y232600D01*
G01X1602266Y204226D02*
X1597612Y208880D01*
G01X1602266Y196013D02*
Y204226D01*
G01X1602909Y195370D02*
X1602266Y196013D01*
G01X1602909Y189417D02*
Y195370D01*
G01X1600369Y186877D02*
X1602909Y189417D01*
G01X1600369Y184130D02*
Y186877D01*
G01X1602154Y182345D02*
X1600369Y184130D01*
G01X1614544Y182345D02*
X1602154D01*
G01X1617535Y179354D02*
X1614544Y182345D01*
G01X1623830Y179354D02*
X1617535D01*
G01X1630056Y173128D02*
X1623830Y179354D01*
G01X1630056Y169223D02*
Y173128D01*
G01X1635068Y164211D02*
X1630056Y169223D01*
G01X1636400Y164211D02*
X1635068D01*
G01X1637264Y163347D02*
X1636400Y164211D01*
G01X1637264Y162257D02*
Y163347D01*
G01X1638460Y161061D02*
X1637264Y162257D01*
G01X1639550Y161061D02*
X1638460D01*
G01X1639551Y161060D02*
X1639550Y161061D01*
G01X1641474Y161060D02*
X1639551D01*
G01X1641475Y161061D02*
X1641474Y161060D01*
G01X1642699Y161061D02*
X1641475D01*
G01X1642700Y161060D02*
X1642699Y161061D01*
G01X1643762Y161060D02*
X1642700D01*
G01X1645237Y159585D02*
X1643762Y161060D01*
G01X1599666Y170510D02*
X1607441Y162735D01*
G01X1599666Y172246D02*
Y170510D01*
G01X1598252Y173660D02*
X1599666Y172246D01*
G01X1593240Y173660D02*
X1598252D01*
G01X1592877Y174023D02*
X1593240Y173660D01*
G01X1592877Y174024D02*
Y174023D01*
G01X1590138Y176763D02*
X1592877Y174024D01*
G01X1590138Y180104D02*
Y176763D01*
G01X1592870Y217791D02*
Y217900D01*
G01X1594796Y215865D02*
X1592870Y217791D01*
G01X1594796Y207712D02*
Y215865D01*
G01X1599091Y203417D02*
X1594796Y207712D01*
G01X1599091Y195204D02*
Y203417D01*
G01X1600092Y194203D02*
X1599091Y195204D01*
G01X1600092Y191084D02*
Y194203D01*
G01X1597375Y188367D02*
X1600092Y191084D01*
G01X1597375Y179647D02*
Y188367D01*
G01X1598773Y178249D02*
X1597375Y179647D01*
G01X1604188Y178249D02*
X1598773D01*
G01X1604189Y178248D02*
X1604188Y178249D01*
G01X1609311Y178248D02*
X1604189D01*
G01X1610438Y179375D02*
X1609311Y178248D01*
G01X1615388Y179375D02*
X1610438D01*
G01X1616911Y177852D02*
X1615388Y179375D01*
G01X1618085Y177852D02*
X1616911D01*
G01X1620467Y175470D02*
X1618085Y177852D01*
G01X1620467Y172625D02*
Y175470D01*
G01X1621801Y171291D02*
X1620467Y172625D01*
G01X1621801Y164060D02*
Y171291D01*
G01X1623250Y162611D02*
X1621801Y164060D01*
G01X1607795Y216768D02*
Y237752D01*
G01X1608281Y216282D02*
X1607795Y216768D01*
G01X1608281Y210557D02*
Y216282D01*
G01X1621858Y196980D02*
X1608281Y210557D01*
G01X1621858Y195236D02*
Y196980D01*
G01X1627016Y190078D02*
X1621858Y195236D01*
G01X1636608Y190078D02*
X1627016D01*
G01X1637410Y189276D02*
X1636608Y190078D01*
G01X1644056Y189276D02*
X1637410D01*
G01X1646774Y186558D02*
X1644056Y189276D01*
G01X1646774Y186557D02*
Y186558D01*
G01X1646775Y186556D02*
X1646774Y186557D01*
G01X1646775Y185934D02*
Y186556D01*
G01X1646774Y185933D02*
X1646775Y185934D01*
G01X1646774Y180485D02*
Y185933D01*
G01X1646094Y179805D02*
X1646774Y180485D01*
G01X1646094Y171542D02*
Y179805D01*
G01X1649153Y168483D02*
X1646094Y171542D01*
G01X1658387Y168483D02*
X1649153D01*
G01X1590955Y172059D02*
Y172754D01*
G01X1594706Y168308D02*
X1590955Y172059D01*
G01X1595768Y168308D02*
X1594706D01*
G01X1603768Y160308D02*
X1595768Y168308D01*
G01X1604631Y160308D02*
X1603768D01*
G01X1606830Y158109D02*
X1604631Y160308D01*
G01X1607854Y158109D02*
X1606830D01*
G01X1608924Y157039D02*
X1607854Y158109D01*
G01X1612821Y156436D02*
X1613741D01*
G01X1611148Y158109D02*
X1612821Y156436D01*
G01X1609981Y158109D02*
X1611148D01*
G01X1609115Y158975D02*
X1609981Y158109D01*
G01X1609115Y159998D02*
Y158975D01*
G01X1608052Y161061D02*
X1609115Y159998D01*
G01X1604079Y161061D02*
X1608052D01*
G01X1596080Y169060D02*
X1604079Y161061D01*
G01X1595017Y169060D02*
X1596080D01*
G01X1592877Y171200D02*
X1595017Y169060D01*
G01X1592877Y171201D02*
Y171200D01*
G01X1591890Y172188D02*
X1592877Y171201D01*
G01X1591890Y172883D02*
Y172188D01*
G01X1639100Y216954D02*
X1632910Y223144D01*
G01X1639100Y214097D02*
Y216954D01*
G01X1643987Y209210D02*
X1639100Y214097D01*
G01X1649896Y209210D02*
X1643987D01*
G01X1654382Y204724D02*
X1649896Y209210D01*
G01X1615217Y157047D02*
X1615300Y156964D01*
G01X1615217Y157048D02*
Y157047D01*
G01X1614353Y157912D02*
X1615217Y157048D01*
G01X1613187Y157912D02*
X1614353D01*
G01X1612067Y159032D02*
X1613187Y157912D01*
G01X1612067Y160197D02*
Y159032D01*
G01X1611203Y161061D02*
X1612067Y160197D01*
G01X1611202Y161061D02*
X1611203D01*
G01X1611004Y161259D02*
X1611202Y161061D01*
G01X1609979Y161259D02*
X1611004D01*
G01X1609115Y162123D02*
X1609979Y161259D01*
G01X1609115Y162125D02*
Y162123D01*
G01X1609021Y162219D02*
X1609115Y162125D01*
G01X1609021Y163242D02*
Y162219D01*
G01X1608917Y163346D02*
X1609021Y163242D01*
G01X1608917Y163347D02*
Y163346D01*
G01X1608053Y164211D02*
X1608917Y163347D01*
G01X1608052Y164211D02*
X1608053D01*
G01X1603369Y168894D02*
X1608052Y164211D01*
G01X1603369Y172297D02*
Y168894D01*
G01X1601176Y174490D02*
X1603369Y172297D01*
G01X1594764Y174490D02*
X1601176D01*
G01X1590890Y178364D02*
X1594764Y174490D01*
G01X1590890Y180510D02*
Y178364D01*
G01X1648615Y193625D02*
X1652386D01*
G01X1647505Y194735D02*
X1648615Y193625D01*
G01X1642668Y194735D02*
X1647505D01*
G01X1640802Y196601D02*
X1642668Y194735D01*
G01X1640802Y197938D02*
Y196601D01*
G01X1638362Y200378D02*
X1640802Y197938D01*
G01X1631561Y200378D02*
X1638362D01*
G01X1611816Y220123D02*
X1631561Y200378D01*
G01X1636843Y216019D02*
X1631974Y220888D01*
G01X1636843Y212409D02*
Y216019D01*
G01X1642298Y206954D02*
X1636843Y212409D01*
G01X1648697Y206954D02*
X1642298D01*
G01X1653325Y202326D02*
X1648697Y206954D01*
G01X1647784Y205546D02*
X1653060Y200270D01*
G01X1641714Y205546D02*
X1647784D01*
G01X1635435Y211825D02*
X1641714Y205546D01*
G01X1635435Y214114D02*
Y211825D01*
G01X1630069Y219480D02*
X1635435Y214114D01*
G01X1607362Y156436D02*
X1607441D01*
G01X1604863Y158935D02*
X1607362Y156436D01*
G01X1603847Y158935D02*
X1604863D01*
G01X1599458Y163324D02*
X1603847Y158935D01*
G01X1590676Y163324D02*
X1599458D01*
G01X1589272Y164728D02*
X1590676Y163324D01*
G01X1589272Y172223D02*
Y164728D01*
G01X1610591Y166449D02*
Y165885D01*
G01X1605100Y171940D02*
X1610591Y166449D01*
G01X1605100Y172872D02*
Y171940D01*
G01X1601976Y175996D02*
X1605100Y172872D01*
G01X1595586Y175996D02*
X1601976D01*
G01X1592629Y178953D02*
X1595586Y175996D01*
G01X1592629Y182360D02*
Y178953D01*
G01X1594177Y157328D02*
Y157326D01*
G01X1594203Y157354D02*
X1594177Y157328D01*
G01X1594203Y157837D02*
Y157354D01*
G01X1595816Y159450D02*
X1594203Y157837D01*
G01X1597174Y159450D02*
X1595816D01*
G01X1598733Y157891D02*
X1597174Y159450D01*
G01X1598733Y157473D02*
Y157891D01*
G01X1599799Y156407D02*
X1598733Y157473D01*
G01X1604169Y156407D02*
X1599799D01*
G01X1616890Y160405D02*
Y159585D01*
G01X1615286Y162009D02*
X1616890Y160405D01*
G01X1615286Y167314D02*
Y162009D01*
G01X1613101Y169499D02*
X1615286Y167314D01*
G01X1609553Y169499D02*
X1613101D01*
G01X1608690Y170362D02*
X1609553Y169499D01*
G01X1608689Y170362D02*
X1608690D01*
G01X1606606Y172445D02*
X1608689Y170362D01*
G01X1606606Y172446D02*
Y172445D01*
G01X1605902Y173150D02*
X1606606Y172446D01*
G01X1605902Y173762D02*
Y173150D01*
G01X1602917Y176747D02*
X1605902Y173762D01*
G01X1595899Y176747D02*
X1602917D01*
G01X1593381Y179265D02*
X1595899Y176747D01*
G01X1593381Y183820D02*
Y179265D01*
G01X1604750Y157912D02*
X1605768Y156894D01*
G01X1603806Y157912D02*
X1604750D01*
G01X1600384Y161334D02*
X1603806Y157912D01*
G01X1590395Y161334D02*
X1600384D01*
G01X1596204Y208296D02*
Y232016D01*
G01X1600500Y204000D02*
X1596204Y208296D01*
G01X1600500Y195787D02*
Y204000D01*
G01X1601500Y194787D02*
X1600500Y195787D01*
G01X1601500Y190000D02*
Y194787D01*
G01X1598961Y187461D02*
X1601500Y190000D01*
G01X1598961Y183539D02*
Y187461D01*
G01X1600610Y181890D02*
X1598961Y183539D01*
G01X1600610Y180056D02*
Y181890D01*
G01X1601666Y179000D02*
X1600610Y180056D01*
G01X1609000Y179000D02*
X1601666D01*
G01X1611000Y181000D02*
X1609000Y179000D01*
G01X1614826Y181000D02*
X1611000D01*
G01X1617223Y178603D02*
X1614826Y181000D01*
G01X1618397Y178603D02*
X1617223D01*
G01X1622288Y174712D02*
X1618397Y178603D01*
G01X1625288Y174712D02*
X1622288D01*
G01X1626500Y173500D02*
X1625288Y174712D01*
G01X1626500Y171000D02*
Y173500D01*
G01X1624864Y169364D02*
X1626500Y171000D01*
G01X1624864Y157364D02*
Y169364D01*
G01X1599772Y209776D02*
Y238910D01*
G01X1612280Y197268D02*
X1599772Y209776D01*
G01X1612280Y194000D02*
Y197268D01*
G01X1619645Y186635D02*
X1612280Y194000D01*
G01X1622901Y186635D02*
X1619645D01*
G01X1623823Y185713D02*
X1622901Y186635D01*
G01X1623823Y184004D02*
Y185713D01*
G01X1625066Y182759D02*
X1623823Y184004D01*
G01X1627326Y182759D02*
X1625066D01*
G01X1650078Y174448D02*
X1663434D01*
G01X1648320Y172690D02*
X1650078Y174448D01*
G01X1602635Y217531D02*
Y244932D01*
G01X1606025Y214141D02*
X1602635Y217531D01*
G01X1606025Y207825D02*
Y214141D01*
G01X1615447Y198403D02*
X1606025Y207825D01*
G01X1615447Y194817D02*
Y198403D01*
G01X1621011Y189253D02*
X1615447Y194817D01*
G01X1624649Y189253D02*
X1621011D01*
G01X1626080Y187822D02*
X1624649Y189253D01*
G01X1627976Y187822D02*
X1626080D01*
G01X1629683Y186115D02*
X1627976Y187822D01*
G01X1629684Y186115D02*
X1629683D01*
G01X1630406Y185393D02*
X1629684Y186115D01*
G01X1630406Y183157D02*
Y185393D01*
G01X1633240Y180323D02*
X1630406Y183157D01*
G01X1640123Y180323D02*
X1633240D01*
G01X1644433Y184633D02*
X1640123Y180323D01*
G01X1644433Y185415D02*
Y184633D01*
G01X1650354Y217305D02*
X1653235Y214424D01*
G01X1646210Y217305D02*
X1650354D01*
G01X1632754Y230761D02*
X1646210Y217305D01*
G01X1605073Y217603D02*
Y239410D01*
G01X1607459Y215217D02*
X1605073Y217603D01*
G01X1607459Y215197D02*
Y215217D01*
G01X1607529Y215127D02*
X1607459Y215197D01*
G01X1607529Y209727D02*
Y215127D01*
G01X1618257Y198999D02*
X1607529Y209727D01*
G01X1618257Y195084D02*
Y198999D01*
G01X1622256Y191085D02*
X1618257Y195084D01*
G01X1624945Y191085D02*
X1622256D01*
G01X1626704Y189326D02*
X1624945Y191085D01*
G01X1636296Y189326D02*
X1626704D01*
G01X1637098Y188524D02*
X1636296Y189326D01*
G01X1643642Y188524D02*
X1637098D01*
G01X1646023Y186143D02*
X1643642Y188524D01*
G01X1646023Y181257D02*
Y186143D01*
G01X1645343Y180577D02*
X1646023Y181257D01*
G01X1645343Y171230D02*
Y180577D01*
G01X1649961Y166612D02*
X1645343Y171230D01*
G01X1649961Y165019D02*
Y166612D01*
G01X1649186Y164244D02*
X1649961Y165019D01*
G01X1647341Y164244D02*
X1649186D01*
G01X1646800Y163703D02*
X1647341Y164244D01*
G01X1646800Y159060D02*
Y163703D01*
G01X1645753Y158013D02*
X1646800Y159060D01*
G01X1634211Y158013D02*
X1645753D01*
G01X1629489Y162735D02*
X1634211Y158013D01*
G01X1637595Y216331D02*
X1632286Y221640D01*
G01X1637595Y213474D02*
Y216331D01*
G01X1643363Y207706D02*
X1637595Y213474D01*
G01X1649272Y207706D02*
X1643363D01*
G01X1653758Y203220D02*
X1649272Y207706D01*
G01X1598299Y160201D02*
X1600490Y158010D01*
G01X1595504Y160201D02*
X1598299D01*
G01X1593450Y158147D02*
X1595504Y160201D01*
G01X1593450Y157664D02*
Y158147D01*
G01X1593426Y157640D02*
X1593450Y157664D01*
G01X1593426Y157638D02*
Y157640D01*
G01X1592562Y156774D02*
X1593426Y157638D01*
G01X1592560Y156774D02*
X1592562D01*
G01X1592361Y156575D02*
X1592560Y156774D01*
G01X1591539Y156575D02*
X1592361D01*
G01X1591340Y156774D02*
X1591539Y156575D01*
G01X1591338Y156774D02*
X1591340D01*
G01X1590474Y157638D02*
X1591338Y156774D01*
G01X1590474Y157640D02*
Y157638D01*
G01X1626935Y217775D02*
X1626568Y218142D01*
G01X1610185Y211777D02*
Y218941D01*
G01X1624304Y197658D02*
X1610185Y211777D01*
G01X1624304Y195484D02*
Y197658D01*
G01X1627806Y191982D02*
X1624304Y195484D01*
G01X1637936Y191982D02*
X1627806D01*
G01X1638738Y191180D02*
X1637936Y191982D01*
G01X1645978Y191180D02*
X1638738D01*
G01X1649025Y188133D02*
X1645978Y191180D01*
G01X1649025Y185647D02*
Y188133D01*
G01X1649947Y184725D02*
X1649025Y185647D01*
G01X1650065Y184725D02*
X1649947D01*
G01X1650823Y183967D02*
X1650065Y184725D01*
G01X1649584Y208458D02*
X1654070Y203972D01*
G01X1643675Y208458D02*
X1649584D01*
G01X1638348Y213785D02*
X1643675Y208458D01*
G01X1638348Y216642D02*
Y213785D01*
G01X1632598Y222392D02*
X1638348Y216642D01*
G01X1647013Y204138D02*
X1659091Y192060D01*
G01X1633121Y204138D02*
X1647013D01*
G01X1615576Y221683D02*
X1633121Y204138D01*
G01X1589125Y176712D02*
Y180148D01*
G01X1592642Y173195D02*
X1589125Y176712D01*
G01X1592642Y172500D02*
Y173195D01*
G01X1592877Y172265D02*
X1592642Y172500D01*
G01X1592877Y172264D02*
Y172265D01*
G01X1593628Y171513D02*
X1592877Y172264D01*
G01X1593628Y171512D02*
Y171513D01*
G01X1595082Y170058D02*
X1593628Y171512D01*
G01X1597891Y170058D02*
X1595082D01*
G01X1600490Y167459D02*
X1597891Y170058D01*
G01X1632809Y203386D02*
X1614824Y221371D01*
G01X1646701Y203386D02*
X1632809D01*
G01X1658780Y191307D02*
X1646701Y203386D01*
G01X1639806Y193141D02*
X1637870Y195077D01*
G01X1646967Y193141D02*
X1639806D01*
G01X1647989Y192119D02*
X1646967Y193141D01*
G01X1647991Y192121D02*
X1647989Y192119D01*
G01X1647993D02*
X1647991Y192121D01*
G01X1648615Y192119D02*
X1647993D01*
G01X1648616Y192120D02*
X1648615Y192119D01*
G01X1649238Y192120D02*
X1648616D01*
G01X1649239Y192121D02*
X1649238Y192120D01*
G01X1650529Y192121D02*
X1649239D01*
G01X1623048Y159585D02*
X1623189D01*
G01X1621427Y161206D02*
X1623048Y159585D01*
G01X1619482Y161206D02*
X1621427D01*
G01X1619429Y161259D02*
X1619482Y161206D01*
G01X1619428Y161259D02*
X1619429D01*
G01X1618564Y162123D02*
X1619428Y161259D01*
G01X1618564Y166499D02*
Y162123D01*
G01X1617663Y167400D02*
X1618564Y166499D01*
G01X1616677Y167400D02*
X1617663D01*
G01X1612963Y171114D02*
X1616677Y167400D01*
G01X1609001Y171114D02*
X1612963D01*
G01X1607358Y172757D02*
X1609001Y171114D01*
G01X1607358Y173966D02*
Y172757D01*
G01X1603826Y177498D02*
X1607358Y173966D01*
G01X1596373Y177498D02*
X1603826D01*
G01X1594133Y179738D02*
X1596373Y177498D01*
G01X1594133Y187191D02*
Y179738D01*
G01X1595022Y188080D02*
X1594133Y187191D01*
G01X1595022Y204180D02*
Y188080D01*
G01X1645988Y168283D02*
X1648386Y165885D01*
G01X1643419Y168283D02*
X1645988D01*
G01X1629100Y182602D02*
X1643419Y168283D01*
G01X1629100Y184799D02*
Y182602D01*
G01X1627485Y186414D02*
X1629100Y184799D01*
G01X1625496Y186414D02*
X1627485D01*
G01X1624221Y187689D02*
X1625496Y186414D01*
G01X1620583Y187689D02*
X1624221D01*
G01X1613688Y194584D02*
X1620583Y187689D01*
G01X1613688Y197852D02*
Y194584D01*
G01X1601180Y210360D02*
X1613688Y197852D01*
G01X1601180Y245603D02*
Y210360D01*
G01X1609033Y211241D02*
Y218376D01*
G01X1622611Y197663D02*
X1609033Y211241D01*
G01X1622611Y195547D02*
Y197663D01*
G01X1627328Y190830D02*
X1622611Y195547D01*
G01X1637458Y190830D02*
X1627328D01*
G01X1638260Y190028D02*
X1637458Y190830D01*
G01X1644368Y190028D02*
X1638260D01*
G01X1647873Y186523D02*
X1644368Y190028D01*
G01X1647873Y186390D02*
Y186523D01*
G01X1648274Y185989D02*
X1647873Y186390D01*
G01X1648274Y185335D02*
Y185989D01*
G01X1648560Y185049D02*
X1648274Y185335D01*
G01X1648560Y184293D02*
Y185049D01*
G01X1649924Y182929D02*
X1648560Y184293D01*
G01X1649924Y181623D02*
Y182929D01*
G01X1646845Y178544D02*
X1649924Y181623D01*
G01X1646845Y171854D02*
Y178544D01*
G01X1648541Y170158D02*
X1646845Y171854D01*
G01X1660124Y170158D02*
X1648541D01*
G01X1649927Y157149D02*
X1650846Y158068D01*
G01X1639852Y217266D02*
X1633222Y223896D01*
G01X1639852Y214648D02*
Y217266D01*
G01X1644538Y209962D02*
X1639852Y214648D01*
G01X1650208Y209962D02*
X1644538D01*
G01X1650470Y209700D02*
X1650208Y209962D01*
G01X1631873Y201130D02*
X1612568Y220435D01*
G01X1641120Y201130D02*
X1631873D01*
G01X1644290Y197960D02*
X1641120Y201130D01*
G01X1644290Y196383D02*
Y197960D01*
G01X1605475Y187275D02*
X1603300Y185100D01*
G01X1616528Y187275D02*
X1605475D01*
G01X1617925Y185878D02*
X1616528Y187275D01*
G01X1617925Y184291D02*
Y185878D01*
G01X1618274Y183942D02*
X1617925Y184291D01*
G01X1618274Y183941D02*
Y183942D01*
G01X1618847Y183369D02*
X1618274Y183941D01*
G01X1622962Y183369D02*
X1618847D01*
G01X1638799Y167532D02*
X1622962Y183369D01*
G01X1643589Y167532D02*
X1638799D01*
G01X1645237Y165884D02*
X1643589Y167532D01*
G01X1641356Y217890D02*
X1634456Y224790D01*
G01X1641356Y216165D02*
Y217890D01*
G01X1645047Y212474D02*
X1641356Y216165D01*
G01X1655188Y212474D02*
X1645047D01*
G01X1611761Y211881D02*
Y213507D01*
G01X1627174Y196468D02*
X1611761Y211881D01*
G01X1627174Y194608D02*
Y196468D01*
G01X1627214Y194568D02*
X1627174Y194608D01*
G01X1627214Y194523D02*
Y194568D01*
G01X1628602Y193135D02*
X1627214Y194523D01*
G01X1638491Y193135D02*
X1628602D01*
G01X1639237Y192389D02*
X1638491Y193135D01*
G01X1646422Y192389D02*
X1639237D01*
G01X1647444Y191367D02*
X1646422Y192389D01*
G01X1647677Y191367D02*
X1647444D01*
G01X1647678Y191366D02*
X1647677Y191367D01*
G01X1648300Y191366D02*
X1647678D01*
G01X1648301Y191367D02*
X1648300Y191366D01*
G01X1649339Y191367D02*
X1648301D01*
G01X1655031Y185675D02*
X1649339Y191367D01*
G01X1646295Y202634D02*
X1658373Y190556D01*
G01X1632497Y202634D02*
X1646295D01*
G01X1614072Y221059D02*
X1632497Y202634D01*
G01X1606777Y214815D02*
X1603387Y218205D01*
G01X1606777Y208602D02*
Y214815D01*
G01X1616577Y198802D02*
X1606777Y208602D01*
G01X1616577Y195271D02*
Y198802D01*
G01X1621843Y190005D02*
X1616577Y195271D01*
G01X1624961Y190005D02*
X1621843D01*
G01X1626392Y188574D02*
X1624961Y190005D01*
G01X1628288Y188574D02*
X1626392D01*
G01X1631285Y185577D02*
X1628288Y188574D01*
G01X1631285Y183679D02*
Y185577D01*
G01X1633739Y181225D02*
X1631285Y183679D01*
G01X1638865Y181225D02*
X1633739D01*
G01X1641800Y184160D02*
X1638865Y181225D01*
G01X1641800Y184400D02*
Y184160D01*
G01X1630964Y158110D02*
X1629489Y159585D01*
G01X1612101Y164375D02*
X1613741Y162735D01*
G01X1609883Y164375D02*
X1612101D01*
G01X1604348Y169910D02*
X1609883Y164375D01*
G01X1604348Y172410D02*
Y169910D01*
G01X1601513Y175245D02*
X1604348Y172410D01*
G01X1595273Y175245D02*
X1601513D01*
G01X1591642Y178876D02*
X1595273Y175245D01*
G01X1591642Y181490D02*
Y178876D01*
G01X1632185Y201882D02*
X1613320Y220747D01*
G01X1645918Y201882D02*
X1632185D01*
G01X1659700Y188100D02*
X1645918Y201882D01*
G01X1611064Y240580D02*
Y219811D01*
G01X1611871Y241387D02*
X1611064Y240580D01*
G01X1611871Y260251D02*
Y241387D01*
G01X1606467Y265655D02*
X1611871Y260251D01*
G01X1606467Y268518D02*
Y265655D01*
G01X1601170Y273815D02*
X1606467Y268518D01*
G01X1601170Y275625D02*
Y273815D01*
G01X1595511Y264652D02*
Y274900D01*
G01X1595510Y264651D02*
X1595511Y264652D01*
G01X1595510Y264029D02*
Y264651D01*
G01X1597257Y262282D02*
X1595510Y264029D01*
G01X1597257Y262280D02*
Y262282D01*
G01X1597272Y262265D02*
X1597257Y262280D01*
G01X1597272Y259906D02*
Y262265D01*
G01X1599804Y257374D02*
X1597272Y259906D01*
G01X1599804Y254118D02*
Y257374D01*
G01X1598171Y252485D02*
X1599804Y254118D01*
G01X1598171Y249536D02*
Y252485D01*
G01X1597361Y248726D02*
X1598171Y249536D01*
G01X1595666Y248726D02*
X1597361D01*
G01X1594267Y247327D02*
X1595666Y248726D01*
G01X1594267Y243351D02*
Y247327D01*
G01X1599020Y238598D02*
X1594267Y243351D01*
G01X1628624Y226694D02*
Y225318D01*
G01X1622368Y232950D02*
X1628624Y226694D01*
G01X1622368Y235957D02*
Y232950D01*
G01X1623222Y236811D02*
X1622368Y235957D01*
G01X1623222Y245943D02*
Y236811D01*
G01X1624852Y247573D02*
X1623222Y245943D01*
G01X1624852Y248819D02*
Y247573D01*
G01X1624851Y248820D02*
X1624852Y248819D01*
G01X1624851Y249442D02*
Y248820D01*
G01X1624850Y249443D02*
X1624851Y249442D01*
G01X1624850Y250065D02*
Y249443D01*
G01X1624849Y250066D02*
X1624850Y250065D01*
G01X1624849Y258691D02*
Y250066D01*
G01X1624850Y258692D02*
X1624849Y258691D01*
G01X1624850Y259301D02*
Y258692D01*
G01X1624849Y259302D02*
X1624850Y259301D01*
G01X1624849Y261187D02*
Y259302D01*
G01X1624747Y261289D02*
X1624849Y261187D01*
G01X1624747Y261323D02*
Y261289D01*
G01X1623000Y263070D02*
X1624747Y261323D01*
G01X1623000Y268755D02*
Y263070D01*
G01X1620631Y271124D02*
X1623000Y268755D01*
G01X1620631Y275045D02*
Y271124D01*
G01X1617601Y278075D02*
X1620631Y275045D01*
G01X1614408Y278075D02*
X1617601D01*
G01X1596750Y295733D02*
X1614408Y278075D01*
G01X1595849Y261696D02*
Y261697D01*
G01X1595864Y261681D02*
X1595849Y261696D01*
G01X1595864Y259322D02*
Y261681D01*
G01X1595866Y259320D02*
X1595864Y259322D01*
G01X1595866Y257198D02*
Y259320D01*
G01X1595865Y257197D02*
X1595866Y257198D01*
G01X1595865Y255035D02*
Y257197D01*
G01X1593920Y253090D02*
X1595865Y255035D01*
G01X1593920Y250490D02*
Y253090D01*
G01X1591970Y248540D02*
X1593920Y250490D01*
G01X1591970Y243656D02*
Y248540D01*
G01X1595425Y240201D02*
X1591970Y243656D01*
G01X1595425Y234787D02*
Y240201D01*
G01X1597612Y232600D02*
X1595425Y234787D01*
G01X1600192Y269714D02*
Y275539D01*
G01X1602386Y267520D02*
X1600192Y269714D01*
G01X1602386Y266100D02*
Y267520D01*
G01X1606604Y261882D02*
X1602386Y266100D01*
G01X1606604Y244319D02*
Y261882D01*
G01X1605073Y242788D02*
X1606604Y244319D01*
G01X1605073Y240474D02*
Y242788D01*
G01X1607795Y237752D02*
X1605073Y240474D01*
G01X1646522Y218057D02*
X1650903D01*
G01X1633506Y231073D02*
X1646522Y218057D01*
G01X1633506Y237168D02*
Y231073D01*
G01X1634076Y237738D02*
X1633506Y237168D01*
G01X1634076Y242660D02*
Y237738D01*
G01X1633506Y243230D02*
X1634076Y242660D01*
G01X1633506Y250762D02*
Y243230D01*
G01X1632697Y251571D02*
X1633506Y250762D01*
G01X1632697Y265766D02*
Y251571D01*
G01X1630466Y267997D02*
X1632697Y265766D01*
G01X1630466Y277033D02*
Y267997D01*
G01X1628000Y279499D02*
X1630466Y277033D01*
G01X1628000Y283500D02*
Y279499D01*
G01X1614096Y277323D02*
X1595998Y295421D01*
G01X1616912Y277323D02*
X1614096D01*
G01X1619839Y274396D02*
X1616912Y277323D01*
G01X1619839Y270852D02*
Y274396D01*
G01X1622166Y268525D02*
X1619839Y270852D01*
G01X1622166Y268268D02*
Y268525D01*
G01X1622167Y268267D02*
X1622166Y268268D01*
G01X1622167Y268200D02*
Y268267D01*
G01X1622207Y268160D02*
X1622167Y268200D01*
G01X1622207Y262783D02*
Y268160D01*
G01X1623994Y260996D02*
X1622207Y262783D01*
G01X1623994Y260978D02*
Y260996D01*
G01X1624097Y260875D02*
X1623994Y260978D01*
G01X1624097Y249754D02*
Y260875D01*
G01X1624098Y249753D02*
X1624097Y249754D01*
G01X1624098Y249131D02*
Y249753D01*
G01X1624099Y249130D02*
X1624098Y249131D01*
G01X1624099Y248508D02*
Y249130D01*
G01X1624100Y248507D02*
X1624099Y248508D01*
G01X1624100Y247885D02*
Y248507D01*
G01X1622207Y245992D02*
X1624100Y247885D01*
G01X1622207Y236860D02*
Y245992D01*
G01X1621616Y236269D02*
X1622207Y236860D01*
G01X1621616Y230182D02*
Y236269D01*
G01X1624548Y227250D02*
X1621616Y230182D01*
G01X1624548Y224597D02*
Y227250D01*
G01X1625525Y223620D02*
X1624548Y224597D01*
G01X1630687Y223620D02*
X1625525D01*
G01X1631163Y223144D02*
X1630687Y223620D01*
G01X1632910Y223144D02*
X1631163D01*
G01X1611816Y240029D02*
Y220123D01*
G01X1612623Y240836D02*
X1611816Y240029D01*
G01X1612623Y260646D02*
Y240836D01*
G01X1607219Y266050D02*
X1612623Y260646D01*
G01X1607219Y268830D02*
Y266050D01*
G01X1601922Y274127D02*
X1607219Y268830D01*
G01X1601922Y275937D02*
Y274127D01*
G01X1613491Y274736D02*
X1593742Y294485D01*
G01X1613491Y273684D02*
Y274736D01*
G01X1619951Y267224D02*
X1613491Y273684D01*
G01X1619951Y261829D02*
Y267224D01*
G01X1621841Y259939D02*
X1619951Y261829D01*
G01X1621841Y248818D02*
Y259939D01*
G01X1619951Y246928D02*
X1621841Y248818D01*
G01X1619951Y237796D02*
Y246928D01*
G01X1619360Y237205D02*
X1619951Y237796D01*
G01X1619360Y222947D02*
Y237205D01*
G01X1621348Y220959D02*
X1619360Y222947D01*
G01X1630156Y220959D02*
X1621348D01*
G01X1630227Y220888D02*
X1630156Y220959D01*
G01X1631974Y220888D02*
X1630227D01*
G01X1627742Y219480D02*
X1630069D01*
G01X1627671Y219551D02*
X1627742Y219480D01*
G01X1621851Y219551D02*
X1627671D01*
G01X1621850Y219550D02*
X1621851Y219551D01*
G01X1620765Y219550D02*
X1621850D01*
G01X1617952Y222363D02*
X1620765Y219550D01*
G01X1617952Y237789D02*
Y222363D01*
G01X1618543Y238380D02*
X1617952Y237789D01*
G01X1618543Y266640D02*
Y238380D01*
G01X1607842Y277341D02*
X1618543Y266640D01*
G01X1607842Y278393D02*
Y277341D01*
G01X1592334Y293901D02*
X1607842Y278393D01*
G01X1599752Y246310D02*
X1599270D01*
G01X1600380Y246938D02*
X1599752Y246310D01*
G01X1600380Y250536D02*
Y246938D01*
G01X1600379Y250537D02*
X1600380Y250536D01*
G01X1600379Y252565D02*
Y250537D01*
G01X1601308Y253494D02*
X1600379Y252565D01*
G01X1601308Y257998D02*
Y253494D01*
G01X1598776Y260530D02*
X1601308Y257998D01*
G01X1598776Y262032D02*
Y260530D01*
G01X1598778Y262034D02*
X1598776Y262032D01*
G01X1598778Y262937D02*
Y262034D01*
G01X1597351Y264364D02*
X1598778Y262937D01*
G01X1597351Y275188D02*
Y264364D01*
G01X1591360Y254152D02*
Y251629D01*
G01X1593305Y256097D02*
X1591360Y254152D01*
G01X1593305Y256135D02*
Y256097D01*
G01X1593304Y256136D02*
X1593305Y256135D01*
G01X1593304Y258258D02*
Y256136D01*
G01X1593305Y258259D02*
X1593304Y258258D01*
G01X1593289Y258275D02*
X1593305Y258259D01*
G01X1593289Y259214D02*
Y258275D01*
G01X1593304Y259229D02*
X1593289Y259214D01*
G01X1593304Y260619D02*
Y259229D01*
G01X1593289Y260634D02*
X1593304Y260619D01*
G01X1593289Y260635D02*
Y260634D01*
G01X1594441Y261112D02*
Y261113D01*
G01X1594456Y261097D02*
X1594441Y261112D01*
G01X1594456Y258751D02*
Y261097D01*
G01X1594450Y258745D02*
X1594456Y258751D01*
G01X1594458Y258736D02*
X1594450Y258745D01*
G01X1594458Y257782D02*
Y258736D01*
G01X1594456Y257780D02*
X1594458Y257782D01*
G01X1594456Y256614D02*
Y257780D01*
G01X1594457Y256613D02*
X1594456Y256614D01*
G01X1594457Y255619D02*
Y256613D01*
G01X1592512Y253674D02*
X1594457Y255619D01*
G01X1592512Y251074D02*
Y253674D01*
G01X1590562Y249124D02*
X1592512Y251074D01*
G01X1590562Y241832D02*
Y249124D01*
G01X1593786Y238608D02*
X1590562Y241832D01*
G01X1593786Y234434D02*
Y238608D01*
G01X1596204Y232016D02*
X1593786Y234434D01*
G01X1596263Y264340D02*
Y275212D01*
G01X1598026Y262577D02*
X1596263Y264340D01*
G01X1598026Y262346D02*
Y262577D01*
G01X1598024Y262344D02*
X1598026Y262346D01*
G01X1598024Y260218D02*
Y262344D01*
G01X1600556Y257686D02*
X1598024Y260218D01*
G01X1600556Y253806D02*
Y257686D01*
G01X1598923Y252173D02*
X1600556Y253806D01*
G01X1598923Y249224D02*
Y252173D01*
G01X1597673Y247974D02*
X1598923Y249224D01*
G01X1595978Y247974D02*
X1597673D01*
G01X1595019Y247015D02*
X1595978Y247974D01*
G01X1595019Y243663D02*
Y247015D01*
G01X1599772Y238910D02*
X1595019Y243663D01*
G01X1598151Y265002D02*
Y275452D01*
G01X1599823Y263330D02*
X1598151Y265002D01*
G01X1601494Y263330D02*
X1599823D01*
G01X1604214Y260610D02*
X1601494Y263330D01*
G01X1604214Y246511D02*
Y260610D01*
G01X1602635Y244932D02*
X1604214Y246511D01*
G01X1632754Y237480D02*
Y230761D01*
G01X1633324Y238050D02*
X1632754Y237480D01*
G01X1633324Y242348D02*
Y238050D01*
G01X1632754Y242918D02*
X1633324Y242348D01*
G01X1632754Y250450D02*
Y242918D01*
G01X1631945Y251259D02*
X1632754Y250450D01*
G01X1631945Y265450D02*
Y251259D01*
G01X1630420Y266975D02*
X1631945Y265450D01*
G01X1630420Y266979D02*
Y266975D01*
G01X1629714Y267685D02*
X1630420Y266979D01*
G01X1629714Y276286D02*
Y267685D01*
G01X1627000Y279000D02*
X1629714Y276286D01*
G01X1627000Y284500D02*
Y279000D01*
G01X1601186Y266006D02*
X1600810D01*
G01X1605852Y261340D02*
X1601186Y266006D01*
G01X1605852Y245039D02*
Y261340D01*
G01X1604321Y243508D02*
X1605852Y245039D01*
G01X1604321Y240162D02*
Y243508D01*
G01X1605073Y239410D02*
X1604321Y240162D01*
G01X1614243Y275048D02*
X1594494Y294797D01*
G01X1614243Y274063D02*
Y275048D01*
G01X1620662Y267644D02*
X1614243Y274063D01*
G01X1620662Y267577D02*
Y267644D01*
G01X1620703Y267536D02*
X1620662Y267577D01*
G01X1620703Y262141D02*
Y267536D01*
G01X1622593Y260251D02*
X1620703Y262141D01*
G01X1622593Y249130D02*
Y260251D01*
G01X1622594Y249129D02*
X1622593Y249130D01*
G01X1622594Y248507D02*
Y249129D01*
G01X1620703Y246616D02*
X1622594Y248507D01*
G01X1620703Y237484D02*
Y246616D01*
G01X1620112Y236893D02*
X1620703Y237484D01*
G01X1620112Y229558D02*
Y236893D01*
G01X1623020Y226650D02*
X1620112Y229558D01*
G01X1623020Y223997D02*
Y226650D01*
G01X1625121Y221896D02*
X1623020Y223997D01*
G01X1630283Y221896D02*
X1625121D01*
G01X1630539Y221640D02*
X1630283Y221896D01*
G01X1632286Y221640D02*
X1630539D01*
G01X1606434Y277809D02*
X1590916Y293327D01*
G01X1606434Y276757D02*
Y277809D01*
G01X1617135Y266056D02*
X1606434Y276757D01*
G01X1617135Y238964D02*
Y266056D01*
G01X1616544Y238373D02*
X1617135Y238964D01*
G01X1616544Y222866D02*
Y238373D01*
G01X1616543Y222865D02*
X1616544Y222866D01*
G01X1616543Y221780D02*
Y222865D01*
G01X1620181Y218142D02*
X1616543Y221780D01*
G01X1626568Y218142D02*
X1620181D01*
G01X1604222Y265934D02*
Y268107D01*
G01X1610627Y259529D02*
X1604222Y265934D01*
G01X1610627Y241773D02*
Y259529D01*
G01X1609912Y241058D02*
X1610627Y241773D01*
G01X1609912Y219214D02*
Y241058D01*
G01X1610185Y218941D02*
X1609912Y219214D01*
G01X1630851Y222392D02*
X1632598D01*
G01X1630423Y222820D02*
X1630851Y222392D01*
G01X1625261Y222820D02*
X1630423D01*
G01X1623773Y224308D02*
X1625261Y222820D01*
G01X1623773Y226961D02*
Y224308D01*
G01X1620864Y229870D02*
X1623773Y226961D01*
G01X1620864Y236581D02*
Y229870D01*
G01X1621455Y237172D02*
X1620864Y236581D01*
G01X1621455Y246304D02*
Y237172D01*
G01X1623347Y248196D02*
X1621455Y246304D01*
G01X1623347Y248818D02*
Y248196D01*
G01X1623346Y248819D02*
X1623347Y248818D01*
G01X1623346Y249441D02*
Y248819D01*
G01X1623345Y249442D02*
X1623346Y249441D01*
G01X1623345Y260563D02*
Y249442D01*
G01X1621455Y262453D02*
X1623345Y260563D01*
G01X1621455Y267848D02*
Y262453D01*
G01X1621415Y267888D02*
X1621455Y267848D01*
G01X1621415Y267955D02*
Y267888D01*
G01X1619082Y270288D02*
X1621415Y267955D01*
G01X1619082Y274078D02*
Y270288D01*
G01X1618407Y274753D02*
X1619082Y274078D01*
G01X1618406Y274753D02*
X1618407D01*
G01X1616589Y276570D02*
X1618406Y274753D01*
G01X1613785Y276570D02*
X1616589D01*
G01X1595246Y295109D02*
X1613785Y276570D01*
G01X1631218Y277781D02*
X1629000Y279999D01*
G01X1631218Y268312D02*
Y277781D01*
G01X1633449Y266081D02*
X1631218Y268312D01*
G01X1633449Y251883D02*
Y266081D01*
G01X1634258Y251074D02*
X1633449Y251883D01*
G01X1634258Y243542D02*
Y251074D01*
G01X1634828Y242972D02*
X1634258Y243542D01*
G01X1634828Y237426D02*
Y242972D01*
G01X1634258Y236856D02*
X1634828Y237426D01*
G01X1634258Y231385D02*
Y236856D01*
G01X1646834Y218809D02*
X1634258Y231385D01*
G01X1652445Y218809D02*
X1646834D01*
G01X1615576Y238469D02*
Y221683D01*
G01X1616383Y239276D02*
X1615576Y238469D01*
G01X1616383Y265744D02*
Y239276D01*
G01X1605682Y276445D02*
X1616383Y265744D01*
G01X1605682Y277497D02*
Y276445D01*
G01X1590164Y293015D02*
X1605682Y277497D01*
G01X1604930Y277185D02*
X1589412Y292703D01*
G01X1604930Y276133D02*
Y277185D01*
G01X1615631Y265432D02*
X1604930Y276133D01*
G01X1615631Y239588D02*
Y265432D01*
G01X1614824Y238781D02*
X1615631Y239588D01*
G01X1614824Y221371D02*
Y238781D01*
G01X1592950Y233278D02*
Y222484D01*
G01X1591865Y234363D02*
X1592950Y233278D01*
G01X1591865Y237407D02*
Y234363D01*
G01X1601788Y246211D02*
X1601180Y245603D01*
G01X1601788Y251120D02*
Y246211D01*
G01X1602716Y252048D02*
X1601788Y251120D01*
G01X1602716Y259132D02*
Y252048D01*
G01X1600567Y261281D02*
X1602716Y259132D01*
G01X1600552Y261281D02*
X1600567D01*
G01X1632876Y268427D02*
Y282043D01*
G01X1634201Y267102D02*
X1632876Y268427D01*
G01X1634201Y252195D02*
Y267102D01*
G01X1635010Y251386D02*
X1634201Y252195D01*
G01X1635010Y243854D02*
Y251386D01*
G01X1635580Y243284D02*
X1635010Y243854D01*
G01X1635580Y237114D02*
Y243284D01*
G01X1635010Y236544D02*
X1635580Y237114D01*
G01X1635010Y231804D02*
Y236544D01*
G01X1647253Y219561D02*
X1635010Y231804D01*
G01X1653922Y219561D02*
X1647253D01*
G01X1646990Y220893D02*
X1653654D01*
G01X1635762Y232121D02*
X1646990Y220893D01*
G01X1635762Y236232D02*
Y232121D01*
G01X1636332Y236802D02*
X1635762Y236232D01*
G01X1636332Y243596D02*
Y236802D01*
G01X1635762Y244166D02*
X1636332Y243596D01*
G01X1635762Y251698D02*
Y244166D01*
G01X1634953Y252507D02*
X1635762Y251698D01*
G01X1634953Y266790D02*
Y252507D01*
G01X1634954Y266791D02*
X1634953Y266790D01*
G01X1634954Y267413D02*
Y266791D01*
G01X1633628Y268739D02*
X1634954Y267413D01*
G01X1633628Y282355D02*
Y268739D01*
G01X1608631Y242995D02*
X1609051Y243415D01*
G01X1608631Y218778D02*
Y242995D01*
G01X1609033Y218376D02*
X1608631Y218778D01*
G01X1626408Y252771D02*
X1627024Y253387D01*
G01X1626408Y246072D02*
Y252771D01*
G01X1631068Y241412D02*
X1626408Y246072D01*
G01X1631068Y238986D02*
Y241412D01*
G01X1630450Y238368D02*
X1631068Y238986D01*
G01X1630450Y224921D02*
Y238368D01*
G01X1631475Y223896D02*
X1630450Y224921D01*
G01X1633222Y223896D02*
X1631475D01*
G01X1602674Y275197D02*
Y276249D01*
G01X1613375Y264496D02*
X1602674Y275197D01*
G01X1613375Y240524D02*
Y264496D01*
G01X1612568Y239717D02*
X1613375Y240524D01*
G01X1612568Y220435D02*
Y239717D01*
G01X1628962Y275538D02*
X1623000Y281500D01*
G01X1628962Y267373D02*
Y275538D01*
G01X1629657Y266678D02*
X1628962Y267373D01*
G01X1629657Y266674D02*
Y266678D01*
G01X1631193Y265138D02*
X1629657Y266674D01*
G01X1631193Y250947D02*
Y265138D01*
G01X1632002Y250138D02*
X1631193Y250947D01*
G01X1632002Y242606D02*
Y250138D01*
G01X1632572Y242036D02*
X1632002Y242606D01*
G01X1632572Y238362D02*
Y242036D01*
G01X1632002Y237792D02*
X1632572Y238362D01*
G01X1632002Y230133D02*
Y237792D01*
G01X1634457Y227678D02*
X1632002Y230133D01*
G01X1634457Y227056D02*
Y227678D01*
G01X1634456Y227055D02*
X1634457Y227056D01*
G01X1634456Y224790D02*
Y227055D01*
G01X1631240Y226360D02*
X1632128Y225472D01*
G01X1631240Y238094D02*
Y226360D01*
G01X1631820Y238674D02*
X1631240Y238094D01*
G01X1631820Y241724D02*
Y238674D01*
G01X1631240Y242304D02*
X1631820Y241724D01*
G01X1631240Y246591D02*
Y242304D01*
G01X1628619Y249212D02*
X1631240Y246591D01*
G01X1628619Y257553D02*
Y249212D01*
G01X1627696Y258476D02*
X1628619Y257553D01*
G01X1626637Y258476D02*
X1627696D01*
G01X1625602Y259511D02*
X1626637Y258476D01*
G01X1625602Y259613D02*
Y259511D01*
G01X1625601Y259614D02*
X1625602Y259613D01*
G01X1625601Y260920D02*
Y259614D01*
G01X1625602Y260921D02*
X1625601Y260920D01*
G01X1625602Y261498D02*
Y260921D01*
G01X1625601Y261499D02*
X1625602Y261498D01*
G01X1625601Y261740D02*
Y261499D01*
G01X1623909Y263432D02*
X1625601Y261740D01*
G01X1623909Y268910D02*
Y263432D01*
G01X1621514Y271305D02*
X1623909Y268910D01*
G01X1621514Y275226D02*
Y271305D01*
G01X1617913Y278827D02*
X1621514Y275226D01*
G01X1615397Y278827D02*
X1617913D01*
G01X1597502Y296722D02*
X1615397Y278827D01*
G01X1614072Y239093D02*
Y221059D01*
G01X1614879Y239900D02*
X1614072Y239093D01*
G01X1614879Y265120D02*
Y239900D01*
G01X1604178Y275821D02*
X1614879Y265120D01*
G01X1604178Y276873D02*
Y275821D01*
G01X1598999Y265218D02*
Y275668D01*
G01X1600043Y264174D02*
X1598999Y265218D01*
G01X1601714Y264174D02*
X1600043D01*
G01X1604966Y260922D02*
X1601714Y264174D01*
G01X1604966Y245578D02*
Y260922D01*
G01X1603387Y243995D02*
X1604966Y245578D01*
G01X1603387Y218205D02*
Y243995D01*
G01X1589592Y252472D02*
Y250925D01*
G01X1603426Y275509D02*
Y276561D01*
G01X1614127Y264808D02*
X1603426Y275509D01*
G01X1614127Y240212D02*
Y264808D01*
G01X1613320Y239405D02*
X1614127Y240212D01*
G01X1613320Y220747D02*
Y239405D01*
G01X1635705Y262857D02*
X1637269Y264421D01*
G01X1635705Y252819D02*
Y262857D01*
G01X1636514Y252010D02*
X1635705Y252819D01*
G01X1636514Y244478D02*
Y252010D01*
G01X1637084Y243908D02*
X1636514Y244478D01*
G01X1637084Y236490D02*
Y243908D01*
G01X1636514Y235920D02*
X1637084Y236490D01*
G01X1636514Y232433D02*
Y235920D01*
G01X1647158Y221789D02*
X1636514Y232433D01*
G01X1653822Y221789D02*
X1647158D01*
G01X1634380Y269059D02*
Y282667D01*
G01X1635993Y267446D02*
X1634380Y269059D01*
G01X1635993Y265697D02*
Y267446D01*
G01X1637269Y264421D02*
X1635993Y265697D01*
G01X1596750Y308974D02*
Y295733D01*
G01X1598730Y310954D02*
X1596750Y308974D01*
G01X1598730Y334632D02*
Y310954D01*
G01X1596227Y337135D02*
X1598730Y334632D01*
G01X1596227Y337665D02*
Y337135D01*
G01X1628985Y284485D02*
X1628000Y283500D01*
G01X1628985Y309139D02*
Y284485D01*
G01X1609172Y328952D02*
X1628985Y309139D01*
G01X1609172Y339630D02*
Y328952D01*
G01X1596942Y310230D02*
Y333019D01*
G01X1595998Y309286D02*
X1596942Y310230D01*
G01X1595998Y295421D02*
Y309286D01*
G01X1594686Y313686D02*
Y323266D01*
G01X1593742Y312742D02*
X1594686Y313686D01*
G01X1593742Y294485D02*
Y312742D01*
G01X1592334Y313326D02*
Y293901D01*
G01X1593196Y314188D02*
X1592334Y313326D01*
G01X1593196Y316662D02*
Y314188D01*
G01X1591449Y318409D02*
X1593196Y316662D01*
G01X1591393Y318409D02*
X1591449D01*
G01X1589374Y320428D02*
X1591393Y318409D01*
G01X1628000Y285500D02*
X1627000Y284500D01*
G01X1628000Y308500D02*
Y285500D01*
G01X1603752Y332748D02*
X1628000Y308500D01*
G01X1603752Y338713D02*
Y332748D01*
G01X1597857Y344608D02*
X1603752Y338713D01*
G01X1595438Y310854D02*
Y323578D01*
G01X1594494Y309910D02*
X1595438Y310854D01*
G01X1594494Y294797D02*
Y309910D01*
G01X1590865Y317001D02*
X1590809D01*
G01X1591788Y316078D02*
X1590865Y317001D01*
G01X1591788Y314772D02*
Y316078D01*
G01X1590916Y313900D02*
X1591788Y314772D01*
G01X1590916Y293327D02*
Y313900D01*
G01X1595246Y309598D02*
Y295109D01*
G01X1596190Y310542D02*
X1595246Y309598D01*
G01X1596190Y331524D02*
Y310542D01*
G01X1612357Y338698D02*
X1609258Y341797D01*
G01X1612357Y326831D02*
Y338698D01*
G01X1629737Y309451D02*
X1612357Y326831D01*
G01X1629737Y282737D02*
Y309451D01*
G01X1629000Y282000D02*
X1629737Y282737D01*
G01X1629000Y279999D02*
Y282000D01*
G01X1590164Y310973D02*
Y293015D01*
G01X1589412Y292703D02*
Y309917D01*
G01X1625400Y314856D02*
Y327667D01*
G01X1627874Y312382D02*
X1625400Y314856D01*
G01X1627874Y312378D02*
Y312382D01*
G01X1630489Y309763D02*
X1627874Y312378D01*
G01X1630489Y284430D02*
Y309763D01*
G01X1632876Y282043D02*
X1630489Y284430D01*
G01X1631241Y284742D02*
X1633628Y282355D01*
G01X1631241Y310075D02*
Y284742D01*
G01X1628626Y312690D02*
X1631241Y310075D01*
G01X1628626Y312694D02*
Y312690D01*
G01X1627079Y314241D02*
X1628626Y312694D01*
G01X1627079Y328217D02*
Y314241D01*
G01X1626053Y329243D02*
X1627079Y328217D01*
G01X1619213Y329243D02*
X1626053D01*
G01X1615144Y333312D02*
X1619213Y329243D01*
G01X1615144Y337541D02*
Y333312D01*
G01X1608850Y343835D02*
X1615144Y337541D01*
G01X1601200Y338279D02*
X1596090Y343389D01*
G01X1601200Y311296D02*
Y338279D01*
G01X1598254Y308350D02*
X1601200Y311296D01*
G01X1598254Y297034D02*
Y308350D01*
G01X1613788Y281500D02*
X1598254Y297034D01*
G01X1623000Y281500D02*
X1613788D01*
G01X1597502Y308662D02*
Y296722D01*
G01X1599482Y310642D02*
X1597502Y308662D01*
G01X1599482Y336317D02*
Y310642D01*
G01X1616317Y339205D02*
X1609711Y345811D01*
G01X1616317Y333203D02*
Y339205D01*
G01X1619525Y329995D02*
X1616317Y333203D01*
G01X1627194Y329995D02*
X1619525D01*
G01X1627946Y329243D02*
X1627194Y329995D01*
G01X1627946Y314438D02*
Y329243D01*
G01X1629378Y313006D02*
X1627946Y314438D01*
G01X1629378Y313002D02*
Y313006D01*
G01X1631993Y310387D02*
X1629378Y313002D01*
G01X1631993Y285054D02*
Y310387D01*
G01X1634380Y282667D02*
X1631993Y285054D01*
G01X1637786Y385199D02*
Y420779D01*
G01X1645489Y377496D02*
X1637786Y385199D01*
G01X1647567Y377496D02*
X1645489D01*
G01X1657361Y367702D02*
X1647567Y377496D01*
G01X1644932Y375992D02*
X1655837Y365087D01*
G01X1644865Y375992D02*
X1644932D01*
G01X1636200Y384657D02*
X1644865Y375992D01*
G01X1636200Y411100D02*
Y384657D01*
G01X1597857Y354847D02*
Y344608D01*
G01X1601285Y349033D02*
Y352545D01*
G01X1608521Y341797D02*
X1601285Y349033D01*
G01X1609258Y341797D02*
X1608521D01*
G01X1637034Y384887D02*
Y421091D01*
G01X1645177Y376744D02*
X1637034Y384887D01*
G01X1647255Y376744D02*
X1645177D01*
G01X1656609Y367390D02*
X1647255Y376744D01*
G01X1596090Y351082D02*
X1590537Y356635D01*
G01X1596090Y343389D02*
Y351082D01*
G01X1640290Y388710D02*
X1659865Y369135D01*
G01X1640290Y419741D02*
Y388710D01*
G01X1602127Y349818D02*
Y352767D01*
G01X1606134Y345811D02*
X1602127Y349818D01*
G01X1609711Y345811D02*
X1606134D01*
G01X1648481Y378748D02*
X1658613Y368616D01*
G01X1646008Y378748D02*
X1648481D01*
G01X1639038Y385718D02*
X1646008Y378748D01*
G01X1639038Y420260D02*
Y385718D01*
G01X1592839Y453710D02*
X1590349D01*
G01X1596718Y449831D02*
X1592839Y453710D01*
G01X1612367Y449831D02*
X1596718D01*
G01X1612368Y449832D02*
X1612367Y449831D01*
G01X1612990Y449832D02*
X1612368D01*
G01X1615263Y447559D02*
X1612990Y449832D01*
G01X1615263Y444163D02*
Y447559D01*
G01X1617326Y442100D02*
X1615263Y444163D01*
G01X1632017Y442100D02*
X1617326D01*
G01X1637723Y447806D02*
X1632017Y442100D01*
G01X1640858Y447806D02*
X1637723D01*
G01X1643057Y445607D02*
X1640858Y447806D01*
G01X1643057Y437267D02*
Y445607D01*
G01X1643120Y437204D02*
X1643057Y437267D01*
G01X1643120Y426113D02*
Y437204D01*
G01X1637786Y420779D02*
X1643120Y426113D01*
G01X1613718Y464500D02*
X1615061Y463157D01*
G01X1611250Y464500D02*
X1613718D01*
G01X1607883Y467867D02*
X1611250Y464500D01*
G01X1602477Y461968D02*
X1597801Y466644D01*
G01X1606372Y461968D02*
X1602477D01*
G01X1607885Y463481D02*
X1606372Y461968D01*
G01X1612419Y463481D02*
X1607885D01*
G01X1614530Y461370D02*
X1612419Y463481D01*
G01X1618070Y461370D02*
X1614530D01*
G01X1621000Y458440D02*
X1618070Y461370D01*
G01X1621000Y452000D02*
Y458440D01*
G01X1638600Y435700D02*
X1639500D01*
G01X1633650Y430750D02*
X1638600Y435700D01*
G01X1620394Y430750D02*
X1633650D01*
G01X1613316Y437828D02*
X1620394Y430750D01*
G01X1612302Y437828D02*
X1613316D01*
G01X1611902Y438228D02*
X1612302Y437828D01*
G01X1596204Y438228D02*
X1611902D01*
G01X1596120Y438144D02*
X1596204Y438228D01*
G01X1628100Y449900D02*
X1630300Y452100D01*
G01X1619901Y449900D02*
X1628100D01*
G01X1617190Y452611D02*
X1619901Y449900D01*
G01X1617190Y459160D02*
Y452611D01*
G01X1616050Y460300D02*
X1617190Y459160D01*
G01X1602700Y460300D02*
X1616050D01*
G01X1597800Y465200D02*
X1602700Y460300D01*
G01X1634400Y412900D02*
X1636200Y411100D01*
G01X1634162Y458800D02*
X1639822Y453140D01*
G01X1626050Y458800D02*
X1634162D01*
G01X1624700Y460150D02*
X1626050Y458800D01*
G01X1596682Y437076D02*
X1596598Y436992D01*
G01X1613004Y437076D02*
X1596682D01*
G01X1620180Y429900D02*
X1613004Y437076D01*
G01X1640185Y429900D02*
X1620180D01*
G01X1640625Y429460D02*
X1640185Y429900D01*
G01X1601086Y428976D02*
X1595055Y435007D01*
G01X1602899Y428976D02*
X1601086D01*
G01X1605828Y426047D02*
X1602899Y428976D01*
G01X1613207Y426047D02*
X1605828D01*
G01X1621552Y417702D02*
X1613207Y426047D01*
G01X1628753Y417702D02*
X1621552D01*
G01X1629938Y418887D02*
X1628753Y417702D01*
G01X1630120Y418887D02*
X1629938D01*
G01X1642368Y436892D02*
X1639774Y439486D01*
G01X1642368Y426425D02*
Y436892D01*
G01X1637034Y421091D02*
X1642368Y426425D01*
G01X1594399Y449079D02*
X1591344Y452134D01*
G01X1612679Y449079D02*
X1594399D01*
G01X1614511Y447247D02*
X1612679Y449079D01*
G01X1614511Y443851D02*
Y447247D01*
G01X1619438Y438924D02*
X1614511Y443851D01*
G01X1630134Y438924D02*
X1619438D01*
G01X1638264Y447054D02*
X1630134Y438924D01*
G01X1640546Y447054D02*
X1638264D01*
G01X1641326Y446274D02*
X1640546Y447054D01*
G01X1641326Y441038D02*
Y446274D01*
G01X1639774Y439486D02*
X1641326Y441038D01*
G01X1600600Y457900D02*
X1591279D01*
G01X1602050Y456450D02*
X1600600Y457900D01*
G01X1612251Y456450D02*
X1602050D01*
G01X1619601Y449100D02*
X1612251Y456450D01*
G01X1629859Y449100D02*
X1619601D01*
G01X1630276Y449517D02*
X1629859Y449100D01*
G01X1645624Y425075D02*
X1640290Y419741D01*
G01X1645624Y436307D02*
Y425075D01*
G01X1645625Y436308D02*
X1645624Y436307D01*
G01X1645625Y437215D02*
Y436308D01*
G01X1648340Y439930D02*
X1645625Y437215D01*
G01X1648340Y452930D02*
Y439930D01*
G01X1647104Y454166D02*
X1648340Y452930D01*
G01X1643415Y454166D02*
X1647104D01*
G01X1640644Y451395D02*
X1643415Y454166D01*
G01X1636395Y451395D02*
X1640644D01*
G01X1632941Y447941D02*
X1636395Y451395D01*
G01X1618659Y447941D02*
X1632941D01*
G01X1613880Y452720D02*
X1618659Y447941D01*
G01X1604428Y452720D02*
X1613880D01*
G01X1600072Y457076D02*
X1604428Y452720D01*
G01X1592085Y457076D02*
X1600072D01*
G01X1592139Y430939D02*
X1593400Y432200D01*
G01X1644372Y425594D02*
X1639038Y420260D01*
G01X1644372Y436826D02*
Y425594D01*
G01X1644373Y436827D02*
X1644372Y436826D01*
G01X1644373Y438133D02*
Y436827D01*
G01X1644309Y438197D02*
X1644373Y438133D01*
G01X1644309Y446596D02*
Y438197D01*
G01X1641446Y449459D02*
X1644309Y446596D01*
G01X1640410Y449459D02*
X1641446D01*
G01X1640409Y449458D02*
X1640410Y449459D01*
G01X1636458Y449458D02*
X1640409D01*
G01X1631424Y444424D02*
X1636458Y449458D01*
G01X1625676Y444424D02*
X1631424D01*
G01X1623500Y446600D02*
X1625676Y444424D01*
G01X1621881Y446600D02*
X1623500D01*
G01X1621879Y446602D02*
X1621881Y446600D01*
G01X1620573Y446602D02*
X1621879D01*
G01X1620571Y446600D02*
X1620573Y446602D01*
G01X1617993Y446600D02*
X1620571D01*
G01X1613466Y451127D02*
X1617993Y446600D01*
G01X1600873Y451127D02*
X1613466D01*
G01X1596500Y455500D02*
X1600873Y451127D01*
G01X1647507Y497225D02*
X1670465Y520183D01*
G01X1647507Y493708D02*
Y497225D01*
G01X1644656Y490857D02*
X1647507Y493708D01*
G01X1644656Y489123D02*
Y490857D01*
G01X1635175Y479642D02*
X1644656Y489123D01*
G01X1635175Y472163D02*
Y479642D01*
G01X1633186Y470174D02*
X1635175Y472163D01*
G01X1633075Y470174D02*
X1633186D01*
G01X1644372Y478357D02*
X1663125Y459604D01*
G01X1644372Y485460D02*
Y478357D01*
G01X1647016Y488104D02*
X1644372Y485460D01*
G01X1647016Y491182D02*
Y488104D01*
G01X1648915Y493081D02*
X1647016Y491182D01*
G01X1648915Y496641D02*
Y493081D01*
G01X1670995Y518721D02*
X1648915Y496641D01*
G01X1646099Y497809D02*
X1669882Y521592D01*
G01X1646099Y494292D02*
Y497809D01*
G01X1643630Y491823D02*
X1646099Y494292D01*
G01X1642144Y491823D02*
X1643630D01*
G01X1641104Y490783D02*
X1642144Y491823D01*
G01X1641104Y490456D02*
Y490783D01*
G01X1640007Y489359D02*
X1641104Y490456D01*
G01X1639868Y489359D02*
X1640007D01*
G01X1633359Y482850D02*
X1639868Y489359D01*
G01X1633359Y472859D02*
Y482850D01*
G01X1647381Y525865D02*
Y542139D01*
G01X1636892Y515376D02*
X1647381Y525865D01*
G01X1636892Y515157D02*
Y515376D01*
G01X1635961Y514226D02*
X1636892Y515157D01*
G01X1635961Y511755D02*
Y514226D01*
G01X1635929Y511723D02*
X1635961Y511755D01*
G01X1635929Y494477D02*
Y511723D01*
G01X1639271Y491135D02*
X1635929Y494477D01*
G01X1648330Y505064D02*
Y504544D01*
G01X1666266Y523000D02*
X1648330Y505064D01*
G01X1641016Y506857D02*
X1641470Y506403D01*
G01X1641016Y515516D02*
Y506857D01*
G01X1667297Y541797D02*
X1641016Y515516D01*
G01X1641963Y497772D02*
Y495964D01*
G01X1646604Y502413D02*
X1641963Y497772D01*
G01X1646604Y510999D02*
Y502413D01*
G01X1648683Y513078D02*
X1646604Y510999D01*
G01X1649661Y513078D02*
X1648683D01*
G01X1673380Y536797D02*
X1649661Y513078D01*
G01X1645969Y517050D02*
Y514870D01*
G01X1668020Y539101D02*
X1645969Y517050D01*
G01X1608817Y468619D02*
X1611636Y465800D01*
G01X1643084Y500705D02*
X1639113Y496734D01*
G01X1643084Y504838D02*
Y500705D01*
G01X1643075Y504847D02*
X1643084Y504838D01*
G01X1643075Y506153D02*
Y504847D01*
G01X1643084Y506162D02*
X1643075Y506153D01*
G01X1643084Y507942D02*
Y506162D01*
G01X1643047Y507979D02*
X1643084Y507942D01*
G01X1643047Y512355D02*
Y507979D01*
G01X1644297Y513605D02*
X1643047Y512355D01*
G01X1644297Y517008D02*
Y513605D01*
G01X1667722Y540433D02*
X1644297Y517008D01*
G01X1649226Y475631D02*
X1665584Y459273D01*
G01X1649226Y491264D02*
Y475631D01*
G01X1650419Y492457D02*
X1649226Y491264D01*
G01X1650419Y496017D02*
Y492457D01*
G01X1671619Y517217D02*
X1650419Y496017D01*
G01X1644651Y510676D02*
Y505500D01*
G01X1647859Y513884D02*
X1644651Y510676D01*
G01X1647859Y517310D02*
Y513884D01*
G01X1664194Y533645D02*
X1647859Y517310D01*
G01X1644691Y498393D02*
X1650944Y504646D01*
G01X1644691Y494876D02*
Y498393D01*
G01X1643115Y493300D02*
X1644691Y494876D01*
G01X1640035Y493300D02*
X1643115D01*
G01X1637337Y495998D02*
X1640035Y493300D01*
G01X1637337Y511139D02*
Y495998D01*
G01X1637369Y511171D02*
X1637337Y511139D01*
G01X1637369Y513642D02*
Y511171D01*
G01X1638300Y514573D02*
X1637369Y513642D01*
G01X1638300Y514792D02*
Y514573D01*
G01X1665889Y542381D02*
X1638300Y514792D01*
G01X1650178Y476026D02*
X1666536Y459668D01*
G01X1650178Y490869D02*
Y476026D01*
G01X1651371Y492062D02*
X1650178Y490869D01*
G01X1645124Y478669D02*
X1664161Y459632D01*
G01X1645124Y485148D02*
Y478669D01*
G01X1647768Y487792D02*
X1645124Y485148D01*
G01X1647768Y490870D02*
Y487792D01*
G01X1649667Y492769D02*
X1647768Y490870D01*
G01X1649667Y496329D02*
Y492769D01*
G01X1671307Y517969D02*
X1649667Y496329D01*
G01X1649715Y511502D02*
X1673791Y535578D01*
G01X1649336Y511502D02*
X1649715D01*
G01X1647381Y542139D02*
X1658542Y553300D01*
G01X1622126Y619726D02*
X1689840D01*
G01X1619700Y617300D02*
X1622126Y619726D01*
G01X1621531Y620478D02*
X1690152D01*
G01X1620853Y619800D02*
X1621531Y620478D01*
G01X1617600Y619800D02*
X1620853D01*
G01X1601300Y623550D02*
X1594828Y617078D01*
G01X1690750Y623550D02*
X1601300D01*
G01X1591002Y624402D02*
X1692722D01*
G01X1625976Y618974D02*
X1660555D01*
G01X1616460Y609458D02*
X1625976Y618974D01*
G01X1607925Y609458D02*
X1616460D01*
G01X1607914Y609460D02*
X1607925Y609458D01*
G01X1603470Y613904D02*
X1607914Y609460D01*
G01X1588933Y613904D02*
X1603470D01*
G01X1649566Y617566D02*
X1659971D01*
G01X1639473Y607473D02*
X1649566Y617566D01*
G01X1616818Y607473D02*
X1639473D01*
G01X1616243Y608048D02*
X1616818Y607473D01*
G01X1615880Y608050D02*
X1616243Y608048D01*
G01X1607341Y608050D02*
X1615880D01*
G01X1607330Y608052D02*
X1607341Y608050D01*
G01X1602886Y612496D02*
X1607330Y608052D01*
G01X1601414Y612496D02*
X1602886D01*
G01X1598282Y609364D02*
X1601414Y612496D01*
G01X1591786Y609364D02*
X1598282D01*
G01X1590530Y610620D02*
X1591786Y609364D01*
G01X1601695Y622598D02*
X1690355D01*
G01X1595223Y616126D02*
X1601695Y622598D01*
G01X1680033Y-16711D02*
X1675098Y-21646D01*
G01X1673104Y-20494D02*
X1676819Y-16779D01*
G01X1710753Y81720D02*
X1714223Y85190D01*
G01X1706702Y81720D02*
X1710753D01*
G01X1704466Y83956D02*
X1706702Y81720D01*
G01X1683891Y83956D02*
X1704466D01*
G01X1679043Y79108D02*
X1683891Y83956D01*
G01X1661485Y79108D02*
X1679043D01*
G01X1661230Y79363D02*
X1661485Y79108D01*
G01X1659180Y79363D02*
X1661230D01*
G01X1655541Y83002D02*
X1659180Y79363D01*
G01X1710441Y82472D02*
X1713911Y85942D01*
G01X1707014Y82472D02*
X1710441D01*
G01X1700836Y88650D02*
X1707014Y82472D01*
G01X1687500Y88650D02*
X1700836D01*
G01X1678710Y79860D02*
X1687500Y88650D01*
G01X1661797Y79860D02*
X1678710D01*
G01X1661542Y80115D02*
X1661797Y79860D01*
G01X1659492Y80115D02*
X1661542D01*
G01X1654807Y84800D02*
X1659492Y80115D01*
G01X1711250Y94300D02*
X1742237D01*
G01X1704150Y101400D02*
X1711250Y94300D01*
G01X1678470Y73070D02*
X1679900Y74500D01*
G01X1669045Y73070D02*
X1678470D01*
G01X1666590Y75525D02*
X1669045Y73070D01*
G01X1660842Y75525D02*
X1666590D01*
G01X1660387Y75980D02*
X1660842Y75525D01*
G01X1711688Y79463D02*
X1715159Y82934D01*
G01X1705400Y79463D02*
X1711688D01*
G01X1703163Y81700D02*
X1705400Y79463D01*
G01X1684827Y81700D02*
X1703163D01*
G01X1679979Y76852D02*
X1684827Y81700D01*
G01X1660549Y76852D02*
X1679979D01*
G01X1660294Y77107D02*
X1660549Y76852D01*
G01X1658244Y77107D02*
X1660294D01*
G01X1654849Y80502D02*
X1658244Y77107D01*
G01X1666999Y82601D02*
X1668000Y81600D01*
G01X1666999Y82999D02*
Y82601D01*
G01X1659498Y90500D02*
X1666999Y82999D01*
G01X1711376Y80215D02*
X1714847Y83686D01*
G01X1706079Y80215D02*
X1711376D01*
G01X1703842Y82452D02*
X1706079Y80215D01*
G01X1684515Y82452D02*
X1703842D01*
G01X1679667Y77604D02*
X1684515Y82452D01*
G01X1660861Y77604D02*
X1679667D01*
G01X1660606Y77859D02*
X1660861Y77604D01*
G01X1658556Y77859D02*
X1660606D01*
G01X1655160Y81255D02*
X1658556Y77859D01*
G01X1654538Y81255D02*
X1655160D01*
G01X1654537Y81254D02*
X1654538Y81255D01*
G01X1685394Y92506D02*
X1681975Y95925D01*
G01X1702211Y92506D02*
X1685394D01*
G01X1702882Y93177D02*
X1702211Y92506D01*
G01X1706196Y93177D02*
X1702882D01*
G01X1708875Y90498D02*
X1706196Y93177D01*
G01X1708875Y89056D02*
Y90498D01*
G01X1709152Y88779D02*
X1708875Y89056D01*
G01X1709152Y88811D02*
Y88779D01*
G01X1709184Y88811D02*
X1709152D01*
G01X1710600Y92200D02*
X1706123Y96677D01*
G01X1710600Y89967D02*
Y92200D01*
G01X1710826Y89741D02*
X1710600Y89967D01*
G01X1710826Y88435D02*
Y89741D01*
G01X1710728Y88337D02*
X1710826Y88435D01*
G01X1710728Y88126D02*
Y88337D01*
G01X1710600Y87998D02*
X1710728Y88126D01*
G01X1710600Y87111D02*
Y87998D01*
G01X1708610Y85121D02*
X1710600Y87111D01*
G01X1711352Y87581D02*
X1715911Y92140D01*
G01X1711352Y85634D02*
Y87581D01*
G01X1709263Y83545D02*
X1711352Y85634D01*
G01X1707957Y83545D02*
X1709263D01*
G01X1707000Y84502D02*
X1707957Y83545D01*
G01X1707000Y87914D02*
Y84502D01*
G01X1706969Y87945D02*
X1707000Y87914D01*
G01X1706969Y89417D02*
Y87945D01*
G01X1707000Y89448D02*
X1706969Y89417D01*
G01X1707000Y90102D02*
Y89448D01*
G01X1705477Y91625D02*
X1707000Y90102D01*
G01X1703525Y91625D02*
X1705477D01*
G01X1702854Y90954D02*
X1703525Y91625D01*
G01X1682740Y90954D02*
X1702854D01*
G01X1679321Y94373D02*
X1682740Y90954D01*
G01X1678926Y94373D02*
X1679321D01*
G01X1677697Y95602D02*
X1678926Y94373D01*
G01X1668725Y71566D02*
X1665545Y68386D01*
G01X1681380Y71566D02*
X1668725D01*
G01X1683320Y71975D02*
X1681380Y71566D01*
G01X1684249Y72171D02*
X1683320Y71975D01*
G01X1688154Y76076D02*
X1684249Y72171D01*
G01X1691124Y76076D02*
X1688154D01*
G01X1693900Y73300D02*
X1691124Y76076D01*
G01X1672740Y91543D02*
X1667197Y97086D01*
G01X1672740Y86716D02*
Y91543D01*
G01X1677856Y81600D02*
X1672740Y86716D01*
G01X1678000Y81600D02*
X1677856D01*
G01X1704521Y89746D02*
X1704824Y90049D01*
G01X1701370Y89746D02*
X1704521D01*
G01X1701314Y89802D02*
X1701370Y89746D01*
G01X1681498Y89802D02*
X1701314D01*
G01X1675922Y95378D02*
X1681498Y89802D01*
G01X1711996Y77779D02*
X1715743Y81526D01*
G01X1709891Y77779D02*
X1711996D01*
G01X1708004Y75892D02*
X1709891Y77779D01*
G01X1699308Y75892D02*
X1708004D01*
G01X1697209Y77991D02*
X1699308Y75892D01*
G01X1696655Y77991D02*
X1697209D01*
G01X1676844Y74646D02*
X1676428D01*
G01X1678274Y76076D02*
X1676844Y74646D01*
G01X1682893Y76076D02*
X1678274D01*
G01X1683972Y74997D02*
X1682893Y76076D01*
G01X1683972Y73691D02*
Y74997D01*
G01X1682946Y72665D02*
X1683972Y73691D01*
G01X1681301Y72318D02*
X1682946Y72665D01*
G01X1667755Y72318D02*
X1681301D01*
G01X1665899Y74174D02*
X1667755Y72318D01*
G01X1660769Y74174D02*
X1665899D01*
G01X1659715Y75228D02*
X1660769Y74174D01*
G01X1666300Y92538D02*
Y101000D01*
G01X1666298Y92536D02*
X1666300Y92538D01*
G01X1666298Y91038D02*
Y92536D01*
G01X1668645Y88691D02*
X1666298Y91038D01*
G01X1668645Y83455D02*
Y88691D01*
G01X1670500Y81600D02*
X1668645Y83455D01*
G01X1711065Y80968D02*
X1714535Y84438D01*
G01X1707014Y80968D02*
X1711065D01*
G01X1707013Y80967D02*
X1707014Y80968D01*
G01X1706391Y80967D02*
X1707013D01*
G01X1704154Y83204D02*
X1706391Y80967D01*
G01X1684203Y83204D02*
X1704154D01*
G01X1679355Y78356D02*
X1684203Y83204D01*
G01X1661173Y78356D02*
X1679355D01*
G01X1660918Y78611D02*
X1661173Y78356D01*
G01X1658868Y78611D02*
X1660918D01*
G01X1655229Y82250D02*
X1658868Y78611D01*
G01X1652351Y103000D02*
X1653111Y102240D01*
G01X1654685Y111765D02*
Y112341D01*
G01X1656162Y110288D02*
X1654685Y111765D01*
G01X1656162Y107338D02*
Y110288D01*
G01X1664500Y99000D02*
X1656162Y107338D01*
G01X1684209Y101400D02*
X1704150D01*
G01X1681882Y99073D02*
X1684209Y101400D01*
G01X1680139Y99073D02*
X1681882D01*
G01X1656161Y148991D02*
Y158162D01*
G01X1655640Y148470D02*
X1656161Y148991D01*
G01X1673775Y117628D02*
X1668038Y123365D01*
G01X1673775Y110552D02*
Y117628D01*
G01X1672666Y109443D02*
X1673775Y110552D01*
G01X1672666Y102381D02*
Y109443D01*
G01X1673736Y101311D02*
X1672666Y102381D01*
G01X1674500Y101311D02*
X1673736D01*
G01X1675624Y100187D02*
X1674500Y101311D01*
G01X1675624Y99871D02*
Y100187D01*
G01X1678497Y96998D02*
X1675624Y99871D01*
G01X1678497Y96997D02*
Y96998D01*
G01X1679569Y95925D02*
X1678497Y96997D01*
G01X1681975Y95925D02*
X1679569D01*
G01X1659480Y146200D02*
Y160292D01*
G01X1658750Y145470D02*
X1659480Y146200D01*
G01X1676365Y117776D02*
X1667607Y126534D01*
G01X1676365Y103763D02*
Y117776D01*
G01X1676375Y103753D02*
X1676365Y103763D01*
G01X1676375Y100183D02*
Y103753D01*
G01X1679881Y96677D02*
X1676375Y100183D01*
G01X1706123Y96677D02*
X1679881D01*
G01X1677697Y95997D02*
Y95602D01*
G01X1676696Y96998D02*
X1677697Y95997D01*
G01X1674363Y96998D02*
X1676696D01*
G01X1669363Y101998D02*
X1674363Y96998D01*
G01X1669363Y111461D02*
Y101998D01*
G01X1668844Y111980D02*
X1669363Y111461D01*
G01X1668844Y119012D02*
Y111980D01*
G01X1667680Y120176D02*
X1668844Y119012D01*
G01X1662660Y113816D02*
X1660985Y115491D01*
G01X1662660Y106961D02*
Y113816D01*
G01X1667197Y102424D02*
X1662660Y106961D01*
G01X1667197Y97086D02*
Y102424D01*
G01X1673812Y95378D02*
X1675922D01*
G01X1667948Y101242D02*
X1673812Y95378D01*
G01X1667948Y102736D02*
Y101242D01*
G01X1664135Y106549D02*
X1667948Y102736D01*
G01X1664135Y112341D02*
Y106549D01*
G01X1678950Y103550D02*
X1678400Y103000D01*
G01X1704900Y103550D02*
X1678950D01*
G01X1713399Y95051D02*
X1704900Y103550D01*
G01X1652146Y116966D02*
X1652012Y117100D01*
G01X1652148Y116966D02*
X1652146D01*
G01X1653011Y116103D02*
X1652148Y116966D01*
G01X1653011Y116101D02*
Y116103D01*
G01X1654191Y114921D02*
X1653011Y116101D01*
G01X1656180Y114921D02*
X1654191D01*
G01X1657139Y113962D02*
X1656180Y114921D01*
G01X1659364Y113962D02*
X1657139D01*
G01X1660985Y112341D02*
X1659364Y113962D01*
G01X1656351Y113249D02*
X1655584Y114016D01*
G01X1656351Y111581D02*
Y113249D01*
G01X1657265Y110667D02*
X1656351Y111581D01*
G01X1658447Y110667D02*
X1657265D01*
G01X1658448Y110666D02*
X1658447Y110667D01*
G01X1658626Y110666D02*
X1658448D01*
G01X1659509Y109783D02*
X1658626Y110666D01*
G01X1659509Y107791D02*
Y109783D01*
G01X1666300Y101000D02*
X1659509Y107791D01*
G01X1658274Y185440D02*
X1650841Y192873D01*
G01X1661060Y185440D02*
X1658274D01*
G01X1665970Y180530D02*
X1661060Y185440D01*
G01X1677663Y180530D02*
X1665970D01*
G01X1678127Y180066D02*
X1677663Y180530D01*
G01X1681356Y180066D02*
X1678127D01*
G01X1685200Y176222D02*
X1681356Y180066D01*
G01X1700928Y176222D02*
X1685200D01*
G01X1706213Y170937D02*
X1700928Y176222D01*
G01X1714987Y170937D02*
X1706213D01*
G01X1660985Y165885D02*
X1658387Y168483D01*
G01X1684051Y204565D02*
X1715683D01*
G01X1676972Y211644D02*
X1684051Y204565D01*
G01X1671960Y211644D02*
X1676972D01*
G01X1667993Y215611D02*
X1671960Y211644D01*
G01X1653349Y215611D02*
X1667993D01*
G01X1650903Y218057D02*
X1653349Y215611D01*
G01X1661725Y204724D02*
X1654382D01*
G01X1664390Y202059D02*
X1661725Y204724D01*
G01X1664390Y201163D02*
Y202059D01*
G01X1667140Y182772D02*
Y182300D01*
G01X1663720Y186192D02*
X1667140Y182772D01*
G01X1659819Y186192D02*
X1663720D01*
G01X1652386Y193625D02*
X1659819Y186192D01*
G01X1658903Y202326D02*
X1653325D01*
G01X1660440Y200789D02*
X1658903Y202326D01*
G01X1708567Y180567D02*
X1713000Y185000D01*
G01X1689793Y180567D02*
X1708567D01*
G01X1689400Y180960D02*
X1689793Y180567D01*
G01X1689400Y182460D02*
Y180960D01*
G01X1682470Y189390D02*
X1689400Y182460D01*
G01X1670350Y189390D02*
X1682470D01*
G01X1666272Y193468D02*
X1670350Y189390D01*
G01X1663585Y193468D02*
X1666272D01*
G01X1656783Y200270D02*
X1663585Y193468D01*
G01X1653060Y200270D02*
X1656783D01*
G01X1677578Y209974D02*
X1673530D01*
G01X1683739Y203813D02*
X1677578Y209974D01*
G01X1715371Y203813D02*
X1683739D01*
G01X1656161Y158162D02*
X1654638Y159685D01*
G01X1663450Y170995D02*
X1665063Y172608D01*
G01X1663450Y163001D02*
Y170995D01*
G01X1661746Y161297D02*
X1663450Y163001D01*
G01X1661634Y161297D02*
X1661746D01*
G01X1661597Y161260D02*
X1661634Y161297D01*
G01X1660448Y161260D02*
X1661597D01*
G01X1659480Y160292D02*
X1660448Y161260D01*
G01X1710095Y166857D02*
X1714289Y162663D01*
G01X1688157Y166857D02*
X1710095D01*
G01X1687718Y167296D02*
X1688157Y166857D01*
G01X1687512Y167296D02*
X1687718D01*
G01X1686531Y168277D02*
X1687512Y167296D01*
G01X1686531Y168483D02*
Y168277D01*
G01X1681156Y173858D02*
X1686531Y168483D01*
G01X1680550Y173858D02*
X1681156D01*
G01X1675937Y178471D02*
X1680550Y173858D01*
G01X1669254Y178471D02*
X1675937D01*
G01X1668177Y177394D02*
X1669254Y178471D01*
G01X1666380Y177394D02*
X1668177D01*
G01X1663434Y174448D02*
X1666380Y177394D01*
G01X1678859Y201557D02*
X1714435D01*
G01X1675140Y205276D02*
X1678859Y201557D01*
G01X1670019Y205276D02*
X1675140D01*
G01X1666474Y208821D02*
X1670019Y205276D01*
G01X1660173Y208821D02*
X1666474D01*
G01X1654570Y214424D02*
X1660173Y208821D01*
G01X1653235Y214424D02*
X1654570D01*
G01X1660813Y203220D02*
X1653758D01*
G01X1662062Y201971D02*
X1660813Y203220D01*
G01X1662062Y199330D02*
Y201971D01*
G01X1663587Y197805D02*
X1662062Y199330D01*
G01X1668495Y197805D02*
X1663587D01*
G01X1672770Y193530D02*
X1668495Y197805D01*
G01X1682510Y193530D02*
X1672770D01*
G01X1684182Y195202D02*
X1682510Y193530D01*
G01X1704268Y195202D02*
X1684182D01*
G01X1711722Y187748D02*
X1704268Y195202D01*
G01X1722495Y187748D02*
X1711722D01*
G01X1677527Y206050D02*
X1676750D01*
G01X1681268Y202309D02*
X1677527Y206050D01*
G01X1714747Y202309D02*
X1681268D01*
G01X1652296Y183967D02*
X1650823D01*
G01X1654502Y181761D02*
X1652296Y183967D01*
G01X1655209Y181761D02*
X1654502D01*
G01X1711606Y191460D02*
X1713565D01*
G01X1711600Y191461D02*
X1711606Y191460D01*
G01X1710302Y191461D02*
X1711600D01*
G01X1705666Y196097D02*
X1710302Y191461D01*
G01X1705666Y198055D02*
Y196097D01*
G01X1704744Y195954D02*
X1712198Y188500D01*
G01X1683864Y195954D02*
X1704744D01*
G01X1682200Y194290D02*
X1683864Y195954D01*
G01X1673310Y194290D02*
X1682200D01*
G01X1669043Y198557D02*
X1673310Y194290D01*
G01X1663899Y198557D02*
X1669043D01*
G01X1662814Y199642D02*
X1663899Y198557D01*
G01X1662814Y202283D02*
Y199642D01*
G01X1661125Y203972D02*
X1662814Y202283D01*
G01X1654070Y203972D02*
X1661125D01*
G01X1654015Y217239D02*
X1652445Y218809D01*
G01X1707149Y173193D02*
X1715923D01*
G01X1701183Y179159D02*
X1707149Y173193D01*
G01X1690377Y179159D02*
X1701183D01*
G01X1690376Y179158D02*
X1690377Y179159D01*
G01X1689210Y179158D02*
X1690376D01*
G01X1687992Y180376D02*
X1689210Y179158D01*
G01X1687992Y181658D02*
Y180376D01*
G01X1681780Y187870D02*
X1687992Y181658D01*
G01X1669878Y187870D02*
X1681780D01*
G01X1665688Y192060D02*
X1669878Y187870D01*
G01X1659091Y192060D02*
X1665688D01*
G01X1659402Y191307D02*
X1658780D01*
G01X1659403Y191308D02*
X1659402Y191307D01*
G01X1664948Y191308D02*
X1659403D01*
G01X1671146Y185110D02*
X1664948Y191308D01*
G01X1676218Y185110D02*
X1671146D01*
G01X1679758Y181570D02*
X1676218Y185110D01*
G01X1682770Y181570D02*
X1679758D01*
G01X1686416Y177924D02*
X1682770Y181570D01*
G01X1701354Y177924D02*
X1686416D01*
G01X1706837Y172441D02*
X1701354Y177924D01*
G01X1715611Y172441D02*
X1706837D01*
G01X1659050Y183600D02*
X1650529Y192121D01*
G01X1659050Y181422D02*
Y183600D01*
G01X1662846Y177626D02*
X1659050Y181422D01*
G01X1665388Y177626D02*
X1662846D01*
G01X1667498Y179736D02*
X1665388Y177626D01*
G01X1677394Y179736D02*
X1667498D01*
G01X1677816Y179314D02*
X1677394Y179736D01*
G01X1680394Y179314D02*
X1677816D01*
G01X1687005Y172703D02*
X1680394Y179314D01*
G01X1688019Y172703D02*
X1687005D01*
G01X1689515Y171207D02*
X1688019Y172703D01*
G01X1702111Y171207D02*
X1689515D01*
G01X1704898Y168420D02*
X1702111Y171207D01*
G01X1710860Y168420D02*
X1704898D01*
G01X1715152Y164128D02*
X1710860Y168420D01*
G01X1659643Y213276D02*
Y213505D01*
G01X1663211Y209708D02*
X1659643Y213276D01*
G01X1667998Y209708D02*
X1663211D01*
G01X1670903Y206803D02*
X1667998Y209708D01*
G01X1672986Y206803D02*
X1670903D01*
G01X1673914Y207731D02*
X1672986Y206803D01*
G01X1678757Y207731D02*
X1673914D01*
G01X1683427Y203061D02*
X1678757Y207731D01*
G01X1715059Y203061D02*
X1683427D01*
G01X1710403Y163103D02*
X1712307Y161199D01*
G01X1697202Y163103D02*
X1710403D01*
G01X1696865Y162766D02*
X1697202Y163103D01*
G01X1693643Y162766D02*
X1696865D01*
G01X1691467Y164942D02*
X1693643Y162766D01*
G01X1687606Y164942D02*
X1691467D01*
G01X1680098Y172450D02*
X1687606Y164942D01*
G01X1679966Y172450D02*
X1680098D01*
G01X1679175Y173241D02*
X1679966Y172450D01*
G01X1679175Y173353D02*
Y173241D01*
G01X1678253Y174275D02*
X1679175Y173353D01*
G01X1678141Y174275D02*
X1678253D01*
G01X1677841Y174575D02*
X1678141Y174275D01*
G01X1677841Y174707D02*
Y174575D01*
G01X1675040Y177508D02*
X1677841Y174707D01*
G01X1674729Y177508D02*
X1675040D01*
G01X1674672Y177565D02*
X1674729Y177508D01*
G01X1673366Y177565D02*
X1674672D01*
G01X1673309Y177508D02*
X1673366Y177565D01*
G01X1671722Y177508D02*
X1673309D01*
G01X1669700Y175486D02*
X1671722Y177508D01*
G01X1669700Y168300D02*
Y175486D01*
G01X1664201Y162801D02*
X1669700Y168300D01*
G01X1664201Y162689D02*
Y162801D01*
G01X1662057Y160545D02*
X1664201Y162689D01*
G01X1661945Y160545D02*
X1662057D01*
G01X1660985Y159585D02*
X1661945Y160545D01*
G01X1656946Y216537D02*
X1653922Y219561D01*
G01X1668131Y216537D02*
X1656946D01*
G01X1672142Y212526D02*
X1668131Y216537D01*
G01X1677154Y212526D02*
X1672142D01*
G01X1684363Y205317D02*
X1677154Y212526D01*
G01X1715995Y205317D02*
X1684363D01*
G01X1684675Y206069D02*
X1716307D01*
G01X1677466Y213278D02*
X1684675Y206069D01*
G01X1672454Y213278D02*
X1677466D01*
G01X1668427Y217305D02*
X1672454Y213278D01*
G01X1657242Y217305D02*
X1668427D01*
G01X1653654Y220893D02*
X1657242Y217305D01*
G01X1662637Y167645D02*
X1660124Y170158D01*
G01X1662637Y165238D02*
Y167645D01*
G01X1661775Y164376D02*
X1662637Y165238D01*
G01X1654239Y164376D02*
X1661775D01*
G01X1653100Y163237D02*
X1654239Y164376D01*
G01X1653100Y159002D02*
Y163237D01*
G01X1652166Y158068D02*
X1653100Y159002D01*
G01X1650846Y158068D02*
X1652166D01*
G01X1650500Y209700D02*
X1650470D01*
G01X1654600Y205600D02*
X1650500Y209700D01*
G01X1664600Y205600D02*
X1654600D01*
G01X1669130Y201070D02*
X1664600Y205600D01*
G01X1673800Y201070D02*
X1669130D01*
G01X1660345Y207317D02*
X1655188Y212474D01*
G01X1665850Y207317D02*
X1660345D01*
G01X1668643Y204524D02*
X1665850Y207317D01*
G01X1674828Y204524D02*
X1668643D01*
G01X1678547Y200805D02*
X1674828Y204524D01*
G01X1714123Y200805D02*
X1678547D01*
G01X1655031Y184505D02*
Y185675D01*
G01X1671700Y182925D02*
X1671688D01*
G01X1671700Y183492D02*
Y182925D01*
G01X1664636Y190556D02*
X1671700Y183492D01*
G01X1659715Y190556D02*
X1664636D01*
G01X1659714Y190555D02*
X1659715Y190556D01*
G01X1658468Y190555D02*
X1659714D01*
G01X1658467Y190556D02*
X1658468Y190555D01*
G01X1658373Y190556D02*
X1658467D01*
G01X1705417Y169672D02*
X1712566D01*
G01X1702630Y172459D02*
X1705417Y169672D01*
G01X1690034Y172459D02*
X1702630D01*
G01X1688046Y174447D02*
X1690034Y172459D01*
G01X1711424Y185724D02*
X1712276Y186576D01*
G01X1709247Y185724D02*
X1711424D01*
G01X1707100Y187871D02*
X1709247Y185724D01*
G01X1707100Y188300D02*
Y187871D01*
G01X1712112Y156518D02*
X1761160D01*
G01X1710130Y158500D02*
X1712112Y156518D01*
G01X1689208Y158500D02*
X1710130D01*
G01X1685046Y162662D02*
X1689208Y158500D01*
G01X1680838Y162662D02*
X1685046D01*
G01X1676030Y167470D02*
X1680838Y162662D01*
G01X1676030Y171716D02*
Y167470D01*
G01X1675088Y172658D02*
X1676030Y171716D01*
G01X1674455Y172658D02*
X1675088D01*
G01X1664100Y188100D02*
X1659700D01*
G01X1670859Y181341D02*
X1664100Y188100D01*
G01X1677915Y181341D02*
X1670859D01*
G01X1678438Y180818D02*
X1677915Y181341D01*
G01X1681668Y180818D02*
X1678438D01*
G01X1685512Y176974D02*
X1681668Y180818D01*
G01X1695074Y176974D02*
X1685512D01*
G01X1695075Y176975D02*
X1695074Y176974D01*
G01X1701239Y176975D02*
X1695075D01*
G01X1706525Y171689D02*
X1701239Y176975D01*
G01X1715299Y171689D02*
X1706525D01*
G01X1672766Y214030D02*
X1668691Y218105D01*
G01X1676530Y214030D02*
X1672766D01*
G01X1676531Y214031D02*
X1676530Y214030D01*
G01X1677777Y214031D02*
X1676531D01*
G01X1684987Y206821D02*
X1677777Y214031D01*
G01X1716619Y206821D02*
X1684987D01*
G01X1695812Y253112D02*
X1821571D01*
G01X1692176Y249476D02*
X1695812Y253112D01*
G01X1688691Y249476D02*
X1692176D01*
G01X1688451Y249716D02*
X1688691Y249476D01*
G01X1660757Y254737D02*
Y304701D01*
G01X1668287Y247207D02*
X1660757Y254737D01*
G01X1685162Y247207D02*
X1668287D01*
G01X1685481Y246888D02*
X1685162Y247207D01*
G01X1693241Y246888D02*
X1685481D01*
G01X1696584Y250231D02*
X1693241Y246888D01*
G01X1715078Y250231D02*
X1696584D01*
G01X1681537Y262916D02*
X1857643D01*
G01X1673604Y270849D02*
X1681537Y262916D01*
G01X1673604Y299204D02*
Y270849D01*
G01X1676857Y270788D02*
Y295924D01*
G01X1682473Y265172D02*
X1676857Y270788D01*
G01X1866928Y265172D02*
X1682473D01*
G01X1664013Y256087D02*
Y301836D01*
G01X1665252Y254848D02*
X1664013Y256087D01*
G01X1669811Y254848D02*
X1665252D01*
G01X1670032Y255069D02*
X1669811Y254848D01*
G01X1670464Y255069D02*
X1670032D01*
G01X1670816Y254717D02*
X1670464Y255069D01*
G01X1670816Y254697D02*
Y254717D01*
G01X1670822Y254691D02*
X1670816Y254697D01*
G01X1697110Y247865D02*
X1717653D01*
G01X1684773Y235528D02*
X1697110Y247865D01*
G01X1679770Y235528D02*
X1684773D01*
G01X1678051Y237246D02*
X1679770Y235528D01*
G01X1665997Y237246D02*
X1678051D01*
G01X1658196Y245047D02*
X1665997Y237246D01*
G01X1658196Y250719D02*
Y245047D01*
G01X1658197Y250720D02*
X1658196Y250719D01*
G01X1658197Y254138D02*
Y250720D01*
G01X1655837Y256498D02*
X1658197Y254138D01*
G01X1655837Y365087D02*
Y256498D01*
G01X1664765Y256399D02*
Y301717D01*
G01X1665564Y255600D02*
X1664765Y256399D01*
G01X1669499Y255600D02*
X1665564D01*
G01X1670140Y256241D02*
X1669499Y255600D01*
G01X1670140Y257547D02*
Y256241D01*
G01X1660005Y251464D02*
Y304389D01*
G01X1658948Y250407D02*
X1660005Y251464D01*
G01X1658948Y245359D02*
Y250407D01*
G01X1666309Y237998D02*
X1658948Y245359D01*
G01X1679122Y237998D02*
X1666309D01*
G01X1680523Y236597D02*
X1679122Y237998D01*
G01X1684014Y236597D02*
X1680523D01*
G01X1696034Y248617D02*
X1684014Y236597D01*
G01X1715485Y248617D02*
X1696034D01*
G01X1675907Y270674D02*
Y296318D01*
G01X1682161Y264420D02*
X1675907Y270674D01*
G01X1866336Y264420D02*
X1682161D01*
G01X1675270Y254264D02*
X1827313D01*
G01X1673863Y252857D02*
X1675270Y254264D01*
G01X1666179Y252857D02*
X1673863D01*
G01X1663261Y255775D02*
X1666179Y252857D01*
G01X1663261Y305739D02*
Y255775D01*
G01X1674556Y270961D02*
Y298809D01*
G01X1681849Y263668D02*
X1674556Y270961D01*
G01X1858238Y263668D02*
X1681849D01*
G01X1657506Y218105D02*
X1653822Y221789D01*
G01X1668691Y218105D02*
X1657506D01*
G01X1696442Y251860D02*
X1720923D01*
G01X1692722Y248140D02*
X1696442Y251860D01*
G01X1687798Y248140D02*
X1692722D01*
G01X1687479Y248459D02*
X1687798Y248140D01*
G01X1668806Y248459D02*
X1687479D01*
G01X1662009Y255256D02*
X1668806Y248459D01*
G01X1662009Y305220D02*
Y255256D01*
G01X1657361Y308097D02*
Y367702D01*
G01X1660757Y304701D02*
X1657361Y308097D01*
G01X1679100Y304700D02*
X1673604Y299204D01*
G01X1677933Y297000D02*
X1679100D01*
G01X1676857Y295924D02*
X1677933Y297000D01*
G01X1664013Y319828D02*
Y372269D01*
G01X1666448Y309558D02*
X1664013Y319828D01*
G01Y301836D02*
X1666448Y309558D01*
G01X1664765Y319934D02*
Y372581D01*
G01X1667200Y309647D02*
X1664765Y319934D01*
G01X1667200Y309439D02*
Y309647D01*
G01X1664765Y301717D02*
X1667200Y309439D01*
G01X1656609Y308409D02*
Y367390D01*
G01X1656608Y308408D02*
X1656609Y308409D01*
G01X1656608Y307786D02*
Y308408D01*
G01X1660005Y304389D02*
X1656608Y307786D01*
G01X1678375Y298775D02*
X1679100Y299500D01*
G01X1678364Y298775D02*
X1678375D01*
G01X1675907Y296318D02*
X1678364Y298775D01*
G01X1659865Y309135D02*
X1663261Y305739D01*
G01X1659865Y369135D02*
Y309135D01*
G01X1677847Y302100D02*
X1679100D01*
G01X1674556Y298809D02*
X1677847Y302100D01*
G01X1658613Y308616D02*
X1662009Y305220D01*
G01X1658613Y368616D02*
Y308616D01*
G01X1664035Y378400D02*
X1664829Y379194D01*
G01X1662732Y378400D02*
X1664035D01*
G01X1661741Y377409D02*
X1662732Y378400D01*
G01X1661741Y374541D02*
Y377409D01*
G01X1664013Y372269D02*
X1661741Y374541D01*
G01X1653194Y402802D02*
X1656806Y406414D01*
G01X1653194Y396075D02*
Y402802D01*
G01X1654208Y395061D02*
X1653194Y396075D01*
G01X1657120Y395061D02*
X1654208D01*
G01X1659359Y397300D02*
X1657120Y395061D01*
G01X1660890Y397300D02*
X1659359D01*
G01X1663952Y377648D02*
X1664905Y376695D01*
G01X1663124Y377648D02*
X1663952D01*
G01X1662516Y377040D02*
X1663124Y377648D01*
G01X1662516Y374830D02*
Y377040D01*
G01X1664765Y372581D02*
X1662516Y374830D01*
G01X1663500Y402238D02*
X1662438Y403300D01*
G01X1663500Y390100D02*
Y402238D01*
G01X1661283Y387883D02*
X1663500Y390100D01*
G01X1660934Y387883D02*
X1661283D01*
G01X1654895Y399145D02*
X1654770D01*
G01X1657558Y401808D02*
X1654895Y399145D01*
G01X1657558Y410387D02*
Y401808D01*
G01X1658310Y398560D02*
Y406610D01*
G01X1656387Y396637D02*
X1658310Y398560D01*
G01X1654861Y396637D02*
X1656387D01*
G01X1671371Y462330D02*
Y470727D01*
G01X1670546Y461505D02*
X1671371Y462330D01*
G01X1670546Y451284D02*
Y461505D01*
G01X1671430Y450400D02*
X1670546Y451284D01*
G01X1671430Y447656D02*
Y450400D01*
G01X1673064Y446022D02*
X1671430Y447656D01*
G01X1663125Y442372D02*
X1664762Y440735D01*
G01X1663125Y459604D02*
Y442372D01*
G01X1668711Y433026D02*
X1667588Y434149D01*
G01X1672276Y433026D02*
X1668711D01*
G01X1690365Y451115D02*
X1672276Y433026D01*
G01X1690365Y466542D02*
Y451115D01*
G01X1680951Y442765D02*
X1678303D01*
G01X1689225Y451039D02*
X1680951Y442765D01*
G01X1689225Y462105D02*
Y451039D01*
G01X1685965Y465365D02*
X1689225Y462105D01*
G01X1673068Y450588D02*
Y448522D01*
G01X1671498Y452158D02*
X1673068Y450588D01*
G01X1671498Y461110D02*
Y452158D01*
G01X1672323Y461935D02*
X1671498Y461110D01*
G01X1672323Y471122D02*
Y461935D01*
G01X1683426Y434600D02*
X1895700D01*
G01X1679700Y430874D02*
X1683426Y434600D01*
G01X1679700Y417400D02*
Y430874D01*
G01X1670334Y408034D02*
X1679700Y417400D01*
G01X1663934Y408034D02*
X1670334D01*
G01X1660834Y404934D02*
X1663934Y408034D01*
G01X1676041Y458884D02*
Y475052D01*
G01X1681866Y438360D02*
X1866260D01*
G01X1674204Y430698D02*
X1681866Y438360D01*
G01X1674204Y428097D02*
Y430698D01*
G01X1656806Y410699D02*
X1674204Y428097D01*
G01X1656806Y406414D02*
Y410699D01*
G01X1705841Y441622D02*
X1722068Y457849D01*
G01X1684064Y441622D02*
X1705841D01*
G01X1673452Y431010D02*
X1684064Y441622D01*
G01X1673452Y428971D02*
Y431010D01*
G01X1670211Y425730D02*
X1673452Y428971D01*
G01X1668918Y425730D02*
X1670211D01*
G01X1667809Y424621D02*
X1668918Y425730D01*
G01X1667729Y424621D02*
X1667809D01*
G01X1669594Y449175D02*
X1669816Y448953D01*
G01X1669594Y461900D02*
Y449175D01*
G01X1670419Y462725D02*
X1669594Y461900D01*
G01X1670419Y470332D02*
Y462725D01*
G01X1671364Y438281D02*
X1669076D01*
G01X1677880Y444797D02*
X1671364Y438281D01*
G01X1677880Y453381D02*
Y444797D01*
G01X1680721Y456222D02*
X1677880Y453381D01*
G01X1680721Y471231D02*
Y456222D01*
G01X1705529Y442374D02*
X1721956Y458801D01*
G01X1683752Y442374D02*
X1705529D01*
G01X1672700Y431322D02*
X1683752Y442374D01*
G01X1672700Y429566D02*
Y431322D01*
G01X1669816Y426682D02*
X1672700Y429566D01*
G01X1668936Y426682D02*
X1669816D01*
G01X1667809Y427809D02*
X1668936Y426682D01*
G01X1668874Y432074D02*
X1667649Y430849D01*
G01X1672388Y432074D02*
X1668874D01*
G01X1691317Y451003D02*
X1672388Y432074D01*
G01X1691317Y466147D02*
Y451003D01*
G01X1685304Y463652D02*
X1683661Y465295D01*
G01X1685305Y463652D02*
X1685304D01*
G01X1687652Y461305D02*
X1685305Y463652D01*
G01X1687652Y455269D02*
Y461305D01*
G01X1681669Y449286D02*
X1687652Y455269D01*
G01X1681154Y449286D02*
X1681669D01*
G01X1666643Y441554D02*
X1667462Y440735D01*
G01X1666643Y444547D02*
Y441554D01*
G01X1665584Y445606D02*
X1666643Y444547D01*
G01X1665584Y459273D02*
Y445606D01*
G01X1683114Y435352D02*
X1895388D01*
G01X1678450Y430688D02*
X1683114Y435352D01*
G01X1678450Y417649D02*
Y430688D01*
G01X1670549Y409748D02*
X1678450Y417649D01*
G01X1663348Y409748D02*
X1670549D01*
G01X1659100Y405500D02*
X1663348Y409748D01*
G01X1659100Y404400D02*
Y405500D01*
G01X1660200Y403300D02*
X1659100Y404400D01*
G01X1662438Y403300D02*
X1660200D01*
G01X1679145Y457372D02*
Y461950D01*
G01X1676397Y454624D02*
X1679145Y457372D01*
G01X1674389Y454624D02*
X1676397D01*
G01X1673213Y455800D02*
X1674389Y454624D01*
G01X1673213Y460056D02*
Y455800D01*
G01X1674031Y460874D02*
X1673213Y460056D01*
G01X1674031Y475877D02*
Y460874D01*
G01X1667447Y420276D02*
X1657558Y410387D01*
G01X1667671Y420276D02*
X1667447D01*
G01X1674956Y427561D02*
X1667671Y420276D01*
G01X1674956Y430386D02*
Y427561D01*
G01X1682178Y437608D02*
X1674956Y430386D01*
G01X1894452Y437608D02*
X1682178D01*
G01X1668190Y442507D02*
X1669962Y440735D01*
G01X1668190Y444347D02*
Y442507D01*
G01X1666536Y446001D02*
X1668190Y444347D01*
G01X1666536Y459668D02*
Y446001D01*
G01X1669816Y444068D02*
Y443953D01*
G01X1667488Y446396D02*
X1669816Y444068D01*
G01X1667488Y460078D02*
Y446396D01*
G01X1662719Y464847D02*
X1667488Y460078D01*
G01X1682802Y436104D02*
X1895076D01*
G01X1677298Y430600D02*
X1682802Y436104D01*
G01X1677298Y417797D02*
Y430600D01*
G01X1670001Y410500D02*
X1677298Y417797D01*
G01X1662200Y410500D02*
X1670001D01*
G01X1658310Y406610D02*
X1662200Y410500D01*
G01X1664161Y444336D02*
X1664762Y443735D01*
G01X1664161Y459632D02*
Y444336D01*
G01X1674465Y457479D02*
X1675744Y456200D01*
G01X1674465Y459537D02*
Y457479D01*
G01X1675283Y460355D02*
X1674465Y459537D01*
G01X1675283Y475358D02*
Y460355D01*
G01X1668240Y448029D02*
X1669816Y446453D01*
G01X1668240Y460390D02*
Y448029D01*
G01X1663471Y465159D02*
X1668240Y460390D01*
G01X1682539Y451786D02*
X1681215D01*
G01X1686500Y455747D02*
X1682539Y451786D01*
G01X1686500Y460827D02*
Y455747D01*
G01X1684828Y462499D02*
X1686500Y460827D01*
G01X1684827Y462499D02*
X1684828D01*
G01X1682735Y464591D02*
X1684827Y462499D01*
G01X1682735Y464592D02*
Y464591D01*
G01X1682509Y464818D02*
X1682735Y464592D01*
G01X1682490Y436856D02*
X1894764D01*
G01X1675708Y430074D02*
X1682490Y436856D01*
G01X1675708Y425596D02*
Y430074D01*
G01X1668812Y418700D02*
X1675708Y425596D01*
G01X1668100Y418700D02*
X1668812D01*
G01X1707271Y516420D02*
X1728849D01*
G01X1693837Y502986D02*
X1707271Y516420D01*
G01X1691467Y502986D02*
X1693837D01*
G01X1690900Y502419D02*
X1691467Y502986D01*
G01X1689438Y502419D02*
X1690900D01*
G01X1689128Y502729D02*
X1689438Y502419D01*
G01X1679583Y502729D02*
X1689128D01*
G01X1677700Y504612D02*
X1679583Y502729D01*
G01X1672051Y504612D02*
X1677700D01*
G01X1667479Y500040D02*
X1672051Y504612D01*
G01X1667479Y488342D02*
Y500040D01*
G01X1670403Y485418D02*
X1667479Y488342D01*
G01X1671461Y485418D02*
X1670403D01*
G01X1672626Y484253D02*
X1671461Y485418D01*
G01X1672626Y477767D02*
Y484253D01*
G01X1669737Y474878D02*
X1672626Y477767D01*
G01X1669737Y472361D02*
Y474878D01*
G01X1671371Y470727D02*
X1669737Y472361D01*
G01X1680584Y520183D02*
X1691584Y531183D01*
G01X1670465Y520183D02*
X1680584D01*
G01X1682461Y518721D02*
X1670995D01*
G01X1692668Y528928D02*
X1682461Y518721D01*
G01X1693928Y470105D02*
X1690365Y466542D01*
G01X1694881Y470105D02*
X1693928D01*
G01X1694882Y470106D02*
X1694881Y470105D01*
G01X1695017Y470106D02*
X1694882D01*
G01X1695018Y470105D02*
X1695017Y470106D01*
G01X1695972Y470105D02*
X1695018D01*
G01X1695973Y470104D02*
X1695972Y470105D01*
G01X1711396Y470104D02*
X1695973D01*
G01X1719748Y461752D02*
X1711396Y470104D01*
G01X1685965Y469283D02*
Y465365D01*
G01X1700964Y484282D02*
X1685965Y469283D01*
G01X1702270Y484282D02*
X1700964D01*
G01X1703193Y483359D02*
X1702270Y484282D01*
G01X1703193Y482779D02*
Y483359D01*
G01X1710683Y475289D02*
X1703193Y482779D01*
G01X1713675Y475289D02*
X1710683D01*
G01X1680000Y521591D02*
X1691000Y532591D01*
G01X1671049Y521591D02*
X1680000D01*
G01X1671048Y521592D02*
X1671049Y521591D01*
G01X1669882Y521592D02*
X1671048D01*
G01X1676911Y497300D02*
X1672313D01*
G01X1678876Y495335D02*
X1676911Y497300D01*
G01X1707041Y495335D02*
X1678876D01*
G01X1716910Y505204D02*
X1707041Y495335D01*
G01X1670689Y472756D02*
X1672323Y471122D01*
G01X1670689Y474483D02*
Y472756D01*
G01X1673578Y477372D02*
X1670689Y474483D01*
G01X1673578Y486701D02*
Y477372D01*
G01X1671136Y489143D02*
X1673578Y486701D01*
G01X1670528Y489143D02*
X1671136D01*
G01X1668431Y491240D02*
X1670528Y489143D01*
G01X1668431Y499645D02*
Y491240D01*
G01X1671714Y502928D02*
X1668431Y499645D01*
G01X1677595Y502928D02*
X1671714D01*
G01X1682269Y498254D02*
X1677595Y502928D01*
G01X1695063Y498254D02*
X1682269D01*
G01X1699446Y502637D02*
X1695063Y498254D01*
G01X1699446Y506339D02*
Y502637D01*
G01X1708575Y515468D02*
X1699446Y506339D01*
G01X1729244Y515468D02*
X1708575D01*
G01X1675500Y523000D02*
X1666266D01*
G01X1676788Y524288D02*
X1675500Y523000D01*
G01X1677112Y524423D02*
X1676788Y524288D01*
G01X1677871Y524929D02*
X1677112Y524423D01*
G01X1686942Y534000D02*
X1677871Y524929D01*
G01X1672604Y494487D02*
X1672159Y494042D01*
G01X1707257Y494487D02*
X1672604D01*
G01X1717222Y504452D02*
X1707257Y494487D01*
G01X1707881Y492983D02*
X1714098Y499200D01*
G01X1685153Y492983D02*
X1707881D01*
G01X1681499Y489329D02*
X1685153Y492983D01*
G01X1681499Y484228D02*
Y489329D01*
G01X1679494Y482223D02*
X1681499Y484228D01*
G01X1679494Y478505D02*
Y482223D01*
G01X1676041Y475052D02*
X1679494Y478505D01*
G01X1711986Y473904D02*
X1718590Y467300D01*
G01X1706287Y473904D02*
X1711986D01*
G01X1701617Y478574D02*
X1706287Y473904D01*
G01X1701617Y482706D02*
Y478574D01*
G01X1664423Y476328D02*
X1670419Y470332D01*
G01X1664423Y501308D02*
Y476328D01*
G01X1671902Y508787D02*
X1664423Y501308D01*
G01X1682701Y508787D02*
X1671902D01*
G01X1695682Y521768D02*
X1682701Y508787D01*
G01X1723624Y521768D02*
X1695682D01*
G01X1670026Y482024D02*
X1671050Y481000D01*
G01X1668499Y482024D02*
X1670026D01*
G01X1665575Y484948D02*
X1668499Y482024D01*
G01X1665575Y500830D02*
Y484948D01*
G01X1672380Y507635D02*
X1665575Y500830D01*
G01X1687738Y507635D02*
X1672380D01*
G01X1698162Y518059D02*
X1687738Y507635D01*
G01X1698162Y519291D02*
Y518059D01*
G01X1697261Y520192D02*
X1698162Y519291D01*
G01X1682364Y472874D02*
X1680721Y471231D01*
G01X1682364Y475766D02*
Y472874D01*
G01X1681369Y476761D02*
X1682364Y475766D01*
G01X1681369Y481869D02*
Y476761D01*
G01X1681500Y482000D02*
X1681369Y481869D01*
G01X1694323Y469153D02*
X1691317Y466147D01*
G01X1695577Y469153D02*
X1694323D01*
G01X1695578Y469152D02*
X1695577Y469153D01*
G01X1711001Y469152D02*
X1695578D01*
G01X1719353Y460800D02*
X1711001Y469152D01*
G01X1698914Y519245D02*
X1699861Y520192D01*
G01X1698914Y517747D02*
Y519245D01*
G01X1688050Y506883D02*
X1698914Y517747D01*
G01X1672692Y506883D02*
X1688050D01*
G01X1666327Y500518D02*
X1672692Y506883D01*
G01X1666327Y485260D02*
Y500518D01*
G01X1668811Y482776D02*
X1666327Y485260D01*
G01X1670226Y482776D02*
X1668811D01*
G01X1671050Y483600D02*
X1670226Y482776D01*
G01X1687259Y489248D02*
X1724040D01*
G01X1685867Y487856D02*
X1687259Y489248D01*
G01X1685867Y480404D02*
Y487856D01*
G01X1686701Y479570D02*
X1685867Y480404D01*
G01X1686701Y471759D02*
Y479570D01*
G01X1683661Y468719D02*
X1686701Y471759D01*
G01X1683661Y465295D02*
Y468719D01*
G01X1683085Y517217D02*
X1671619D01*
G01X1693292Y527424D02*
X1683085Y517217D01*
G01X1699190Y487709D02*
X1724131D01*
G01X1698354Y486873D02*
X1699190Y487709D01*
G01X1674830Y476676D02*
X1674031Y475877D01*
G01X1674830Y489299D02*
Y476676D01*
G01X1671703Y492426D02*
X1674830Y489299D01*
G01X1671546Y492426D02*
X1671703D01*
G01X1669683Y494289D02*
X1671546Y492426D01*
G01X1669683Y499126D02*
Y494289D01*
G01X1671953Y501396D02*
X1669683Y499126D01*
G01X1675518Y501396D02*
X1671953D01*
G01X1680327Y496587D02*
X1675518Y501396D01*
G01X1705204Y496587D02*
X1680327D01*
G01X1708052Y499435D02*
X1705204Y496587D01*
G01X1708052Y504338D02*
Y499435D01*
G01X1714107Y510393D02*
X1708052Y504338D01*
G01X1650944Y504646D02*
Y505166D01*
G01X1712038Y471657D02*
X1720391Y463304D01*
G01X1692410Y471657D02*
X1712038D01*
G01X1687741Y466988D02*
X1692410Y471657D01*
G01X1651371Y495622D02*
Y492062D01*
G01X1672014Y516265D02*
X1651371Y495622D01*
G01X1683480Y516265D02*
X1672014D01*
G01X1693687Y526472D02*
X1683480Y516265D01*
G01X1662719Y502015D02*
Y464847D01*
G01X1674017Y513313D02*
X1662719Y502015D01*
G01X1684704Y513313D02*
X1674017D01*
G01X1694911Y523520D02*
X1684704Y513313D01*
G01X1722965Y523520D02*
X1694911D01*
G01X1682773Y517969D02*
X1671307D01*
G01X1692980Y528176D02*
X1682773Y517969D01*
G01X1678500Y478575D02*
X1675283Y475358D01*
G01X1678500Y482500D02*
Y478575D01*
G01X1680698Y484698D02*
X1678500Y482500D01*
G01X1680747Y484698D02*
X1680698D01*
G01X1680747Y489641D02*
Y484698D01*
G01X1684841Y493735D02*
X1680747Y489641D01*
G01X1707569Y493735D02*
X1684841D01*
G01X1717534Y503700D02*
X1707569Y493735D01*
G01X1663471Y501703D02*
Y465159D01*
G01X1674329Y512561D02*
X1663471Y501703D01*
G01X1685016Y512561D02*
X1674329D01*
G01X1695223Y522768D02*
X1685016Y512561D01*
G01X1723277Y522768D02*
X1695223D01*
G01X1682509Y469197D02*
Y464818D01*
G01X1685549Y472237D02*
X1682509Y469197D01*
G01X1685549Y478681D02*
Y472237D01*
G01X1684484Y479746D02*
X1685549Y478681D01*
G01X1684484Y488103D02*
Y479746D01*
G01X1686781Y490400D02*
X1684484Y488103D01*
G01X1712211Y490400D02*
X1686781D01*
G01X1691584Y531183D02*
X1719667D01*
G01X1720450Y528928D02*
X1692668D01*
G01X1691000Y532591D02*
X1719083D01*
G01X1699600Y576256D02*
Y578100D01*
G01X1699951Y575905D02*
X1699600Y576256D01*
G01X1699951Y561818D02*
Y575905D01*
G01X1696266Y558133D02*
X1699951Y561818D01*
G01X1668741Y558133D02*
X1696266D01*
G01X1663908Y553300D02*
X1668741Y558133D01*
G01X1658542Y553300D02*
X1663908D01*
G01X1718500Y534000D02*
X1686942D01*
G01X1667297Y550753D02*
Y541797D01*
G01X1671850Y555306D02*
X1667297Y550753D01*
G01X1703368Y555306D02*
X1671850D01*
G01X1712958Y564896D02*
X1703368Y555306D01*
G01X1702526Y581284D02*
X1712958Y570852D01*
G01X1695205Y581284D02*
X1702526D01*
G01X1694000Y580079D02*
X1695205Y581284D01*
G01X1680133Y538394D02*
Y535489D01*
G01X1683906Y542167D02*
X1680133Y538394D01*
G01X1689813Y542167D02*
X1683906D01*
G01X1698073Y550427D02*
X1689813Y542167D01*
G01X1699027Y550427D02*
X1698073D01*
G01X1699028Y550426D02*
X1699027Y550427D01*
G01X1707310Y550426D02*
X1699028D01*
G01X1717764Y560880D02*
X1707310Y550426D01*
G01X1701291Y592733D02*
X1717764Y576260D01*
G01X1678825Y536797D02*
X1673380D01*
G01X1680133Y535489D02*
X1678825Y536797D01*
G01X1677579Y539101D02*
X1668020D01*
G01X1682949Y544471D02*
X1677579Y539101D01*
G01X1688857Y544471D02*
X1682949D01*
G01X1697117Y552731D02*
X1688857Y544471D01*
G01X1699983Y552731D02*
X1697117D01*
G01X1699984Y552730D02*
X1699983Y552731D01*
G01X1706354Y552730D02*
X1699984D01*
G01X1715460Y561836D02*
X1706354Y552730D01*
G01X1710389Y577787D02*
X1715460Y572716D01*
G01X1677281Y540433D02*
X1667722D01*
G01X1682471Y545623D02*
X1677281Y540433D01*
G01X1688379Y545623D02*
X1682471D01*
G01X1696910Y554154D02*
X1688379Y545623D01*
G01X1703846Y554154D02*
X1696910D01*
G01X1714110Y564418D02*
X1703846Y554154D01*
G01X1699088Y586590D02*
X1714110Y571568D01*
G01X1693197Y586590D02*
X1699088D01*
G01X1689187Y590600D02*
X1693197Y586590D01*
G01X1721074Y527424D02*
X1693292D01*
G01X1668396Y533645D02*
X1664194D01*
G01X1672700Y537949D02*
X1668396Y533645D01*
G01X1678057Y537949D02*
X1672700D01*
G01X1683427Y543319D02*
X1678057Y537949D01*
G01X1689335Y543319D02*
X1683427D01*
G01X1697595Y551579D02*
X1689335Y543319D01*
G01X1699505Y551579D02*
X1697595D01*
G01X1699506Y551578D02*
X1699505Y551579D01*
G01X1706832Y551578D02*
X1699506D01*
G01X1716612Y561358D02*
X1706832Y551578D01*
G01X1700794Y591600D02*
X1716612Y575782D01*
G01X1665889Y551337D02*
Y542381D01*
G01X1671266Y556714D02*
X1665889Y551337D01*
G01X1702784Y556714D02*
X1671266D01*
G01X1711550Y565480D02*
X1702784Y556714D01*
G01X1711550Y570268D02*
Y565480D01*
G01X1701942Y579876D02*
X1711550Y570268D01*
G01X1698643Y579876D02*
X1701942D01*
G01X1696319Y577552D02*
X1698643Y579876D01*
G01X1672512Y577552D02*
X1696319D01*
G01X1667800Y582264D02*
X1672512Y577552D01*
G01X1667800Y594400D02*
Y582264D01*
G01X1721469Y526472D02*
X1693687D01*
G01X1720762Y528176D02*
X1692980D01*
G01X1718916Y576738D02*
X1703950Y591704D01*
G01X1707788Y549274D02*
X1718923Y560409D01*
G01X1698550Y549274D02*
X1707788D01*
G01X1690291Y541015D02*
X1698550Y549274D01*
G01X1684384Y541015D02*
X1690291D01*
G01X1682195Y538826D02*
X1684384Y541015D01*
G01X1682195Y537872D02*
Y538826D01*
G01X1682196Y537871D02*
X1682195Y537872D01*
G01X1682196Y537826D02*
Y537871D01*
G01X1681285Y536915D02*
X1682196Y537826D01*
G01X1681285Y536566D02*
Y536915D01*
G01X1681709Y536142D02*
X1681285Y536566D01*
G01X1681709Y534836D02*
Y536142D01*
G01X1680786Y533913D02*
X1681709Y534836D01*
G01X1679480Y533913D02*
X1680786D01*
G01X1677815Y535578D02*
X1679480Y533913D01*
G01X1673791Y535578D02*
X1677815D01*
G01X1701088Y606548D02*
X1719501D01*
G01X1693800Y613836D02*
X1701088Y606548D01*
G01X1693800Y615766D02*
Y613836D01*
G01X1689840Y619726D02*
X1693800Y615766D01*
G01X1711731Y607753D02*
X1715609Y611631D01*
G01X1701982Y607753D02*
X1711731D01*
G01X1694752Y614983D02*
X1701982Y607753D01*
G01X1694752Y615878D02*
Y614983D01*
G01X1690152Y620478D02*
X1694752Y615878D01*
G01X1697496Y616804D02*
X1690750Y623550D01*
G01X1697496Y614712D02*
Y616804D01*
G01X1702751Y609457D02*
X1697496Y614712D01*
G01X1710897Y609457D02*
X1702751D01*
G01X1714575Y613135D02*
X1710897Y609457D01*
G01X1701291Y602268D02*
Y592733D01*
G01X1692722Y624402D02*
X1699106Y618018D01*
G01X1674424Y590600D02*
X1689187D01*
G01X1668152Y596872D02*
X1674424Y590600D01*
G01X1668152Y598852D02*
Y596872D01*
G01X1668182Y598882D02*
X1668152Y598852D01*
G01X1668182Y611347D02*
Y598882D01*
G01X1660555Y618974D02*
X1668182Y611347D01*
G01X1694290Y591600D02*
X1700794D01*
G01X1691047Y594843D02*
X1694290Y591600D01*
G01X1691047Y600551D02*
Y594843D01*
G01X1666744Y595456D02*
X1667800Y594400D01*
G01X1666744Y599436D02*
Y595456D01*
G01X1666774Y599466D02*
X1666744Y599436D01*
G01X1666774Y610763D02*
Y599466D01*
G01X1659971Y617566D02*
X1666774Y610763D01*
G01X1711419Y608505D02*
X1715297Y612383D01*
G01X1702294Y608505D02*
X1711419D01*
G01X1696544Y614255D02*
X1702294Y608505D01*
G01X1696544Y616409D02*
Y614255D01*
G01X1690355Y622598D02*
X1696544Y616409D01*
G01X1691047Y609946D02*
Y615512D01*
G01X1696293Y604700D02*
X1691047Y609946D01*
G01X1701088Y604700D02*
X1696293D01*
G01X1703950Y601838D02*
X1701088Y604700D01*
G01X1703950Y591704D02*
Y601838D01*
G01X1761872Y-6673D02*
Y-7220D01*
G01X1767454Y-1091D02*
X1761872Y-6673D01*
G01X1776351Y-1091D02*
X1767454D01*
G01X1751450Y91463D02*
X1757700Y97713D01*
G01X1738022Y91463D02*
X1751450D01*
G01X1737812Y91253D02*
X1738022Y91463D01*
G01X1737811Y91253D02*
X1737812D01*
G01X1734358Y87800D02*
X1737811Y91253D01*
G01X1723763Y87800D02*
X1734358D01*
G01X1721153Y85190D02*
X1723763Y87800D01*
G01X1717046Y85190D02*
X1721153D01*
G01X1717045Y85191D02*
X1717046Y85190D01*
G01X1716423Y85191D02*
X1717045D01*
G01X1716422Y85190D02*
X1716423Y85191D01*
G01X1714223Y85190D02*
X1716422D01*
G01X1751138Y92214D02*
X1765000Y106076D01*
G01X1737710Y92214D02*
X1751138D01*
G01X1737500Y92004D02*
X1737710Y92214D01*
G01X1737499Y92004D02*
X1737500D01*
G01X1736748Y91253D02*
X1737499Y92004D01*
G01X1736747Y91253D02*
X1736748D01*
G01X1734094Y88600D02*
X1736747Y91253D01*
G01X1723499Y88600D02*
X1734094D01*
G01X1720841Y85942D02*
X1723499Y88600D01*
G01X1717358Y85942D02*
X1720841D01*
G01X1717357Y85943D02*
X1717358Y85942D01*
G01X1716111Y85943D02*
X1717357D01*
G01X1716110Y85942D02*
X1716111Y85943D01*
G01X1713911Y85942D02*
X1716110D01*
G01X1750454Y93329D02*
X1757000Y99875D01*
G01X1743208Y93329D02*
X1750454D01*
G01X1742237Y94300D02*
X1743208Y93329D01*
G01X1769329Y96076D02*
X1791082Y74323D01*
G01X1752538Y89208D02*
X1759406Y96076D01*
G01X1738958Y89208D02*
X1752538D01*
G01X1735195Y85445D02*
X1738958Y89208D01*
G01X1724600Y85445D02*
X1735195D01*
G01X1722089Y82934D02*
X1724600Y85445D01*
G01X1715159Y82934D02*
X1722089D01*
G01X1769641Y96828D02*
X1791359Y75110D01*
G01X1752226Y89960D02*
X1759094Y96828D01*
G01X1738646Y89960D02*
X1752226D01*
G01X1734883Y86197D02*
X1738646Y89960D01*
G01X1724288Y86197D02*
X1734883D01*
G01X1721777Y83686D02*
X1724288Y86197D01*
G01X1714847Y83686D02*
X1721777D01*
G01X1755662Y86527D02*
X1757395Y84794D01*
G01X1755662Y90411D02*
Y86527D01*
G01X1757501Y92250D02*
X1755662Y90411D01*
G01X1771525Y92250D02*
X1757501D01*
G01X1790225Y73550D02*
X1771525Y92250D01*
G01X1715911Y92140D02*
X1731350D01*
G01X1769252Y86100D02*
X1786420Y68932D01*
G01X1764112Y86100D02*
X1769252D01*
G01X1760285Y82273D02*
X1764112Y86100D01*
G01X1753928Y82273D02*
X1760285D01*
G01X1750244Y85957D02*
X1753928Y82273D01*
G01X1737699Y85957D02*
X1750244D01*
G01X1735779Y84037D02*
X1737699Y85957D01*
G01X1725184Y84037D02*
X1735779D01*
G01X1722673Y81526D02*
X1725184Y84037D01*
G01X1715743Y81526D02*
X1722673D01*
G01X1743520Y94080D02*
X1742549Y95051D01*
G01X1750142Y94080D02*
X1743520D01*
G01X1756249Y100187D02*
X1750142Y94080D01*
G01X1771213Y91498D02*
X1789913Y72798D01*
G01X1759096Y91498D02*
X1771213D01*
G01X1757772Y90174D02*
X1759096Y91498D01*
G01X1751914Y90712D02*
X1762300Y101098D01*
G01X1738334Y90712D02*
X1751914D01*
G01X1734571Y86949D02*
X1738334Y90712D01*
G01X1725224Y86949D02*
X1734571D01*
G01X1725223Y86950D02*
X1725224Y86949D01*
G01X1723977Y86950D02*
X1725223D01*
G01X1721465Y84438D02*
X1723977Y86950D01*
G01X1714535Y84438D02*
X1721465D01*
G01X1768450Y102050D02*
X1787108Y83392D01*
G01X1762038Y102050D02*
X1768450D01*
G01X1757701Y97713D02*
X1762038Y102050D01*
G01X1757700Y97713D02*
X1757701D01*
G01X1765000Y106076D02*
X1776239D01*
G01X1757000Y118000D02*
X1758100Y119100D01*
G01X1757000Y99875D02*
Y118000D01*
G01X1759406Y96076D02*
X1769329D01*
G01X1759094Y96828D02*
X1769641D01*
G01X1773199Y152876D02*
X1775976Y150099D01*
G01X1773199Y157989D02*
Y152876D01*
G01X1768886Y151937D02*
Y156173D01*
G01X1788441Y132382D02*
X1768886Y151937D01*
G01X1771791Y152292D02*
X1795583Y128500D01*
G01X1771791Y157405D02*
Y152292D01*
G01X1742549Y95051D02*
X1713399D01*
G01X1756249Y119761D02*
Y100187D01*
G01X1757364Y120876D02*
X1756249Y119761D01*
G01X1759524Y120876D02*
X1757364D01*
G01X1761300Y119100D02*
X1759524Y120876D01*
G01X1768055Y101098D02*
X1786848Y82305D01*
G01X1762300Y101098D02*
X1768055D01*
G01X1770639Y151814D02*
X1789593Y132860D01*
G01X1770639Y156927D02*
Y151814D01*
G01X1719065Y166859D02*
X1714987Y170937D01*
G01X1774393Y166859D02*
X1719065D01*
G01X1728843Y191552D02*
X1814512D01*
G01X1716041Y204354D02*
X1728843Y191552D01*
G01X1715894Y204354D02*
X1716041D01*
G01X1715683Y204565D02*
X1715894Y204354D01*
G01X1715582Y203602D02*
X1715371Y203813D01*
G01X1715729Y203602D02*
X1715582D01*
G01X1728531Y190800D02*
X1715729Y203602D01*
G01X1814200Y190800D02*
X1728531D01*
G01X1768581Y162607D02*
X1773199Y157989D01*
G01X1765253Y162607D02*
X1768581D01*
G01X1765197Y162663D02*
X1765253Y162607D01*
G01X1714289Y162663D02*
X1765197D01*
G01X1729181Y186504D02*
X1791469D01*
G01X1717679Y198006D02*
X1729181Y186504D01*
G01X1717679Y198313D02*
Y198006D01*
G01X1714435Y201557D02*
X1717679Y198313D01*
G01X1727503Y182740D02*
X1722495Y187748D01*
G01X1770036Y182740D02*
X1727503D01*
G01X1773296Y179480D02*
X1770036Y182740D01*
G01X1773296Y175040D02*
Y179480D01*
G01X1775615Y172721D02*
X1773296Y175040D01*
G01X1718431Y198625D02*
X1714747Y202309D01*
G01X1718431Y198318D02*
Y198625D01*
G01X1729208Y187541D02*
X1718431Y198318D01*
G01X1793897Y187541D02*
X1729208D01*
G01X1771912Y184244D02*
X1774800Y181356D01*
G01X1728127Y184244D02*
X1771912D01*
G01X1720295Y192076D02*
X1728127Y184244D01*
G01X1714186Y192076D02*
X1720295D01*
G01X1713571Y191461D02*
X1714186Y192076D01*
G01X1713565Y191460D02*
X1713571Y191461D01*
G01X1771600Y183492D02*
X1774048Y181044D01*
G01X1727815Y183492D02*
X1771600D01*
G01X1722807Y188500D02*
X1727815Y183492D01*
G01X1712198Y188500D02*
X1722807D01*
G01X1720001Y169115D02*
X1778878D01*
G01X1715923Y173193D02*
X1720001Y169115D01*
G01X1719689Y168363D02*
X1715611Y172441D01*
G01X1778566Y168363D02*
X1719689D01*
G01X1769052Y164128D02*
X1715152D01*
G01X1774607Y158573D02*
X1769052Y164128D01*
G01X1729824Y188296D02*
X1715059Y203061D01*
G01X1802276Y188296D02*
X1729824D01*
G01X1767997Y161199D02*
X1771791Y157405D01*
G01X1712307Y161199D02*
X1767997D01*
G01X1716206Y205106D02*
X1715995Y205317D01*
G01X1716353Y205106D02*
X1716206D01*
G01X1729155Y192304D02*
X1716353Y205106D01*
G01X1828476Y192304D02*
X1729155D01*
G01X1729821Y203292D02*
X1826437D01*
G01X1727148Y205965D02*
X1729821Y203292D01*
G01X1716411Y205965D02*
X1727148D01*
G01X1716307Y206069D02*
X1716411Y205965D01*
G01X1716927Y198001D02*
X1714123Y200805D01*
G01X1716927Y197572D02*
Y198001D01*
G01X1728751Y185748D02*
X1716927Y197572D01*
G01X1780691Y185748D02*
X1728751D01*
G01X1769716Y165380D02*
X1776828Y158268D01*
G01X1716858Y165380D02*
X1769716D01*
G01X1712566Y169672D02*
X1716858Y165380D01*
G01X1767283Y171718D02*
X1781191D01*
G01X1762100Y176901D02*
X1767283Y171718D01*
G01X1762100Y178078D02*
Y176901D01*
G01X1758190Y181988D02*
X1762100Y178078D01*
G01X1727191Y181988D02*
X1758190D01*
G01X1722603Y186576D02*
X1727191Y181988D01*
G01X1712276Y186576D02*
X1722603D01*
G01X1769497Y158069D02*
X1770639Y156927D01*
G01X1762711Y158069D02*
X1769497D01*
G01X1761160Y156518D02*
X1762711Y158069D01*
G01X1719377Y167611D02*
X1715299Y171689D01*
G01X1777089Y167611D02*
X1719377D01*
G01X1716723Y206717D02*
X1716619Y206821D01*
G01X1727460Y206717D02*
X1716723D01*
G01X1730133Y204044D02*
X1727460Y206717D01*
G01X1829408Y204044D02*
X1730133D01*
G01X1717653Y247865D02*
X1718820Y249032D01*
G01X1715523Y248655D02*
X1715485Y248617D01*
G01X1715731Y248655D02*
X1715523D01*
G01X1717684Y250608D02*
X1715731Y248655D01*
G01X1719710Y250608D02*
X1717684D01*
G01X1720699Y249619D02*
X1719710Y250608D01*
G01X1720701Y249619D02*
X1720699D01*
G01X1721681Y248639D02*
X1720701Y249619D01*
G01X1730570Y248639D02*
X1721681D01*
G01X1734291Y252360D02*
X1730570Y248639D01*
G01X1821016Y252360D02*
X1734291D01*
G01X1720923Y251860D02*
X1722251Y250532D01*
G01X1819922Y461752D02*
X1719748D01*
G01X1722068Y457849D02*
X1820596D01*
G01X1721956Y458801D02*
X1820201D01*
G01X1820317Y460800D02*
X1719353D01*
G01X1733474Y463304D02*
X1739115Y468945D01*
G01X1720391Y463304D02*
X1733474D01*
G01X1736500Y524071D02*
Y540227D01*
G01X1728849Y516420D02*
X1736500Y524071D01*
G01X1718729Y470235D02*
X1713675Y475289D01*
G01X1724201Y470235D02*
X1718729D01*
G01X1734114Y480148D02*
X1724201Y470235D01*
G01X1765630Y480148D02*
X1734114D01*
G01X1775309Y489827D02*
X1765630Y480148D01*
G01X1773486Y514376D02*
X1793748D01*
G01X1767843Y508733D02*
X1773486Y514376D01*
G01X1767843Y496993D02*
Y508733D01*
G01X1762500Y491650D02*
X1767843Y496993D01*
G01X1762500Y489662D02*
Y491650D01*
G01X1756186Y483348D02*
X1762500Y489662D01*
G01X1731252Y483348D02*
X1756186D01*
G01X1720008Y472104D02*
X1731252Y483348D01*
G01X1719089Y472104D02*
X1720008D01*
G01X1722193Y505204D02*
X1716910D01*
G01X1723059Y506070D02*
X1722193Y505204D01*
G01X1723075Y506070D02*
X1723059D01*
G01X1723079Y506074D02*
X1723075Y506070D01*
G01X1723392Y506074D02*
X1723079D01*
G01X1750379Y533061D02*
X1723392Y506074D01*
G01X1737500Y523724D02*
X1729244Y515468D01*
G01X1737500Y538671D02*
Y523724D01*
G01X1722505Y504452D02*
X1717222D01*
G01X1723371Y505318D02*
X1722505Y504452D01*
G01X1723387Y505318D02*
X1723371D01*
G01X1723391Y505322D02*
X1723387Y505318D01*
G01X1723704Y505322D02*
X1723391D01*
G01X1750491Y532109D02*
X1723704Y505322D01*
G01X1734074Y511158D02*
X1752994Y530078D01*
G01X1731668Y511158D02*
X1734074D01*
G01X1724328Y503818D02*
X1731668Y511158D01*
G01X1724015Y503818D02*
X1724328D01*
G01X1724011Y503814D02*
X1724015Y503818D01*
G01X1723995Y503814D02*
X1724011D01*
G01X1719381Y499200D02*
X1723995Y503814D01*
G01X1714098Y499200D02*
X1719381D01*
G01X1770600Y474769D02*
X1781700Y485869D01*
G01X1770600Y472400D02*
Y474769D01*
G01X1769324Y471124D02*
X1770600Y472400D01*
G01X1734824Y471124D02*
X1769324D01*
G01X1731000Y467300D02*
X1734824Y471124D01*
G01X1718590Y467300D02*
X1731000D01*
G01X1735498Y533642D02*
X1723624Y521768D01*
G01X1729700Y470200D02*
X1728700D01*
G01X1736896Y477396D02*
X1729700Y470200D01*
G01X1759939Y477396D02*
X1736896D01*
G01X1760674Y478131D02*
X1759939Y477396D01*
G01X1772332Y478131D02*
X1760674D01*
G01X1779788Y485587D02*
X1772332Y478131D01*
G01X1763037Y525564D02*
X1770622Y533149D01*
G01X1758028Y525564D02*
X1763037D01*
G01X1735649Y503185D02*
X1758028Y525564D01*
G01X1735649Y499583D02*
Y503185D01*
G01X1731343Y495277D02*
X1735649Y499583D01*
G01X1730069Y495277D02*
X1731343D01*
G01X1724040Y489248D02*
X1730069Y495277D01*
G01X1768595Y504540D02*
X1776695Y512640D01*
G01X1768595Y496115D02*
Y504540D01*
G01X1763652Y491172D02*
X1768595Y496115D01*
G01X1763652Y490140D02*
Y491172D01*
G01X1763653Y490139D02*
X1763652Y490140D01*
G01X1763653Y489185D02*
Y490139D01*
G01X1756664Y482196D02*
X1763653Y489185D01*
G01X1732376Y482196D02*
X1756664D01*
G01X1722365Y472185D02*
X1732376Y482196D01*
G01X1722365Y471811D02*
Y472185D01*
G01X1722347Y471811D02*
X1722365D01*
G01X1750800Y510776D02*
Y516100D01*
G01X1734149Y494125D02*
X1750800Y510776D01*
G01X1730547Y494125D02*
X1734149D01*
G01X1724131Y487709D02*
X1730547Y494125D01*
G01X1758928Y524228D02*
X1750800Y516100D01*
G01X1770158Y524228D02*
X1758928D01*
G01X1775962Y518424D02*
X1770158Y524228D01*
G01X1725940Y510393D02*
X1714107D01*
G01X1739000Y523453D02*
X1725940Y510393D01*
G01X1739000Y538000D02*
Y523453D01*
G01X1739115Y468945D02*
X1809528D01*
G01X1733794Y534349D02*
X1722965Y523520D01*
G01X1722817Y503700D02*
X1717534D01*
G01X1723683Y504566D02*
X1722817Y503700D01*
G01X1723699Y504566D02*
X1723683D01*
G01X1723703Y504570D02*
X1723699Y504566D01*
G01X1724016Y504570D02*
X1723703D01*
G01X1731356Y511910D02*
X1724016Y504570D01*
G01X1733479Y511910D02*
X1731356D01*
G01X1752592Y531023D02*
X1733479Y511910D01*
G01X1734546Y534037D02*
X1723277Y522768D01*
G01X1724473Y502662D02*
X1712211Y490400D01*
G01X1724489Y502662D02*
X1724473D01*
G01X1724493Y502666D02*
X1724489Y502662D01*
G01X1724806Y502666D02*
X1724493D01*
G01X1727762Y505622D02*
X1724806Y502666D01*
G01X1735753Y505622D02*
X1727762D01*
G01X1756847Y526716D02*
X1735753Y505622D01*
G01X1770600Y574083D02*
X1770719Y573964D01*
G01X1770600Y600800D02*
Y574083D01*
G01X1746128Y561700D02*
X1743100D01*
G01X1746480Y561348D02*
X1746128Y561700D01*
G01X1746480Y550207D02*
Y561348D01*
G01X1736500Y540227D02*
X1746480Y550207D01*
G01X1722316Y569312D02*
Y595428D01*
G01X1725684Y565944D02*
X1722316Y569312D01*
G01X1725684Y560680D02*
Y565944D01*
G01X1724816Y559812D02*
X1725684Y560680D01*
G01X1724816Y536332D02*
Y559812D01*
G01X1719667Y531183D02*
X1724816Y536332D01*
G01X1726472Y534950D02*
X1720450Y528928D01*
G01X1726472Y559476D02*
Y534950D01*
G01X1727500Y560504D02*
X1726472Y559476D01*
G01X1727500Y570008D02*
Y560504D01*
G01X1725694Y571814D02*
X1727500Y570008D01*
G01X1720908Y568582D02*
Y596012D01*
G01X1724276Y565214D02*
X1720908Y568582D01*
G01X1724276Y561264D02*
Y565214D01*
G01X1723408Y560396D02*
X1724276Y561264D01*
G01X1723408Y536916D02*
Y560396D01*
G01X1719083Y532591D02*
X1723408Y536916D01*
G01X1760887Y533061D02*
X1750379D01*
G01X1765200Y537374D02*
X1760887Y533061D01*
G01X1765200Y551494D02*
Y537374D01*
G01X1762496Y554198D02*
X1765200Y551494D01*
G01X1762496Y564504D02*
Y554198D01*
G01X1757850Y569150D02*
X1762496Y564504D01*
G01X1757850Y579950D02*
Y569150D01*
G01X1765500Y587600D02*
X1757850Y579950D01*
G01X1765500Y593807D02*
Y587600D01*
G01X1747485Y548656D02*
X1737500Y538671D01*
G01X1749177Y548656D02*
X1747485D01*
G01X1750677Y550156D02*
X1749177Y548656D01*
G01X1750677Y574530D02*
Y550156D01*
G01X1754897Y578750D02*
X1750677Y574530D01*
G01X1722000Y537500D02*
X1718500Y534000D01*
G01X1722000Y561500D02*
Y537500D01*
G01X1722500Y562000D02*
X1722000Y561500D01*
G01X1712958Y570852D02*
Y564896D01*
G01X1760999Y532109D02*
X1750491D01*
G01X1765952Y537062D02*
X1760999Y532109D01*
G01X1765952Y551806D02*
Y537062D01*
G01X1763248Y554510D02*
X1765952Y551806D01*
G01X1763248Y565252D02*
Y554510D01*
G01X1759296Y569204D02*
X1763248Y565252D01*
G01X1759296Y579120D02*
Y569204D01*
G01X1766476Y586300D02*
X1759296Y579120D01*
G01X1766476Y593895D02*
Y586300D01*
G01X1767980Y585000D02*
Y595568D01*
G01X1760800Y577820D02*
X1767980Y585000D01*
G01X1760800Y571300D02*
Y577820D01*
G01X1765000Y567100D02*
X1760800Y571300D01*
G01X1765000Y555333D02*
Y567100D01*
G01X1768005Y552328D02*
X1765000Y555333D01*
G01X1768005Y535875D02*
Y552328D01*
G01X1762208Y530078D02*
X1768005Y535875D01*
G01X1752994Y530078D02*
X1762208D01*
G01X1735498Y540572D02*
Y533642D01*
G01X1745528Y550602D02*
X1735498Y540572D01*
G01X1745528Y556972D02*
Y550602D01*
G01X1741000Y561500D02*
X1745528Y556972D01*
G01X1741000Y565500D02*
Y561500D01*
G01X1742800Y567300D02*
X1741000Y565500D01*
G01X1743200Y567300D02*
X1742800D01*
G01X1717764Y576260D02*
Y560880D01*
G01X1715460Y572716D02*
Y561836D01*
G01X1714110Y570374D02*
Y564418D01*
G01X1714111Y570375D02*
X1714110Y570374D01*
G01X1714111Y571329D02*
Y570375D01*
G01X1714110Y571330D02*
X1714111Y571329D01*
G01X1714110Y571568D02*
Y571330D01*
G01X1770622Y533149D02*
X1785351D01*
G01X1772578Y575993D02*
Y602123D01*
G01X1728105Y534455D02*
X1721074Y527424D01*
G01X1728105Y542871D02*
Y534455D01*
G01X1729880Y544646D02*
X1728105Y542871D01*
G01X1729880Y544696D02*
Y544646D01*
G01X1734635Y549451D02*
X1729880Y544696D01*
G01X1734635Y565462D02*
Y549451D01*
G01X1741501Y572328D02*
X1734635Y565462D01*
G01X1747626Y572328D02*
X1741501D01*
G01X1748306Y573008D02*
X1747626Y572328D01*
G01X1748306Y582605D02*
Y573008D01*
G01X1742381Y588530D02*
X1748306Y582605D01*
G01X1716612Y575782D02*
Y561358D01*
G01X1748404Y547404D02*
X1739000Y538000D01*
G01X1749696Y547404D02*
X1748404D01*
G01X1751930Y549638D02*
X1749696Y547404D01*
G01X1751930Y550674D02*
Y549638D01*
G01X1751929Y550675D02*
X1751930Y550674D01*
G01X1751929Y568911D02*
Y550675D01*
G01X1756500Y573482D02*
X1751929Y568911D01*
G01X1756500Y581000D02*
Y573482D01*
G01X1764000Y588500D02*
X1756500Y581000D01*
G01X1729193Y534196D02*
X1721469Y526472D01*
G01X1729193Y542612D02*
Y534196D01*
G01X1737581Y551000D02*
X1729193Y542612D01*
G01X1738088Y551000D02*
X1737581D01*
G01X1733794Y541279D02*
Y534349D01*
G01X1740286Y547771D02*
X1733794Y541279D01*
G01X1740286Y554696D02*
Y547771D01*
G01X1739151Y555831D02*
X1740286Y554696D01*
G01X1737380Y555831D02*
X1739151D01*
G01X1736294Y556917D02*
X1737380Y555831D01*
G01X1736294Y566057D02*
Y556917D01*
G01X1741813Y571576D02*
X1736294Y566057D01*
G01X1747938Y571576D02*
X1741813D01*
G01X1749058Y572696D02*
X1747938Y571576D01*
G01X1749058Y587627D02*
Y572696D01*
G01X1743246Y593439D02*
X1749058Y587627D01*
G01X1727224Y534638D02*
X1720762Y528176D01*
G01X1727224Y559164D02*
Y534638D01*
G01X1728400Y560340D02*
X1727224Y559164D01*
G01X1728400Y577586D02*
Y560340D01*
G01X1730774Y579960D02*
X1728400Y577586D01*
G01X1762089Y531023D02*
X1752592D01*
G01X1767053Y535987D02*
X1762089Y531023D01*
G01X1767053Y551933D02*
Y535987D01*
G01X1764000Y554986D02*
X1767053Y551933D01*
G01X1764000Y567000D02*
Y554986D01*
G01X1760048Y570952D02*
X1764000Y567000D01*
G01X1760048Y578420D02*
Y570952D01*
G01X1767228Y585600D02*
X1760048Y578420D01*
G01X1767228Y596320D02*
Y585600D01*
G01X1734546Y540967D02*
Y534037D01*
G01X1744576Y550997D02*
X1734546Y540967D01*
G01X1744576Y555532D02*
Y550997D01*
G01X1739608Y560500D02*
X1744576Y555532D01*
G01X1737958Y560500D02*
X1739608D01*
G01X1762559Y526716D02*
X1756847D01*
G01X1771737Y535894D02*
X1762559Y526716D01*
G01X1785006Y535894D02*
X1771737D01*
G01X1718916Y575440D02*
Y576738D01*
G01X1718923Y575433D02*
X1718916Y575440D01*
G01X1718923Y560409D02*
Y575433D01*
G01X1759797Y589555D02*
X1762062D01*
G01X1749576Y599776D02*
X1759797Y589555D01*
G01X1726664Y599776D02*
X1749576D01*
G01X1722316Y595428D02*
X1726664Y599776D01*
G01X1759289Y592055D02*
X1762062D01*
G01X1750160Y601184D02*
X1759289Y592055D01*
G01X1726080Y601184D02*
X1750160D01*
G01X1720908Y596012D02*
X1726080Y601184D01*
G01X1761063Y598244D02*
X1765500Y593807D01*
G01X1761063Y605663D02*
Y598244D01*
G01X1756397Y610329D02*
X1761063Y605663D01*
G01X1732847Y610329D02*
X1756397D01*
G01X1729944Y607426D02*
X1732847Y610329D01*
G01X1720379Y607426D02*
X1729944D01*
G01X1719501Y606548D02*
X1720379Y607426D01*
G01X1761895Y598476D02*
X1766476Y593895D01*
G01X1761895Y605895D02*
Y598476D01*
G01X1756159Y611631D02*
X1761895Y605895D01*
G01X1715609Y611631D02*
X1756159D01*
G01X1755535Y613135D02*
X1714575D01*
G01X1755536Y613136D02*
X1755535Y613135D01*
G01X1756782Y613136D02*
X1755536D01*
G01X1756783Y613135D02*
X1756782Y613136D01*
G01X1758640Y613135D02*
X1756783D01*
G01X1768728Y603047D02*
X1758640Y613135D01*
G01X1768728Y596307D02*
Y603047D01*
G01X1767989Y595568D02*
X1768728Y596307D01*
G01X1767980Y595568D02*
X1767989D01*
G01X1768374Y615256D02*
X1764912Y618718D01*
G01X1768374Y606327D02*
Y615256D01*
G01X1772578Y602123D02*
X1768374Y606327D01*
G01X1764000Y593000D02*
Y588500D01*
G01X1754662Y602338D02*
X1764000Y593000D01*
G01X1754662Y604422D02*
Y602338D01*
G01X1757319Y607079D02*
X1754662Y604422D01*
G01X1757319Y606953D02*
Y607079D01*
G01X1741779Y593439D02*
X1743246D01*
G01X1740755Y592415D02*
X1741779Y593439D01*
G01X1740755Y589739D02*
Y592415D01*
G01X1740002Y588986D02*
X1740755Y589739D01*
G01X1738434Y588986D02*
X1740002D01*
G01X1767976Y597068D02*
X1767228Y596320D01*
G01X1767976Y602735D02*
Y597068D01*
G01X1758328Y612383D02*
X1767976Y602735D01*
G01X1756471Y612383D02*
X1758328D01*
G01X1756470Y612384D02*
X1756471Y612383D01*
G01X1755848Y612384D02*
X1756470D01*
G01X1755847Y612383D02*
X1755848Y612384D01*
G01X1715297Y612383D02*
X1755847D01*
G01X1813913Y2295D02*
Y2287D01*
G01X1818568Y6950D02*
X1813913Y2295D01*
G01X1818568Y13782D02*
Y6950D01*
G01X1814157Y18193D02*
X1818568Y13782D01*
G01X1814157Y18313D02*
Y18193D01*
G01X1814156Y18314D02*
X1814157Y18313D01*
G01X1814156Y19268D02*
Y18314D01*
G01X1814157Y19269D02*
X1814156Y19268D01*
G01X1814157Y23428D02*
Y19269D01*
G01X1824346Y33617D02*
X1814157Y23428D01*
G01X1832000Y7500D02*
X1835600Y3900D01*
G01X1828500Y7500D02*
X1832000D01*
G01X1825700Y10300D02*
X1828500Y7500D01*
G01X1825700Y15400D02*
Y10300D01*
G01X1821700Y19400D02*
X1825700Y15400D01*
G01X1821700Y22900D02*
Y19400D01*
G01X1827808Y29008D02*
X1821700Y22900D01*
G01X1829008Y29008D02*
X1827808D01*
G01X1835924Y35924D02*
X1829008Y29008D01*
G01X1830066Y15759D02*
X1838091D01*
G01X1827100Y12793D02*
X1830066Y15759D01*
G01X1827100Y10264D02*
Y12793D01*
G01X1828864Y8500D02*
X1827100Y10264D01*
G01X1836700Y8500D02*
X1828864D01*
G01X1827983Y23700D02*
X1838200D01*
G01X1825870Y21587D02*
X1827983Y23700D01*
G01X1812150Y31414D02*
X1810772Y32792D01*
G01X1812150Y25620D02*
Y31414D01*
G01X1810700Y24170D02*
X1812150Y25620D01*
G01X1810700Y13031D02*
Y24170D01*
G01X1813950Y9781D02*
X1810700Y13031D01*
G01X1816723Y9781D02*
X1813950D01*
G01X1834349Y15007D02*
X1832842Y13500D01*
G01X1838675Y15007D02*
X1834349D01*
G01X1828531Y30161D02*
X1834772Y36402D01*
G01X1826069Y30161D02*
X1828531D01*
G01X1818261Y22353D02*
X1826069Y30161D01*
G01X1818261Y20116D02*
Y22353D01*
G01X1822024Y16353D02*
X1818261Y20116D01*
G01X1822024Y5981D02*
Y16353D01*
G01X1824564Y3441D02*
X1822024Y5981D01*
G01X1785104Y600D02*
X1779504Y-5000D01*
G01X1787436Y600D02*
X1785104D01*
G01X1787588Y752D02*
X1787436Y600D01*
G01X1803759Y752D02*
X1787588D01*
G01X1803835Y828D02*
X1803759Y752D01*
G01X1805765Y828D02*
X1803835D01*
G01X1805840Y753D02*
X1805765Y828D01*
G01X1806411Y753D02*
X1805840D01*
G01X1806564Y600D02*
X1806411Y753D01*
G01X1815806Y600D02*
X1806564D01*
G01X1819720Y4514D02*
X1815806Y600D01*
G01X1819720Y14380D02*
Y4514D01*
G01X1815309Y18791D02*
X1819720Y14380D01*
G01X1815309Y22950D02*
Y18791D01*
G01X1824823Y32464D02*
X1815309Y22950D01*
G01X1825112Y32464D02*
X1824823D01*
G01X1825113Y32465D02*
X1825112Y32464D01*
G01X1827494Y32465D02*
X1825113D01*
G01X1832430Y37401D02*
X1827494Y32465D01*
G01X1782939Y5497D02*
X1776351Y-1091D01*
G01X1794078Y5497D02*
X1782939D01*
G01X1796900Y8319D02*
X1794078Y5497D01*
G01X1796900Y13446D02*
Y8319D01*
G01X1801000Y17546D02*
X1796900Y13446D01*
G01X1801000Y27032D02*
Y17546D01*
G01X1806009Y32041D02*
X1801000Y27032D01*
G01X1806009Y43625D02*
Y32041D01*
G01X1830064Y29000D02*
X1838171D01*
G01X1829320Y28256D02*
X1830064Y29000D01*
G01X1828983Y28256D02*
X1829320D01*
G01X1823300Y22573D02*
X1828983Y28256D01*
G01X1823300Y21700D02*
Y22573D01*
G01X1820872Y3172D02*
X1819800Y2100D01*
G01X1820872Y15128D02*
Y3172D01*
G01X1817109Y18891D02*
X1820872Y15128D01*
G01X1817109Y22831D02*
Y18891D01*
G01X1825591Y31313D02*
X1817109Y22831D01*
G01X1827972Y31313D02*
X1825591D01*
G01X1833620Y36961D02*
X1827972Y31313D01*
G01X1807219Y10684D02*
X1808603Y9300D01*
G01X1807219Y13219D02*
Y10684D01*
G01X1809800Y15800D02*
X1807219Y13219D01*
G01X1809800Y24334D02*
Y15800D01*
G01X1811398Y25932D02*
X1809800Y24334D01*
G01X1811398Y31102D02*
Y25932D01*
G01X1810020Y32480D02*
X1811398Y31102D01*
G01X1810020Y41606D02*
Y32480D01*
G01X1827016Y33617D02*
X1824346D01*
G01X1831230Y37831D02*
X1827016Y33617D01*
G01X1831230Y39670D02*
Y37831D01*
G01X1830953Y39947D02*
X1831230Y39670D01*
G01X1830953Y60607D02*
Y39947D01*
G01X1825660Y65900D02*
X1830953Y60607D01*
G01X1820739Y65900D02*
X1825660D01*
G01X1816452Y70187D02*
X1820739Y65900D01*
G01X1816452Y82822D02*
Y70187D01*
G01X1816768Y83138D02*
X1816452Y82822D01*
G01X1816768Y105732D02*
Y83138D01*
G01X1817677Y55471D02*
X1818396Y54752D01*
G01X1817677Y62047D02*
Y55471D01*
G01X1801330Y78394D02*
X1817677Y62047D01*
G01X1799248Y78394D02*
X1801330D01*
G01X1799248Y78439D02*
Y78394D01*
G01X1794295Y83392D02*
X1799248Y78439D01*
G01X1787108Y83392D02*
X1794295D01*
G01X1819972Y42715D02*
X1817186Y39929D01*
G01X1819972Y61700D02*
Y42715D01*
G01X1812169Y69503D02*
X1819972Y61700D01*
G01X1812169Y70770D02*
Y69503D01*
G01X1789776Y93163D02*
X1812169Y70770D01*
G01X1789776Y93653D02*
Y93163D01*
G01X1788853Y94576D02*
X1789776Y93653D01*
G01X1823079Y35486D02*
X1826414D01*
G01X1820765Y33172D02*
X1823079Y35486D01*
G01X1817796Y33172D02*
X1820765D01*
G01X1814270Y36698D02*
X1817796Y33172D01*
G01X1814270Y40050D02*
Y36698D01*
G01X1799788Y54532D02*
X1814270Y40050D01*
G01X1799788Y58081D02*
Y54532D01*
G01X1800952Y59245D02*
X1799788Y58081D01*
G01X1800952Y70025D02*
Y59245D01*
G01X1796654Y74323D02*
X1800952Y70025D01*
G01X1791082Y74323D02*
X1796654D01*
G01X1828022Y37062D02*
X1829580Y38620D01*
G01X1825348Y37062D02*
X1828022D01*
G01X1825261Y36975D02*
X1825348Y37062D01*
G01X1823504Y36975D02*
X1825261D01*
G01X1820453Y33924D02*
X1823504Y36975D01*
G01X1818108Y33924D02*
X1820453D01*
G01X1815288Y36744D02*
X1818108Y33924D01*
G01X1815288Y40096D02*
Y36744D01*
G01X1800543Y54841D02*
X1815288Y40096D01*
G01X1800543Y57723D02*
Y54841D01*
G01X1801704Y58884D02*
X1800543Y57723D01*
G01X1801704Y70337D02*
Y58884D01*
G01X1796931Y75110D02*
X1801704Y70337D01*
G01X1791359Y75110D02*
X1796931D01*
G01X1796363Y73550D02*
X1790225D01*
G01X1800200Y69713D02*
X1796363Y73550D01*
G01X1800200Y59587D02*
Y69713D01*
G01X1798980Y58367D02*
X1800200Y59587D01*
G01X1798980Y53710D02*
Y58367D01*
G01X1810773Y41917D02*
X1798980Y53710D01*
G01X1810773Y41295D02*
Y41917D01*
G01X1810772Y41294D02*
X1810773Y41295D01*
G01X1810772Y32792D02*
Y41294D01*
G01X1828726Y93736D02*
Y106744D01*
G01X1822664Y87674D02*
X1828726Y93736D01*
G01X1822664Y83027D02*
Y87674D01*
G01X1829584Y76107D02*
X1822664Y83027D01*
G01X1829584Y69822D02*
Y76107D01*
G01X1835100Y64306D02*
X1829584Y69822D01*
G01X1835100Y46312D02*
Y64306D01*
G01X1840076Y41336D02*
X1835100Y46312D01*
G01X1834772Y37131D02*
X1836094Y38453D01*
G01X1834772Y36402D02*
Y37131D01*
G01X1832430Y61171D02*
Y37401D01*
G01X1826266Y67335D02*
X1832430Y61171D01*
G01X1820934Y67335D02*
X1826266D01*
G01X1817604Y70665D02*
X1820934Y67335D01*
G01X1817604Y82344D02*
Y70665D01*
G01X1818300Y83040D02*
X1817604Y82344D01*
G01X1818300Y109455D02*
Y83040D01*
G01X1802334Y47300D02*
X1806009Y43625D01*
G01X1796592Y47300D02*
X1802334D01*
G01X1790210Y53682D02*
X1796592Y47300D01*
G01X1790210Y62120D02*
Y53682D01*
G01X1786420Y65910D02*
X1790210Y62120D01*
G01X1786420Y68932D02*
Y65910D01*
G01X1795018Y90282D02*
Y102467D01*
G01X1813393Y71907D02*
X1795018Y90282D01*
G01X1813393Y69986D02*
Y71907D01*
G01X1820631Y62748D02*
X1813393Y69986D01*
G01X1825552Y62748D02*
X1820631D01*
G01X1828576Y59724D02*
X1825552Y62748D01*
G01X1828576Y52161D02*
Y59724D01*
G01X1823756Y47341D02*
X1828576Y52161D01*
G01X1823756Y41758D02*
Y47341D01*
G01X1824130Y41384D02*
X1823756Y41758D01*
G01X1824130Y39703D02*
Y41384D01*
G01X1824240Y86629D02*
Y83680D01*
G01X1831892Y94281D02*
X1824240Y86629D01*
G01X1831892Y105208D02*
Y94281D01*
G01X1833620Y38141D02*
Y36961D01*
G01X1835876Y40397D02*
X1833620Y38141D01*
G01X1833582Y44168D02*
X1835876Y41874D01*
G01X1833582Y62918D02*
Y44168D01*
G01X1827500Y69000D02*
X1833582Y62918D01*
G01X1827500Y71391D02*
Y69000D01*
G01X1823991Y74900D02*
X1827500Y71391D01*
G01X1820513Y74900D02*
X1823991D01*
G01X1818779Y76634D02*
X1820513Y74900D01*
G01X1818779Y81879D02*
Y76634D01*
G01X1819600Y82700D02*
X1818779Y81879D01*
G01X1819600Y109881D02*
Y82700D01*
G01X1798228Y53398D02*
X1810020Y41606D01*
G01X1798228Y58679D02*
Y53398D01*
G01X1799448Y59899D02*
X1798228Y58679D01*
G01X1799448Y69401D02*
Y59899D01*
G01X1796051Y72798D02*
X1799448Y69401D01*
G01X1789913Y72798D02*
X1796051D01*
G01X1816725Y55863D02*
X1815637Y54775D01*
G01X1816725Y61652D02*
Y55863D01*
G01X1800735Y77642D02*
X1816725Y61652D01*
G01X1798821Y77642D02*
X1800735D01*
G01X1794158Y82305D02*
X1798821Y77642D01*
G01X1786848Y82305D02*
X1794158D01*
G01X1821458Y38127D02*
X1820457Y39128D01*
G01X1824783Y38127D02*
X1821458D01*
G01X1824870Y38214D02*
X1824783Y38127D01*
G01X1826943Y38214D02*
X1824870D01*
G01X1829728Y40999D02*
X1826943Y38214D01*
G01X1829728Y60202D02*
Y40999D01*
G01X1826030Y63900D02*
X1829728Y60202D01*
G01X1821109Y63900D02*
X1826030D01*
G01X1815300Y69709D02*
X1821109Y63900D01*
G01X1815300Y72400D02*
Y69709D01*
G01X1801600Y86100D02*
X1815300Y72400D01*
G01X1801600Y104100D02*
Y86100D01*
G01X1807818Y114682D02*
X1816768Y105732D01*
G01X1807818Y124179D02*
Y114682D01*
G01X1793128Y155804D02*
X1788479Y160453D01*
G01X1793128Y140830D02*
Y155804D01*
G01X1798206Y135752D02*
X1793128Y140830D01*
G01X1800168Y135752D02*
X1798206D01*
G01X1805837Y130083D02*
X1800168Y135752D01*
G01X1805837Y125478D02*
Y130083D01*
G01X1798872Y118513D02*
X1805837Y125478D01*
G01X1798872Y111144D02*
Y118513D01*
G01X1807092Y102924D02*
X1798872Y111144D01*
G01X1808669Y102924D02*
X1807092D01*
G01X1810245Y104500D02*
X1808669Y102924D01*
G01X1787739Y94576D02*
X1788853D01*
G01X1776239Y106076D02*
X1787739Y94576D01*
G01X1824990Y108850D02*
Y103620D01*
G01X1821789Y112051D02*
X1824990Y108850D01*
G01X1821789Y134586D02*
Y112051D01*
G01X1813400Y142975D02*
X1821789Y134586D01*
G01X1813400Y149848D02*
Y142975D01*
G01X1807918Y155330D02*
X1813400Y149848D01*
G01X1807918Y156138D02*
Y155330D01*
G01X1802728Y161328D02*
X1807918Y156138D01*
G01X1822198Y142587D02*
X1821348Y143437D01*
G01X1822198Y140602D02*
Y142587D01*
G01X1786199Y150099D02*
X1790100Y154000D01*
G01X1775976Y150099D02*
X1786199D01*
G01X1817924Y154884D02*
Y157847D01*
G01X1817248Y154208D02*
X1817924Y154884D01*
G01X1817248Y140774D02*
Y154208D01*
G01X1822941Y135081D02*
X1817248Y140774D01*
G01X1822941Y112529D02*
Y135081D01*
G01X1828726Y106744D02*
X1822941Y112529D01*
G01X1816348Y121478D02*
X1815026D01*
G01X1821037Y126167D02*
X1816348Y121478D01*
G01X1821037Y134274D02*
Y126167D01*
G01X1818211Y137100D02*
X1821037Y134274D01*
G01X1815238Y137100D02*
X1818211D01*
G01X1805590Y146748D02*
X1815238Y137100D01*
G01X1805590Y156338D02*
Y146748D01*
G01X1797936Y142824D02*
Y164235D01*
G01X1799612Y141148D02*
X1797936Y142824D01*
G01X1807045Y141148D02*
X1799612D01*
G01X1814307Y133886D02*
X1807045Y141148D01*
G01X1814307Y132624D02*
Y133886D01*
G01X1816627Y130304D02*
X1814307Y132624D01*
G01X1817383Y130304D02*
X1816627D01*
G01X1818746Y128941D02*
X1817383Y130304D01*
G01X1818746Y127011D02*
Y128941D01*
G01X1816139Y124404D02*
X1818746Y127011D01*
G01X1814015Y124404D02*
X1816139D01*
G01X1812698Y123087D02*
X1814015Y124404D01*
G01X1812698Y119102D02*
Y123087D01*
G01X1814900Y116900D02*
X1812698Y119102D01*
G01X1810794Y116961D02*
X1818300Y109455D01*
G01X1810794Y124337D02*
Y116961D01*
G01X1812857Y126400D02*
X1810794Y124337D01*
G01X1813771Y126400D02*
X1812857D01*
G01X1814694Y127323D02*
X1813771Y126400D01*
G01X1814694Y129543D02*
Y127323D01*
G01X1808226Y136011D02*
X1814694Y129543D01*
G01X1808226Y136171D02*
Y136011D01*
G01X1807166Y155826D02*
X1801976Y161016D01*
G01X1807166Y147401D02*
Y155826D01*
G01X1821350Y110450D02*
Y98270D01*
G01X1817800Y114000D02*
X1821350Y110450D01*
G01X1817800Y116265D02*
Y114000D01*
G01X1813450Y120615D02*
X1817800Y116265D01*
G01X1813450Y122591D02*
Y120615D01*
G01X1814369Y123510D02*
X1813450Y122591D01*
G01X1816309Y123510D02*
X1814369D01*
G01X1820285Y127486D02*
X1816309Y123510D01*
G01X1820285Y133949D02*
Y127486D01*
G01X1818224Y136010D02*
X1820285Y133949D01*
G01X1814311Y136010D02*
X1818224D01*
G01X1804007Y146314D02*
X1814311Y136010D01*
G01X1804007Y155377D02*
Y146314D01*
G01X1799484Y159900D02*
X1804007Y155377D01*
G01X1815883Y133374D02*
Y133277D01*
G01X1807357Y141900D02*
X1815883Y133374D01*
G01X1799924Y141900D02*
X1807357D01*
G01X1798688Y143136D02*
X1799924Y141900D01*
G01X1798688Y166129D02*
Y143136D01*
G01X1806500Y113518D02*
X1808313Y111705D01*
G01X1806500Y115419D02*
Y113518D01*
G01X1804619Y117300D02*
X1806500Y115419D01*
G01X1804619Y123196D02*
Y117300D01*
G01X1806589Y125166D02*
X1804619Y123196D01*
G01X1806589Y125179D02*
Y125166D01*
G01X1809085Y127675D02*
X1806589Y125179D01*
G01X1809085Y130437D02*
Y127675D01*
G01X1802266Y137256D02*
X1809085Y130437D01*
G01X1798830Y137256D02*
X1802266D01*
G01X1794632Y141454D02*
X1798830Y137256D01*
G01X1794632Y156428D02*
Y141454D01*
G01X1822950Y140970D02*
X1824748Y139172D01*
G01X1822950Y142539D02*
Y140970D01*
G01X1824064Y143653D02*
X1822950Y142539D01*
G01X1824509Y143653D02*
X1824064D01*
G01X1793880Y156116D02*
X1788577Y161419D01*
G01X1793880Y141142D02*
Y156116D01*
G01X1798518Y136504D02*
X1793880Y141142D01*
G01X1800896Y136504D02*
X1798518D01*
G01X1806600Y130800D02*
X1800896Y136504D01*
G01X1806600Y129409D02*
Y130800D01*
G01X1807509Y128500D02*
X1806600Y129409D01*
G01X1774607Y153655D02*
Y158573D01*
G01X1776253Y152009D02*
X1774607Y153655D01*
G01X1781723Y152009D02*
X1776253D01*
G01X1786460Y156746D02*
X1781723Y152009D01*
G01X1792376Y154282D02*
X1789912Y156746D01*
G01X1792376Y140518D02*
Y154282D01*
G01X1797894Y135000D02*
X1792376Y140518D01*
G01X1799856Y135000D02*
X1797894D01*
G01X1805085Y129771D02*
X1799856Y135000D01*
G01X1805085Y126984D02*
Y129771D01*
G01X1800792Y122691D02*
X1805085Y126984D01*
G01X1788441Y130953D02*
Y132382D01*
G01X1793015Y126379D02*
X1788441Y130953D01*
G01X1793015Y104470D02*
Y126379D01*
G01X1795018Y102467D02*
X1793015Y104470D01*
G01X1795583Y128500D02*
X1803509D01*
G01X1824093Y113007D02*
X1831892Y105208D01*
G01X1824093Y135559D02*
Y113007D01*
G01X1818400Y141252D02*
X1824093Y135559D01*
G01X1818400Y148853D02*
Y141252D01*
G01X1824852Y155305D02*
X1818400Y148853D01*
G01X1824852Y167683D02*
Y155305D01*
G01X1776828Y158268D02*
Y155211D01*
G01X1811946Y117535D02*
X1819600Y109881D01*
G01X1811946Y123399D02*
Y117535D01*
G01X1813779Y125232D02*
X1811946Y123399D01*
G01X1815903Y125232D02*
X1813779D01*
G01X1817994Y127323D02*
X1815903Y125232D01*
G01X1817994Y128629D02*
Y127323D01*
G01X1817071Y129552D02*
X1817994Y128629D01*
G01X1816315Y129552D02*
X1817071D01*
G01X1813555Y132312D02*
X1816315Y129552D01*
G01X1813555Y132472D02*
Y132312D01*
G01X1813553Y132474D02*
X1813555Y132472D01*
G01X1813553Y133576D02*
Y132474D01*
G01X1806734Y140395D02*
X1813553Y133576D01*
G01X1799301Y140395D02*
X1806734D01*
G01X1797184Y142512D02*
X1799301Y140395D01*
G01X1797184Y163923D02*
Y142512D01*
G01X1797720Y107980D02*
X1801600Y104100D01*
G01X1797720Y118991D02*
Y107980D01*
G01X1798076Y119347D02*
X1797720Y118991D01*
G01X1798076Y124299D02*
Y119347D01*
G01X1789593Y132782D02*
X1798076Y124299D01*
G01X1789593Y132860D02*
Y132782D01*
G01X1825604Y154993D02*
Y166995D01*
G01X1825441Y154830D02*
X1825604Y154993D01*
G01X1825441Y154826D02*
Y154830D01*
G01X1819200Y148585D02*
X1825441Y154826D01*
G01X1819200Y141903D02*
Y148585D01*
G01X1822206Y138897D02*
X1819200Y141903D01*
G01X1822206Y138896D02*
Y138897D01*
G01X1825602Y135500D02*
X1822206Y138896D01*
G01X1845469Y135500D02*
X1825602D01*
G01X1780799Y160453D02*
X1774393Y166859D01*
G01X1788479Y160453D02*
X1780799D01*
G01X1802728Y168952D02*
Y161328D01*
G01X1801080Y170600D02*
X1802728Y168952D01*
G01X1801080Y172979D02*
Y170600D01*
G01X1801707Y173606D02*
X1801080Y172979D01*
G01X1810694Y173606D02*
X1801707D01*
G01X1812148Y172152D02*
X1810694Y173606D01*
G01X1816219Y172152D02*
X1812148D01*
G01X1819949Y168422D02*
X1816219Y172152D01*
G01X1823005Y168422D02*
X1819949D01*
G01X1825776Y171193D02*
X1823005Y168422D01*
G01X1825776Y180288D02*
Y171193D01*
G01X1814512Y191552D02*
X1825776Y180288D01*
G01X1824200Y180800D02*
X1814200Y190800D01*
G01X1824200Y176900D02*
Y180800D01*
G01X1814772Y168139D02*
X1816125Y169492D01*
G01X1814772Y160999D02*
Y168139D01*
G01X1817924Y157847D02*
X1814772Y160999D01*
G01X1801224Y160704D02*
X1805590Y156338D01*
G01X1801224Y168328D02*
Y160704D01*
G01X1799576Y169976D02*
X1801224Y168328D01*
G01X1799576Y175453D02*
Y169976D01*
G01X1798245Y176784D02*
X1799576Y175453D01*
G01X1798245Y179728D02*
Y176784D01*
G01X1791469Y186504D02*
X1798245Y179728D01*
G01X1781252Y172721D02*
X1775615D01*
G01X1782486Y171487D02*
X1781252Y172721D01*
G01X1786869Y171487D02*
X1782486D01*
G01X1790312Y168044D02*
X1786869Y171487D01*
G01X1794127Y168044D02*
X1790312D01*
G01X1797936Y164235D02*
X1794127Y168044D01*
G01X1798997Y182441D02*
X1793897Y187541D01*
G01X1798997Y177096D02*
Y182441D01*
G01X1800328Y175765D02*
X1798997Y177096D01*
G01X1800328Y170288D02*
Y175765D01*
G01X1801976Y168640D02*
X1800328Y170288D01*
G01X1801976Y161016D02*
Y168640D01*
G01X1799484Y166397D02*
Y159900D01*
G01X1796333Y169548D02*
X1799484Y166397D01*
G01X1792000Y169548D02*
X1796333D01*
G01X1788048Y173500D02*
X1792000Y169548D01*
G01X1782601Y173500D02*
X1788048D01*
G01X1781865Y174236D02*
X1782601Y173500D01*
G01X1777364Y174236D02*
X1781865D01*
G01X1774800Y176800D02*
X1777364Y174236D01*
G01X1774800Y181356D02*
Y176800D01*
G01X1796021Y168796D02*
X1798688Y166129D01*
G01X1790624Y168796D02*
X1796021D01*
G01X1787063Y172357D02*
X1790624Y168796D01*
G01X1782680Y172357D02*
X1787063D01*
G01X1781564Y173473D02*
X1782680Y172357D01*
G01X1775927Y173473D02*
X1781564D01*
G01X1774100Y175300D02*
X1775927Y173473D01*
G01X1774100Y175472D02*
Y175300D01*
G01X1774048Y175524D02*
X1774100Y175472D01*
G01X1774048Y181044D02*
Y175524D01*
G01X1788889Y162171D02*
X1794632Y156428D01*
G01X1784889Y162171D02*
X1788889D01*
G01X1781800Y165260D02*
X1784889Y162171D01*
G01X1781800Y166193D02*
Y165260D01*
G01X1778878Y169115D02*
X1781800Y166193D01*
G01X1781048Y165881D02*
X1778566Y168363D01*
G01X1781048Y165572D02*
Y165881D01*
G01X1781047Y165571D02*
X1781048Y165572D01*
G01X1781047Y164949D02*
Y165571D01*
G01X1784577Y161419D02*
X1781047Y164949D01*
G01X1788577Y161419D02*
X1784577D01*
G01X1789912Y156746D02*
X1786460D01*
G01X1812600Y177972D02*
X1802276Y188296D01*
G01X1812600Y176656D02*
Y177972D01*
G01X1814933Y174323D02*
X1812600Y176656D01*
G01X1816950Y174323D02*
X1814933D01*
G01X1821261Y170012D02*
X1816950Y174323D01*
G01X1830415Y194243D02*
X1828476Y192304D01*
G01X1830415Y196567D02*
Y194243D01*
G01X1830795Y173626D02*
X1824852Y167683D01*
G01X1830795Y190598D02*
Y173626D01*
G01X1831991Y191794D02*
X1830795Y190598D01*
G01X1831991Y197738D02*
Y191794D01*
G01X1826437Y203292D02*
X1831991Y197738D01*
G01X1787000Y179439D02*
X1780691Y185748D01*
G01X1787000Y175500D02*
Y179439D01*
G01X1793815Y167292D02*
X1797184Y163923D01*
G01X1790000Y167292D02*
X1793815D01*
G01X1786837Y170455D02*
X1790000Y167292D01*
G01X1782454Y170455D02*
X1786837D01*
G01X1781191Y171718D02*
X1782454Y170455D01*
G01X1778900Y165800D02*
X1777089Y167611D01*
G01X1834195Y199257D02*
X1829408Y204044D01*
G01X1834195Y192883D02*
Y199257D01*
G01X1831812Y190500D02*
X1834195Y192883D01*
G01X1831812Y173203D02*
Y190500D01*
G01X1825604Y166995D02*
X1831812Y173203D01*
G01X1825362Y246781D02*
X1841093D01*
G01X1822724Y249419D02*
X1825362Y246781D01*
G01X1822724Y251959D02*
Y249419D01*
G01X1821571Y253112D02*
X1822724Y251959D01*
G01X1821857Y251519D02*
X1821016Y252360D01*
G01X1821857Y249222D02*
Y251519D01*
G01X1825078Y246001D02*
X1821857Y249222D01*
G01X1840802Y246001D02*
X1825078D01*
G01X1833644Y247933D02*
X1842300D01*
G01X1827313Y254264D02*
X1833644Y247933D01*
G01X1842769Y484599D02*
X1819922Y461752D01*
G01X1823944Y461167D02*
X1838877Y476100D01*
G01X1823914Y461167D02*
X1823944D01*
G01X1820596Y457849D02*
X1823914Y461167D01*
G01X1823549Y462119D02*
X1838730Y477300D01*
G01X1823519Y462119D02*
X1823549D01*
G01X1820201Y458801D02*
X1823519Y462119D01*
G01X1843017Y483500D02*
X1820317Y460800D01*
G01X1825931Y519000D02*
X1828200D01*
G01X1822359Y515428D02*
X1825931Y519000D01*
G01X1822359Y505992D02*
Y515428D01*
G01X1827975Y500376D02*
X1822359Y505992D01*
G01X1845324Y500376D02*
X1827975D01*
G01X1775309Y498649D02*
Y489827D01*
G01X1788532Y511872D02*
X1775309Y498649D01*
G01X1804070Y511872D02*
X1788532D01*
G01X1813675Y521477D02*
X1804070Y511872D01*
G01X1817764Y521477D02*
X1813675D01*
G01X1822467Y526180D02*
X1817764Y521477D01*
G01X1822467Y549542D02*
Y526180D01*
G01X1817452Y522229D02*
X1821715Y526492D01*
G01X1812797Y522229D02*
X1817452D01*
G01X1803192Y512624D02*
X1812797Y522229D01*
G01X1795500Y512624D02*
X1803192D01*
G01X1793748Y514376D02*
X1795500Y512624D01*
G01X1812391Y507291D02*
X1838600Y533500D01*
G01X1812391Y504391D02*
Y507291D01*
G01X1808100Y500100D02*
X1812391Y504391D01*
G01X1801900Y500100D02*
X1808100D01*
G01X1795260Y493460D02*
X1801900Y500100D01*
G01X1783050Y493460D02*
X1795260D01*
G01X1781700Y492110D02*
X1783050Y493460D01*
G01X1781700Y485869D02*
Y492110D01*
G01X1779788Y494905D02*
Y485587D01*
G01X1781020Y496137D02*
X1779788Y494905D01*
G01X1781020Y503296D02*
Y496137D01*
G01X1786824Y509100D02*
X1781020Y503296D01*
G01X1811519Y509100D02*
X1786824D01*
G01X1825076Y522657D02*
X1811519Y509100D01*
G01X1825076Y522676D02*
Y522657D01*
G01X1825900Y523500D02*
X1825076Y522676D01*
G01X1808774Y526303D02*
X1809697Y527226D01*
G01X1808774Y523994D02*
Y526303D01*
G01X1804571Y519791D02*
X1808774Y523994D01*
G01X1798709Y519791D02*
X1804571D01*
G01X1785351Y533149D02*
X1798709Y519791D01*
G01X1805558Y518424D02*
X1775962D01*
G01X1812058Y524924D02*
X1805558Y518424D01*
G01X1816024Y524924D02*
X1812058D01*
G01X1816800Y525700D02*
X1816024Y524924D01*
G01X1828382Y472204D02*
X1836396Y480218D01*
G01X1824224Y472204D02*
X1828382D01*
G01X1824139Y472289D02*
X1824224Y472204D01*
G01X1812872Y472289D02*
X1824139D01*
G01X1809528Y468945D02*
X1812872Y472289D01*
G01X1795200Y525700D02*
X1785006Y535894D01*
G01X1816092Y555917D02*
X1822467Y549542D01*
G01X1809513Y555917D02*
X1816092D01*
G01X1809309Y555713D02*
X1809513Y555917D01*
G01X1821715Y533440D02*
X1810052Y545103D01*
G01X1821715Y526492D02*
Y533440D01*
G01X1803752Y574220D02*
Y529301D01*
G01X1811200Y581668D02*
X1803752Y574220D01*
G01X1811200Y583801D02*
Y581668D01*
G01X1801474Y593527D02*
X1811200Y583801D01*
G01X1818073Y582080D02*
X1816052Y584101D01*
G01X1829550Y582080D02*
X1818073D01*
G01X1832472Y585002D02*
X1829550Y582080D01*
G01X1832472Y586519D02*
Y585002D01*
G01X1833224Y587271D02*
X1832472Y586519D01*
G01X1833224Y593093D02*
Y587271D01*
G01X1801170Y568080D02*
X1793660Y560570D01*
G01X1801170Y574370D02*
Y568080D01*
G01X1809600Y582800D02*
X1801170Y574370D01*
G01X1832472Y587583D02*
Y594984D01*
G01X1829176Y584287D02*
X1832472Y587583D01*
G01X1812774Y527226D02*
X1813500Y526500D01*
G01X1809697Y527226D02*
X1812774D01*
G01X1800378Y593527D02*
X1801474D01*
G01X1836952Y596821D02*
X1833224Y593093D01*
G01X1835118Y597630D02*
X1840555D01*
G01X1832472Y594984D02*
X1835118Y597630D01*
G01X1891448Y23936D02*
Y56512D01*
G01X1887026Y19514D02*
X1891448Y23936D01*
G01X1880886Y19514D02*
X1887026D01*
G01X1879600Y20800D02*
X1880886Y19514D01*
G01X1878262Y20800D02*
X1879600D01*
G01X1876881Y22181D02*
X1878262Y20800D01*
G01X1866524Y32025D02*
X1874699Y40200D01*
G01X1847924Y32025D02*
X1866524D01*
G01X1843196Y27297D02*
X1847924Y32025D01*
G01X1843196Y20864D02*
Y27297D01*
G01X1838091Y15759D02*
X1843196Y20864D01*
G01X1837900Y9700D02*
X1836700Y8500D01*
G01X1844245Y29745D02*
Y44515D01*
G01X1838200Y23700D02*
X1844245Y29745D01*
G01X1843949Y20281D02*
X1838675Y15007D01*
G01X1843949Y23346D02*
Y20281D01*
G01X1843948Y23347D02*
X1843949Y23346D01*
G01X1843948Y26435D02*
Y23347D01*
G01X1848786Y31273D02*
X1843948Y26435D01*
G01X1866932Y31273D02*
X1848786D01*
G01X1871467Y35808D02*
X1866932Y31273D01*
G01X1892400Y23541D02*
Y56400D01*
G01X1887421Y18562D02*
X1892400Y23541D01*
G01X1880491Y18562D02*
X1887421D01*
G01X1879205Y19848D02*
X1880491Y18562D01*
G01X1878179Y19848D02*
X1879205D01*
G01X1876792Y18461D02*
X1878179Y19848D01*
G01X1838171Y29000D02*
X1843470Y34299D01*
G01X1841879Y11179D02*
X1840400Y9700D01*
G01X1841879Y16121D02*
Y11179D01*
G01X1844701Y18943D02*
X1841879Y16121D01*
G01X1844701Y23034D02*
Y18943D01*
G01X1844702Y23035D02*
X1844701Y23034D01*
G01X1844702Y23657D02*
Y23035D01*
G01X1844700Y23659D02*
X1844702Y23657D01*
G01X1844700Y26123D02*
Y23659D01*
G01X1849098Y30521D02*
X1844700Y26123D01*
G01X1866620Y30521D02*
X1849098D01*
G01X1866621Y30520D02*
X1866620Y30521D01*
G01X1867243Y30520D02*
X1866621D01*
G01X1871727Y35004D02*
X1867243Y30520D01*
G01X1890255Y68600D02*
X1899000D01*
G01X1884500Y62845D02*
X1890255Y68600D01*
G01X1884500Y43049D02*
Y62845D01*
G01X1878997Y37546D02*
X1884500Y43049D01*
G01X1835924Y36653D02*
Y35924D01*
G01X1836571Y37300D02*
X1835924Y36653D01*
G01X1840200Y37300D02*
X1836571D01*
G01X1841800Y38900D02*
X1840200Y37300D01*
G01X1841800Y50000D02*
Y38900D01*
G01X1845800Y54000D02*
X1841800Y50000D01*
G01X1853000Y54000D02*
X1845800D01*
G01X1870723Y71723D02*
X1853000Y54000D01*
G01X1870723Y98477D02*
Y71723D01*
G01X1891448Y56512D02*
X1902336Y67400D01*
G01X1874699Y40200D02*
X1878800D01*
G01X1839400Y33800D02*
X1837500Y35700D01*
G01X1841551Y33800D02*
X1839400D01*
G01X1842718Y34967D02*
X1841551Y33800D01*
G01X1842718Y49854D02*
Y34967D01*
G01X1846112Y53248D02*
X1842718Y49854D01*
G01X1853312Y53248D02*
X1846112D01*
G01X1871475Y71411D02*
X1853312Y53248D01*
G01X1871475Y98789D02*
Y71411D01*
G01X1881581Y87800D02*
X1899873Y106092D01*
G01X1878662Y87800D02*
X1881581D01*
G01X1873252Y82390D02*
X1878662Y87800D01*
G01X1873252Y70800D02*
Y82390D01*
G01X1854196Y51744D02*
X1873252Y70800D01*
G01X1846736Y51744D02*
X1854196D01*
G01X1844222Y49230D02*
X1846736Y51744D01*
G01X1844222Y44538D02*
Y49230D01*
G01X1844245Y44515D02*
X1844222Y44538D01*
G01X1881315Y35808D02*
X1871467D01*
G01X1885260Y39753D02*
X1881315Y35808D01*
G01X1885260Y62541D02*
Y39753D01*
G01X1890189Y67470D02*
X1885260Y62541D01*
G01X1899470Y67470D02*
X1890189D01*
G01X1840076Y39747D02*
Y41336D01*
G01X1838781Y38452D02*
X1840076Y39747D01*
G01X1837349Y38452D02*
X1838781D01*
G01X1837348Y38453D02*
X1837349Y38452D01*
G01X1836094Y38453D02*
X1837348D01*
G01X1892400Y56400D02*
X1902448Y66448D01*
G01X1874283Y60626D02*
X1873956Y60299D01*
G01X1874283Y82357D02*
Y60626D01*
G01X1878974Y87048D02*
X1874283Y82357D01*
G01X1881893Y87048D02*
X1878974D01*
G01X1900625Y105780D02*
X1881893Y87048D01*
G01X1880700Y88900D02*
X1893063Y101263D01*
G01X1878698Y88900D02*
X1880700D01*
G01X1872500Y82702D02*
X1878698Y88900D01*
G01X1872500Y71372D02*
Y82702D01*
G01X1853624Y52496D02*
X1872500Y71372D01*
G01X1846424Y52496D02*
X1853624D01*
G01X1843470Y49542D02*
X1846424Y52496D01*
G01X1843470Y41958D02*
Y49542D01*
G01X1843471Y41957D02*
X1843470Y41958D01*
G01X1843471Y41335D02*
Y41957D01*
G01X1843470Y41334D02*
X1843471Y41335D01*
G01X1843470Y34299D02*
Y41334D01*
G01X1877775Y35004D02*
X1871727D01*
G01X1877827Y35056D02*
X1877775Y35004D01*
G01X1881627Y35056D02*
X1877827D01*
G01X1886012Y39441D02*
X1881627Y35056D01*
G01X1886012Y43241D02*
Y39441D01*
G01X1886260Y43489D02*
X1886012Y43241D01*
G01X1886260Y62477D02*
Y43489D01*
G01X1890421Y66638D02*
X1886260Y62477D01*
G01X1900338Y66638D02*
X1890421D01*
G01X1835876Y41874D02*
Y40397D01*
G01X1860300Y108900D02*
X1870723Y98477D01*
G01X1860300Y116300D02*
Y108900D01*
G01X1851258Y125342D02*
X1860300Y116300D01*
G01X1851258Y139390D02*
Y125342D01*
G01X1851868Y140000D02*
X1851258Y139390D01*
G01X1851868Y150280D02*
Y140000D01*
G01X1856301Y154713D02*
X1851868Y150280D01*
G01X1856301Y161299D02*
Y154713D01*
G01X1859352Y135386D02*
X1860969Y133769D01*
G01X1859352Y140012D02*
Y135386D01*
G01X1863519Y144179D02*
X1859352Y140012D01*
G01X1863519Y150381D02*
Y144179D01*
G01X1859800Y154100D02*
X1863519Y150381D01*
G01X1859800Y173000D02*
Y154100D01*
G01X1861476Y108788D02*
X1871475Y98789D01*
G01X1861476Y116964D02*
Y108788D01*
G01X1852010Y126430D02*
X1861476Y116964D01*
G01X1852010Y139078D02*
Y126430D01*
G01X1852620Y139688D02*
X1852010Y139078D01*
G01X1852620Y149968D02*
Y139688D01*
G01X1857937Y155285D02*
X1852620Y149968D01*
G01X1857937Y156123D02*
Y155285D01*
G01X1883652Y151298D02*
Y156931D01*
G01X1880816Y148462D02*
X1883652Y151298D01*
G01X1880816Y141647D02*
Y148462D01*
G01X1890654Y131809D02*
X1880816Y141647D01*
G01X1890654Y113118D02*
Y131809D01*
G01X1894628Y109144D02*
X1890654Y113118D01*
G01X1897133Y109144D02*
X1894628D01*
G01X1898102Y108175D02*
X1897133Y109144D01*
G01X1884404Y150986D02*
Y157243D01*
G01X1881568Y148150D02*
X1884404Y150986D01*
G01X1881568Y141959D02*
Y148150D01*
G01X1891594Y131933D02*
X1881568Y141959D01*
G01X1891594Y113242D02*
Y131933D01*
G01X1894939Y109897D02*
X1891594Y113242D01*
G01X1897796Y109897D02*
X1894939D01*
G01X1857110Y117244D02*
Y113600D01*
G01X1849756Y124598D02*
X1857110Y117244D01*
G01X1849756Y140014D02*
Y124598D01*
G01X1850366Y140624D02*
X1849756Y140014D01*
G01X1850366Y150904D02*
Y140624D01*
G01X1852337Y152875D02*
X1850366Y150904D01*
G01X1852337Y157283D02*
Y152875D01*
G01X1890800Y105774D02*
X1890974Y105600D01*
G01X1890800Y109860D02*
Y105774D01*
G01X1888879Y111781D02*
X1890800Y109860D01*
G01X1888879Y131173D02*
Y111781D01*
G01X1886352Y133700D02*
X1888879Y131173D01*
G01X1879600Y133700D02*
X1886352D01*
G01X1874300Y139000D02*
X1879600Y133700D01*
G01X1874300Y152848D02*
Y139000D01*
G01X1874652Y153200D02*
X1874300Y152848D01*
G01X1875150Y153200D02*
X1874652D01*
G01X1875425Y152925D02*
X1875150Y153200D01*
G01X1858145Y127744D02*
X1857020Y126619D01*
G01X1862536Y127744D02*
X1858145D01*
G01X1863987Y129195D02*
X1862536Y127744D01*
G01X1863987Y136290D02*
Y129195D01*
G01X1866251Y138554D02*
X1863987Y136290D01*
G01X1866251Y154248D02*
Y138554D01*
G01X1867703Y155700D02*
X1866251Y154248D01*
G01X1872720Y155700D02*
X1867703D01*
G01X1875056Y158036D02*
X1872720Y155700D01*
G01X1865499Y154560D02*
X1867392Y156453D01*
G01X1865499Y138866D02*
Y154560D01*
G01X1863235Y136602D02*
X1865499Y138866D01*
G01X1863235Y129507D02*
Y136602D01*
G01X1862224Y128496D02*
X1863235Y129507D01*
G01X1858143Y128496D02*
X1862224D01*
G01X1857020Y129619D02*
X1858143Y128496D01*
G01X1895250Y110650D02*
X1898107D01*
G01X1892346Y113554D02*
X1895250Y110650D01*
G01X1892346Y132245D02*
Y113554D01*
G01X1882321Y142270D02*
X1892346Y132245D01*
G01X1882321Y147475D02*
Y142270D01*
G01X1884001Y149155D02*
X1882321Y147475D01*
G01X1886573Y149155D02*
X1884001D01*
G01X1887722Y150304D02*
X1886573Y149155D01*
G01X1887722Y152505D02*
Y150304D01*
G01X1886299Y153928D02*
X1887722Y152505D01*
G01X1895850Y118950D02*
X1899495Y115305D01*
G01X1895850Y133078D02*
Y118950D01*
G01X1893040Y135888D02*
X1895850Y133078D01*
G01X1893040Y143049D02*
Y135888D01*
G01X1897462Y147471D02*
X1893040Y143049D01*
G01X1882900Y151610D02*
Y156619D01*
G01X1880064Y148774D02*
X1882900Y151610D01*
G01X1880064Y141335D02*
Y148774D01*
G01X1889831Y131568D02*
X1880064Y141335D01*
G01X1889831Y112877D02*
Y131568D01*
G01X1893063Y109645D02*
X1889831Y112877D01*
G01X1893063Y101263D02*
Y109645D01*
G01X1897000Y139083D02*
X1899683Y136400D01*
G01X1897000Y144400D02*
Y139083D01*
G01X1898714Y146114D02*
X1897000Y144400D01*
G01X1844193Y150536D02*
Y171163D01*
G01X1843642Y149985D02*
X1844193Y150536D01*
G01X1843642Y147035D02*
Y149985D01*
G01X1843310Y146703D02*
X1843642Y147035D01*
G01X1843310Y143480D02*
Y146703D01*
G01X1848100Y138690D02*
X1843310Y143480D01*
G01X1848100Y134750D02*
Y138690D01*
G01X1860552Y154694D02*
Y172405D01*
G01X1864471Y150775D02*
X1860552Y154694D01*
G01X1864471Y143784D02*
Y150775D01*
G01X1860312Y139625D02*
X1864471Y143784D01*
G01X1860312Y137026D02*
Y139625D01*
G01X1860969Y136369D02*
X1860312Y137026D01*
G01X1855300Y162300D02*
X1856301Y161299D01*
G01X1855300Y164500D02*
Y162300D01*
G01X1856800Y166000D02*
X1855300Y164500D01*
G01X1856800Y170200D02*
Y166000D01*
G01X1854900Y172100D02*
X1856800Y170200D01*
G01X1854900Y175900D02*
Y172100D01*
G01X1869860Y183060D02*
X1859800Y173000D01*
G01X1869860Y199845D02*
Y183060D01*
G01X1861057Y208648D02*
X1869860Y199845D01*
G01X1860212Y208648D02*
X1861057D01*
G01X1857244Y211616D02*
X1860212Y208648D01*
G01X1857244Y215622D02*
Y211616D01*
G01X1857494Y215872D02*
X1857244Y215622D01*
G01X1857494Y215947D02*
Y215872D01*
G01X1863391Y221844D02*
X1857494Y215947D01*
G01X1867772Y216683D02*
X1878797Y227708D01*
G01X1862983Y216683D02*
X1867772D01*
G01X1861497Y215197D02*
X1862983Y216683D01*
G01X1861497Y211481D02*
Y215197D01*
G01X1857919Y156123D02*
X1857937D01*
G01X1889401Y210609D02*
Y219499D01*
G01X1887082Y208290D02*
X1889401Y210609D01*
G01X1878239Y208290D02*
X1887082D01*
G01X1877353Y209176D02*
X1878239Y208290D01*
G01X1876047Y209176D02*
X1877353D01*
G01X1875161Y208290D02*
X1876047Y209176D01*
G01X1874852Y208290D02*
X1875161D01*
G01X1874500Y207938D02*
X1874852Y208290D01*
G01X1874500Y193190D02*
Y207938D01*
G01X1875700Y191990D02*
X1874500Y193190D01*
G01X1875700Y184800D02*
Y191990D01*
G01X1877880Y192860D02*
Y203780D01*
G01X1879000Y191740D02*
X1877880Y192860D01*
G01X1879000Y174924D02*
Y191740D01*
G01X1880757Y173167D02*
X1879000Y174924D01*
G01X1880757Y159826D02*
Y173167D01*
G01X1883652Y156931D02*
X1880757Y159826D01*
G01X1890500Y210300D02*
Y229800D01*
G01X1887050Y206850D02*
X1890500Y210300D01*
G01X1883850Y206850D02*
X1887050D01*
G01X1878730Y201730D02*
X1883850Y206850D01*
G01X1878730Y193612D02*
Y201730D01*
G01X1879752Y192590D02*
X1878730Y193612D01*
G01X1879752Y175236D02*
Y192590D01*
G01X1881509Y173479D02*
X1879752Y175236D01*
G01X1881509Y160138D02*
Y173479D01*
G01X1884404Y157243D02*
X1881509Y160138D01*
G01X1850600Y159020D02*
X1852337Y157283D01*
G01X1850600Y173970D02*
Y159020D01*
G01X1851747Y175117D02*
X1850600Y173970D01*
G01X1851747Y190936D02*
Y175117D01*
G01X1850248Y192435D02*
X1851747Y190936D01*
G01X1850248Y207911D02*
Y192435D01*
G01X1853604Y211267D02*
X1850248Y207911D01*
G01X1853604Y214455D02*
Y211267D01*
G01X1853095Y214964D02*
X1853604Y214455D01*
G01X1853095Y231929D02*
Y214964D01*
G01X1875056Y173032D02*
Y158036D01*
G01X1872916Y175172D02*
X1875056Y173032D01*
G01X1872916Y201388D02*
Y175172D01*
G01X1867200Y207104D02*
X1872916Y201388D01*
G01X1867200Y212252D02*
Y207104D01*
G01X1883924Y228976D02*
X1867200Y212252D01*
G01X1866448Y212564D02*
X1883172Y229288D01*
G01X1866448Y206792D02*
Y212564D01*
G01X1872164Y201076D02*
X1866448Y206792D01*
G01X1872164Y174860D02*
Y201076D01*
G01X1874304Y172720D02*
X1872164Y174860D01*
G01X1874304Y158348D02*
Y172720D01*
G01X1872409Y156453D02*
X1874304Y158348D01*
G01X1867392Y156453D02*
X1872409D01*
G01X1853847Y215276D02*
Y232241D01*
G01X1854356Y214767D02*
X1853847Y215276D01*
G01X1854356Y210955D02*
Y214767D01*
G01X1851000Y207599D02*
X1854356Y210955D01*
G01X1851000Y193535D02*
Y207599D01*
G01X1852500Y192035D02*
X1851000Y193535D01*
G01X1852500Y184547D02*
Y192035D01*
G01X1854942Y182105D02*
X1852500Y184547D01*
G01X1854942Y181655D02*
Y182105D01*
G01X1867187Y217633D02*
X1877847Y228293D01*
G01X1862589Y217633D02*
X1867187D01*
G01X1859550Y214594D02*
X1862589Y217633D01*
G01X1859550Y213260D02*
Y214594D01*
G01X1859604Y213206D02*
X1859550Y213260D01*
G01X1891332Y165275D02*
X1897462Y159145D01*
G01X1891332Y176868D02*
Y165275D01*
G01X1887600Y180600D02*
X1891332Y176868D01*
G01X1885300Y180600D02*
X1887600D01*
G01X1883800Y179100D02*
X1885300Y180600D01*
G01X1875360Y206260D02*
X1876700Y207600D01*
G01X1875360Y194030D02*
Y206260D01*
G01X1878248Y191142D02*
X1875360Y194030D01*
G01X1878248Y174612D02*
Y191142D01*
G01X1880005Y172855D02*
X1878248Y174612D01*
G01X1880005Y159514D02*
Y172855D01*
G01X1882900Y156619D02*
X1880005Y159514D01*
G01X1892740Y165638D02*
X1898714Y159664D01*
G01X1892740Y179433D02*
Y165638D01*
G01X1902876Y189569D02*
X1892740Y179433D01*
G01X1851942Y214487D02*
Y218089D01*
G01X1852452Y213977D02*
X1851942Y214487D01*
G01X1852452Y211745D02*
Y213977D01*
G01X1849096Y208389D02*
X1852452Y211745D01*
G01X1849096Y189368D02*
Y208389D01*
G01X1849822Y188642D02*
X1849096Y189368D01*
G01X1849822Y176792D02*
Y188642D01*
G01X1844193Y171163D02*
X1849822Y176792D01*
G01X1861243Y194544D02*
Y183100D01*
G01X1853929Y201858D02*
X1861243Y194544D01*
G01X1853929Y208898D02*
Y201858D01*
G01X1855508Y210477D02*
X1853929Y208898D01*
G01X1855508Y215245D02*
Y210477D01*
G01X1854999Y215754D02*
X1855508Y215245D01*
G01X1854999Y235234D02*
Y215754D01*
G01X1857996Y215310D02*
X1863578Y220892D01*
G01X1857996Y211928D02*
Y215310D01*
G01X1860524Y209400D02*
X1857996Y211928D01*
G01X1861652Y209400D02*
X1860524D01*
G01X1870812Y200240D02*
X1861652Y209400D01*
G01X1870812Y182665D02*
Y200240D01*
G01X1860552Y172405D02*
X1870812Y182665D01*
G01X1841093Y246781D02*
X1843449Y244425D01*
G01X1868482Y221844D02*
X1863391D01*
G01X1875404Y228766D02*
X1868482Y221844D01*
G01X1875404Y245155D02*
Y228766D01*
G01X1857643Y262916D02*
X1875404Y245155D01*
G01X1878797Y253303D02*
X1866928Y265172D01*
G01X1878797Y227708D02*
Y253303D01*
G01X1884800Y224100D02*
X1884400D01*
G01X1889401Y219499D02*
X1884800Y224100D01*
G01X1893159Y232459D02*
X1901342D01*
G01X1890500Y229800D02*
X1893159Y232459D01*
G01X1844373Y240651D02*
X1853095Y231929D01*
G01X1842917Y240651D02*
X1844373D01*
G01X1840149Y243419D02*
X1842917Y240651D01*
G01X1840149Y244425D02*
Y243419D01*
G01X1898452Y237003D02*
X1896529Y235080D01*
G01X1883924Y232676D02*
Y228976D01*
G01X1882200Y234400D02*
X1883924Y232676D01*
G01X1883172Y231010D02*
X1882345Y231837D01*
G01X1883172Y229288D02*
Y231010D01*
G01X1886108Y228608D02*
X1885000Y227500D01*
G01X1886108Y230192D02*
Y228608D01*
G01X1889127Y233211D02*
X1886108Y230192D01*
G01X1910689Y233211D02*
X1889127D01*
G01X1841725Y245078D02*
X1840802Y246001D01*
G01X1841725Y242907D02*
Y245078D01*
G01X1843229Y241403D02*
X1841725Y242907D01*
G01X1844685Y241403D02*
X1843229D01*
G01X1853847Y232241D02*
X1844685Y241403D01*
G01X1877847Y252909D02*
X1866336Y264420D01*
G01X1877847Y228293D02*
Y252909D01*
G01X1888526Y238850D02*
X1884651Y234975D01*
G01X1910788Y238850D02*
X1888526D01*
G01X1895092Y237898D02*
X1892274Y235080D01*
G01X1910393Y237898D02*
X1895092D01*
G01X1850781Y219250D02*
X1850723D01*
G01X1851942Y218089D02*
X1850781Y219250D01*
G01X1842300Y247933D02*
X1854999Y235234D01*
G01X1876356Y245550D02*
X1858238Y263668D01*
G01X1876356Y228371D02*
Y245550D01*
G01X1868877Y220892D02*
X1876356Y228371D01*
G01X1863578Y220892D02*
X1868877D01*
G01X1895700Y434600D02*
X1899986Y438886D01*
G01X1866260Y438360D02*
X1878100Y450200D01*
G01X1895388Y435352D02*
X1900074Y440038D01*
G01X1899650Y442806D02*
X1894452Y437608D01*
G01X1895076Y436104D02*
X1900162Y441190D01*
G01X1894764Y436856D02*
X1899962Y442054D01*
G01X1848319Y497381D02*
X1845324Y500376D01*
G01X1876761Y497381D02*
X1848319D01*
G01X1882430Y503050D02*
X1876761Y497381D01*
G01X1897897Y503050D02*
X1882430D01*
G01X1865232Y484599D02*
X1842769D01*
G01X1879433Y498800D02*
X1865232Y484599D01*
G01X1898300Y498800D02*
X1879433D01*
G01X1876430Y504400D02*
X1897900D01*
G01X1873632Y501602D02*
X1876430Y504400D01*
G01X1873632Y500904D02*
Y501602D01*
G01X1840750Y475748D02*
Y475724D01*
G01X1840398Y476100D02*
X1840750Y475748D01*
G01X1838877Y476100D02*
X1840398D01*
G01X1842174Y477300D02*
X1843750Y475724D01*
G01X1838730Y477300D02*
X1842174D01*
G01X1865697Y483500D02*
X1843017D01*
G01X1868562Y486365D02*
X1865697Y483500D01*
G01X1868562Y486385D02*
Y486365D01*
G01X1869485Y487308D02*
X1868562Y486385D01*
G01X1869505Y487308D02*
X1869485D01*
G01X1879797Y497600D02*
X1869505Y487308D01*
G01X1883500Y497600D02*
X1879797D01*
G01X1884100Y497000D02*
X1883500Y497600D01*
G01X1884100Y493000D02*
Y497000D01*
G01X1836396Y480218D02*
Y481349D01*
G01X1857983Y583896D02*
X1849553Y592326D01*
G01X1866746Y583896D02*
X1857983D01*
G01X1874894Y575748D02*
X1866746Y583896D01*
G01X1887371Y575748D02*
X1874894D01*
G01X1900362Y562757D02*
X1887371Y575748D01*
G01X1842100Y548200D02*
X1848900D01*
G01X1838600Y544700D02*
X1842100Y548200D01*
G01X1838600Y533500D02*
Y544700D01*
G01X1859500Y548000D02*
X1855750D01*
G01X1860456Y548956D02*
X1859500Y548000D01*
G01X1861086Y548956D02*
X1860456D01*
G01X1863478Y551348D02*
X1861086Y548956D01*
G01X1869478Y551348D02*
X1863478D01*
G01X1877978Y559848D02*
X1869478Y551348D01*
G01X1910022Y559848D02*
X1877978D01*
G01X1857671Y583144D02*
X1850065Y590750D01*
G01X1865868Y583144D02*
X1857671D01*
G01X1874262Y574750D02*
X1865868Y583144D01*
G01X1886751Y574750D02*
X1874262D01*
G01X1899901Y561600D02*
X1886751Y574750D01*
G01X1891054Y585946D02*
X1898900Y578100D01*
G01X1866494Y585946D02*
X1891054D01*
G01X1863720Y588720D02*
X1866494Y585946D01*
G01X1879720Y537320D02*
X1906980D01*
G01X1872200Y529800D02*
X1879720Y537320D01*
G01X1847200Y529800D02*
X1872200D01*
G01X1845536Y528136D02*
X1847200Y529800D01*
G01X1842764Y528136D02*
X1845536D01*
G01X1885100Y579083D02*
X1900674Y563509D01*
G01X1885100Y584300D02*
Y579083D01*
G01X1846526Y592326D02*
X1845000Y590800D01*
G01X1849553Y592326D02*
X1846526D01*
G01X1839653Y596821D02*
X1836952D01*
G01X1843364Y593110D02*
X1839653Y596821D01*
G01X1890081Y593110D02*
X1843364D01*
G01X1891086Y592105D02*
X1890081Y593110D01*
G01X1850065Y590750D02*
X1848900D01*
G01X1856040Y588720D02*
X1863720D01*
G01X1856040Y588704D02*
Y588720D01*
G01X1886500Y607519D02*
X1891086Y612105D01*
G01X1886500Y597879D02*
Y607519D01*
G01X1882683Y594062D02*
X1886500Y597879D01*
G01X1844123Y594062D02*
X1882683D01*
G01X1840555Y597630D02*
X1844123Y594062D01*
G01X1919955Y81367D02*
Y123635D01*
G01X1909602Y71014D02*
X1919955Y81367D01*
G01X1901414Y71014D02*
X1909602D01*
G01X1899000Y68600D02*
X1901414Y71014D01*
G01X1924548Y90495D02*
X1929272Y95219D01*
G01X1924548Y78495D02*
Y90495D01*
G01X1913453Y67400D02*
X1924548Y78495D01*
G01X1902336Y67400D02*
X1913453D01*
G01X1901500Y69500D02*
X1899470Y67470D01*
G01X1912459Y69500D02*
X1901500D01*
G01X1922576Y79617D02*
X1912459Y69500D01*
G01X1922576Y91076D02*
Y79617D01*
G01X1927377Y95877D02*
X1922576Y91076D01*
G01X1925500Y90100D02*
X1930106Y94706D01*
G01X1925500Y78100D02*
Y90100D01*
G01X1913848Y66448D02*
X1925500Y78100D01*
G01X1902448Y66448D02*
X1913848D01*
G01X1902300Y68600D02*
X1900338Y66638D01*
G01X1912623Y68600D02*
X1902300D01*
G01X1923328Y79305D02*
X1912623Y68600D01*
G01X1923328Y90628D02*
Y79305D01*
G01X1928129Y95429D02*
X1923328Y90628D01*
G01X1926042Y154473D02*
X1922674Y157841D01*
G01X1928527Y154473D02*
X1926042D01*
G01X1929400Y153600D02*
X1928527Y154473D01*
G01X1929400Y140848D02*
Y153600D01*
G01X1925426Y136874D02*
X1929400Y140848D01*
G01X1925426Y129106D02*
Y136874D01*
G01X1919955Y123635D02*
X1925426Y129106D01*
G01X1923200Y129418D02*
X1919702Y125920D01*
G01X1923200Y141100D02*
Y129418D01*
G01X1925400Y143300D02*
X1923200Y141100D01*
G01X1925400Y153700D02*
Y143300D01*
G01X1921722Y157378D02*
X1925400Y153700D01*
G01X1948636Y155507D02*
Y164751D01*
G01X1946525Y153396D02*
X1948636Y155507D01*
G01X1946525Y148725D02*
Y153396D01*
G01X1938050Y140250D02*
X1946525Y148725D01*
G01X1938050Y113450D02*
Y140250D01*
G01X1929272Y104672D02*
X1938050Y113450D01*
G01X1929272Y95219D02*
Y104672D01*
G01X1898102Y107325D02*
Y108175D01*
G01X1899873Y107820D02*
X1897796Y109897D01*
G01X1899873Y106092D02*
Y107820D01*
G01X1916656Y113300D02*
X1914500D01*
G01X1917400Y114044D02*
X1916656Y113300D01*
G01X1917400Y140800D02*
Y114044D01*
G01X1921700Y145100D02*
X1917400Y140800D01*
G01X1921700Y149900D02*
Y145100D01*
G01X1917900Y153700D02*
X1921700Y149900D01*
G01X1917900Y190495D02*
Y153700D01*
G01X1931811Y154160D02*
Y164789D01*
G01X1930152Y152501D02*
X1931811Y154160D01*
G01X1930152Y142422D02*
Y152501D01*
G01X1931019Y141555D02*
X1930152Y142422D01*
G01X1931019Y135827D02*
Y141555D01*
G01X1927693Y132501D02*
X1931019Y135827D01*
G01X1927693Y126381D02*
Y132501D01*
G01X1927918Y126156D02*
X1927693Y126381D01*
G01X1927377Y106777D02*
Y95877D01*
G01X1936400Y115800D02*
X1927377Y106777D01*
G01X1936400Y141200D02*
Y115800D01*
G01X1940106Y144906D02*
X1936400Y141200D01*
G01X1940106Y150647D02*
Y144906D01*
G01X1946732Y157273D02*
X1940106Y150647D01*
G01X1949588Y155112D02*
Y165146D01*
G01X1947277Y152801D02*
X1949588Y155112D01*
G01X1947277Y148413D02*
Y152801D01*
G01X1938884Y140020D02*
X1947277Y148413D01*
G01X1938884Y113104D02*
Y140020D01*
G01X1930106Y104326D02*
X1938884Y113104D01*
G01X1930106Y94706D02*
Y104326D01*
G01X1900625Y108132D02*
Y105780D01*
G01X1898107Y110650D02*
X1900625Y108132D01*
G01X1899495Y115305D02*
X1906467D01*
G01X1897462Y159145D02*
Y147471D01*
G01X1933715Y153370D02*
Y164789D01*
G01X1931856Y151511D02*
X1933715Y153370D01*
G01X1931856Y145344D02*
Y151511D01*
G01X1934544Y142656D02*
X1931856Y145344D01*
G01X1934544Y127957D02*
Y142656D01*
G01X1932763Y153765D02*
Y165184D01*
G01X1930904Y151906D02*
X1932763Y153765D01*
G01X1930904Y143017D02*
Y151906D01*
G01X1931971Y141950D02*
X1930904Y143017D01*
G01X1931971Y129486D02*
Y141950D01*
G01X1930840Y128355D02*
X1931971Y129486D01*
G01X1929737Y128355D02*
X1930840D01*
G01X1929737Y128337D02*
Y128355D01*
G01X1929736Y128337D02*
X1929737D01*
G01X1928129Y106465D02*
Y95429D01*
G01X1937152Y115488D02*
X1928129Y106465D01*
G01X1937152Y140888D02*
Y115488D01*
G01X1940858Y144594D02*
X1937152Y140888D01*
G01X1940858Y150315D02*
Y144594D01*
G01X1947484Y156941D02*
X1940858Y150315D01*
G01X1902704Y118004D02*
X1906414D01*
G01X1899683Y121025D02*
X1902704Y118004D01*
G01X1899683Y136400D02*
Y121025D01*
G01X1898714Y159664D02*
Y146114D01*
G01X1920744Y217391D02*
X1918215Y219920D01*
G01X1920744Y207345D02*
Y217391D01*
G01X1925591Y202498D02*
X1920744Y207345D01*
G01X1925591Y198918D02*
Y202498D01*
G01X1930666Y193843D02*
X1925591Y198918D01*
G01X1930666Y192537D02*
Y193843D01*
G01X1922674Y184545D02*
X1930666Y192537D01*
G01X1922674Y157841D02*
Y184545D01*
G01X1921722Y185422D02*
Y157378D01*
G01X1926576Y190276D02*
X1921722Y185422D01*
G01X1926576Y192895D02*
Y190276D01*
G01X1923824Y195647D02*
X1926576Y192895D01*
G01X1923824Y196953D02*
Y195647D01*
G01X1923891Y197020D02*
X1923824Y196953D01*
G01X1923891Y202309D02*
Y197020D01*
G01X1919749Y206451D02*
X1923891Y202309D01*
G01X1919749Y211253D02*
Y206451D01*
G01X1918489Y212513D02*
X1919749Y211253D01*
G01X1918489Y216787D02*
X1916100Y219176D01*
G01X1918489Y212513D02*
Y216787D01*
G01X1933316Y210998D02*
X1921800Y222514D01*
G01X1937031Y210998D02*
X1933316D01*
G01X1947942Y200087D02*
X1937031Y210998D01*
G01X1947942Y165445D02*
Y200087D01*
G01X1948636Y164751D02*
X1947942Y165445D01*
G01X1915448Y192947D02*
X1917900Y190495D01*
G01X1915448Y194253D02*
Y192947D01*
G01X1915500Y194305D02*
X1915448Y194253D01*
G01X1915500Y206728D02*
Y194305D01*
G01X1913045Y209183D02*
X1915500Y206728D01*
G01X1913045Y220136D02*
Y209183D01*
G01X1921496Y207657D02*
Y218725D01*
G01X1928370Y200783D02*
X1921496Y207657D01*
G01X1928370Y198285D02*
Y200783D01*
G01X1932043Y194612D02*
X1928370Y198285D01*
G01X1932043Y191981D02*
Y194612D01*
G01X1924031Y183969D02*
X1932043Y191981D01*
G01X1924031Y167094D02*
Y183969D01*
G01X1925056Y166069D02*
X1924031Y167094D01*
G01X1930531Y166069D02*
X1925056D01*
G01X1931811Y164789D02*
X1930531Y166069D01*
G01X1946732Y163961D02*
Y157273D01*
G01X1946038Y164655D02*
X1946732Y163961D01*
G01X1946038Y169572D02*
Y164655D01*
G01X1940515Y175095D02*
X1946038Y169572D01*
G01X1940515Y183185D02*
Y175095D01*
G01X1940976Y183646D02*
X1940515Y183185D01*
G01X1940976Y199053D02*
Y183646D01*
G01X1932465Y207564D02*
X1940976Y199053D01*
G01X1927064Y207564D02*
X1932465D01*
G01X1943500Y208900D02*
Y209500D01*
G01X1950813Y201587D02*
X1943500Y208900D01*
G01X1950813Y194948D02*
Y201587D01*
G01X1959661Y186100D02*
X1950813Y194948D01*
G01X1933711Y211950D02*
X1922552Y223109D01*
G01X1937426Y211950D02*
X1933711D01*
G01X1948894Y200482D02*
X1937426Y211950D01*
G01X1948894Y165840D02*
Y200482D01*
G01X1949588Y165146D02*
X1948894Y165840D01*
G01X1913884Y209408D02*
Y230016D01*
G01X1916252Y207040D02*
X1913884Y209408D01*
G01X1916252Y205160D02*
Y207040D01*
G01X1921871Y199541D02*
X1916252Y205160D01*
G01X1921871Y195458D02*
Y199541D01*
G01X1925000Y192329D02*
X1921871Y195458D01*
G01X1925000Y192000D02*
Y192329D01*
G01X1924200Y208002D02*
Y218432D01*
G01X1926802Y205400D02*
X1924200Y208002D01*
G01X1933250Y205400D02*
X1926802D01*
G01X1937681Y200969D02*
X1933250Y205400D01*
G01X1937681Y195010D02*
Y200969D01*
G01X1937624Y194953D02*
X1937681Y195010D01*
G01X1937624Y193647D02*
Y194953D01*
G01X1937681Y193590D02*
X1937624Y193647D01*
G01X1937681Y187581D02*
Y193590D01*
G01X1933716Y183616D02*
X1937681Y187581D01*
G01X1933716Y164790D02*
Y183616D01*
G01X1933715Y164789D02*
X1933716Y164790D01*
G01X1922531Y208086D02*
Y218754D01*
G01X1929405Y201212D02*
X1922531Y208086D01*
G01X1929405Y198714D02*
Y201212D01*
G01X1931839Y196280D02*
X1929405Y198714D01*
G01X1934482Y196280D02*
X1931839D01*
G01X1935826Y194936D02*
X1934482Y196280D01*
G01X1935826Y192685D02*
Y194936D01*
G01X1924983Y181842D02*
X1935826Y192685D01*
G01X1924983Y167489D02*
Y181842D01*
G01X1925451Y167021D02*
X1924983Y167489D01*
G01X1930926Y167021D02*
X1925451D01*
G01X1932763Y165184D02*
X1930926Y167021D01*
G01X1947484Y164273D02*
Y156941D01*
G01X1946790Y164967D02*
X1947484Y164273D01*
G01X1946790Y170190D02*
Y164967D01*
G01X1941507Y175473D02*
X1946790Y170190D01*
G01X1941507Y183113D02*
Y175473D01*
G01X1941728Y183334D02*
X1941507Y183113D01*
G01X1941728Y199365D02*
Y183334D01*
G01X1932777Y208316D02*
X1941728Y199365D01*
G01X1931648Y208316D02*
X1932777D01*
G01X1930500Y209464D02*
X1931648Y208316D01*
G01X1902876Y194936D02*
Y189569D01*
G01X1901574Y196238D02*
X1902876Y194936D01*
G01X1901574Y218709D02*
Y196238D01*
G01X1918215Y219848D02*
X1918143D01*
G01X1918215Y219920D02*
Y219848D01*
G01X1900832Y236051D02*
X1899816Y235035D01*
G01X1909196Y236051D02*
X1900832D01*
G01X1916100Y229147D02*
X1909196Y236051D01*
G01X1916100Y219176D02*
Y229147D01*
G01X1924800Y232700D02*
X1925835Y233735D01*
G01X1923500Y232700D02*
X1924800D01*
G01X1921800Y231000D02*
X1923500Y232700D01*
G01X1921800Y222514D02*
Y231000D01*
G01X1902507Y231294D02*
X1902907D01*
G01X1901342Y232459D02*
X1902507Y231294D01*
G01X1912440Y220741D02*
X1913045Y220136D01*
G01X1910340Y220741D02*
X1912440D01*
G01X1909802Y237003D02*
X1898452D01*
G01X1917534Y229271D02*
X1909802Y237003D01*
G01X1917534Y222687D02*
Y229271D01*
G01X1921496Y218725D02*
X1917534Y222687D01*
G01X1925400Y231900D02*
X1926100Y231200D01*
G01X1923800Y231900D02*
X1925400D01*
G01X1922552Y230652D02*
X1923800Y231900D01*
G01X1922552Y223109D02*
Y230652D01*
G01X1913884Y230016D02*
X1910689Y233211D01*
G01X1919537Y230101D02*
X1910788Y238850D01*
G01X1919537Y229313D02*
Y230101D01*
G01X1919536Y229312D02*
X1919537Y229313D01*
G01X1919536Y223096D02*
Y229312D01*
G01X1924200Y218432D02*
X1919536Y223096D01*
G01X1918584Y229707D02*
X1910393Y237898D01*
G01X1918584Y222701D02*
Y229707D01*
G01X1922531Y218754D02*
X1918584Y222701D01*
G01X1904485Y221620D02*
X1901574Y218709D01*
G01X1904485Y224605D02*
Y221620D01*
G01X1903314Y225776D02*
X1904485Y224605D01*
G01X1903020Y225776D02*
X1903314D01*
G01X1944733Y449943D02*
Y467300D01*
G01X1939845Y445055D02*
X1944733Y449943D01*
G01X1937906Y434574D02*
X1960088D01*
G01X1933594Y438886D02*
X1937906Y434574D01*
G01X1899986Y438886D02*
X1933594D01*
G01X1938384Y435726D02*
X1959610D01*
G01X1934072Y440038D02*
X1938384Y435726D01*
G01X1900074Y440038D02*
X1934072D01*
G01X1935291Y442806D02*
X1899650D01*
G01X1939640Y438457D02*
X1935291Y442806D01*
G01X1958363Y438457D02*
X1939640D01*
G01X1970176Y450270D02*
X1958363Y438457D01*
G01X1938862Y436878D02*
X1959132D01*
G01X1934550Y441190D02*
X1938862Y436878D01*
G01X1900162Y441190D02*
X1934550D01*
G01X1958675Y437705D02*
X1970976Y450006D01*
G01X1939328Y437705D02*
X1958675D01*
G01X1934979Y442054D02*
X1939328Y437705D01*
G01X1899962Y442054D02*
X1934979D01*
G01X1902647Y507800D02*
X1897897Y503050D01*
G01X1914700Y507800D02*
X1902647D01*
G01X1921078Y514178D02*
X1914700Y507800D01*
G01X1924648Y514178D02*
X1921078D01*
G01X1930570Y520100D02*
X1924648Y514178D01*
G01X1943270Y520100D02*
X1930570D01*
G01X1949330Y514040D02*
X1943270Y520100D01*
G01X1949330Y492541D02*
Y514040D01*
G01X1953800Y488071D02*
X1949330Y492541D01*
G01X1953800Y476367D02*
Y488071D01*
G01X1944733Y467300D02*
X1953800Y476367D01*
G01X1955430Y524030D02*
X1949260Y530200D01*
G01X1957970Y524030D02*
X1955430D01*
G01X1966650Y515350D02*
X1957970Y524030D01*
G01X1958789Y476885D02*
X1960722D01*
G01X1957063Y475159D02*
X1958789Y476885D01*
G01X1957063Y474769D02*
Y475159D01*
G01X1904100Y493000D02*
X1898300Y498800D01*
G01X1955304Y510402D02*
X1963262D01*
G01X1944206Y521500D02*
X1955304Y510402D01*
G01X1930570Y521500D02*
X1944206D01*
G01X1924200Y515130D02*
X1930570Y521500D01*
G01X1920630Y515130D02*
X1924200D01*
G01X1914500Y509000D02*
X1920630Y515130D01*
G01X1902500Y509000D02*
X1914500D01*
G01X1897900Y504400D02*
X1902500Y509000D01*
G01X1955130Y522700D02*
X1948880Y528950D01*
G01X1957400Y522700D02*
X1955130D01*
G01X1965850Y514250D02*
X1957400Y522700D01*
G01X1958364Y477757D02*
X1960530D01*
G01X1957212Y478909D02*
X1958364Y477757D01*
G01X1957212Y479521D02*
Y478909D01*
G01X1947351Y524849D02*
X1956300Y515900D01*
G01X1929542Y524849D02*
X1947351D01*
G01X1925841Y528550D02*
X1929542Y524849D01*
G01X1955742Y524782D02*
X1967308D01*
G01X1949424Y531100D02*
X1955742Y524782D01*
G01X1936900Y565400D02*
Y568000D01*
G01X1939800Y562500D02*
X1936900Y565400D01*
G01X1939800Y551700D02*
Y562500D01*
G01X1937800Y549700D02*
X1939800Y551700D01*
G01X1919371Y562757D02*
X1900362D01*
G01X1926500Y555628D02*
X1919371Y562757D01*
G01X1926500Y543423D02*
Y555628D01*
G01X1939723Y530200D02*
X1926500Y543423D01*
G01X1949260Y530200D02*
X1939723D01*
G01X1931224Y566224D02*
X1934400Y569400D01*
G01X1931224Y562708D02*
Y566224D01*
G01X1933257Y560675D02*
X1931224Y562708D01*
G01X1933257Y548343D02*
Y560675D01*
G01X1936500Y545100D02*
X1933257Y548343D01*
G01X1937200Y545100D02*
X1936500D01*
G01X1929600Y579664D02*
Y607500D01*
G01X1928216Y578280D02*
X1929600Y579664D01*
G01X1928216Y561460D02*
Y578280D01*
G01X1929900Y559776D02*
X1928216Y561460D01*
G01X1929900Y544543D02*
Y559776D01*
G01X1940543Y533900D02*
X1929900Y544543D01*
G01X1950900Y533900D02*
X1940543D01*
G01X1951900Y534900D02*
X1950900Y533900D01*
G01X1911000Y558870D02*
X1910022Y559848D01*
G01X1911000Y556700D02*
Y558870D01*
G01X1918900Y561600D02*
X1899901D01*
G01X1925500Y555000D02*
X1918900Y561600D01*
G01X1925500Y542793D02*
Y555000D01*
G01X1939343Y528950D02*
X1925500Y542793D01*
G01X1948880Y528950D02*
X1939343D01*
G01X1956073Y526671D02*
X1956606D01*
G01X1950444Y532300D02*
X1956073Y526671D01*
G01X1940796Y532300D02*
X1950444D01*
G01X1928762Y544334D02*
X1940796Y532300D01*
G01X1928762Y559567D02*
Y544334D01*
G01X1927120Y561209D02*
X1928762Y559567D01*
G01X1923613Y561209D02*
X1927120D01*
G01X1920161Y564661D02*
X1923613Y561209D01*
G01X1920029Y564661D02*
X1920161D01*
G01X1920028Y564662D02*
X1920029Y564661D01*
G01X1919074Y564662D02*
X1920028D01*
G01X1919073Y564661D02*
X1919074Y564662D01*
G01X1901152Y564661D02*
X1919073D01*
G01X1898900Y566913D02*
X1901152Y564661D01*
G01X1898900Y578100D02*
Y566913D01*
G01X1915750Y528550D02*
X1925841D01*
G01X1906980Y537320D02*
X1915750Y528550D01*
G01X1928968Y576568D02*
X1935400Y583000D01*
G01X1928968Y561772D02*
Y576568D01*
G01X1931000Y559740D02*
X1928968Y561772D01*
G01X1931000Y544507D02*
Y559740D01*
G01X1938407Y537100D02*
X1931000Y544507D01*
G01X1940600Y537100D02*
X1938407D01*
G01X1940800Y537300D02*
X1940600Y537100D01*
G01X1930472Y569972D02*
X1934200Y573700D01*
G01X1930472Y562396D02*
Y569972D01*
G01X1932505Y560363D02*
X1930472Y562396D01*
G01X1932505Y545303D02*
Y560363D01*
G01X1936505Y541303D02*
X1932505Y545303D01*
G01X1937003Y541303D02*
X1936505D01*
G01X1937300Y541600D02*
X1937003Y541303D01*
G01X1934532Y564300D02*
X1932800D01*
G01X1936559Y562273D02*
X1934532Y564300D01*
G01X1936559Y551959D02*
Y562273D01*
G01X1935400Y550800D02*
X1936559Y551959D01*
G01X1940366Y531100D02*
X1949424D01*
G01X1927609Y543857D02*
X1940366Y531100D01*
G01X1927609Y544811D02*
Y543857D01*
G01X1927610Y544812D02*
X1927609Y544811D01*
G01X1927610Y555582D02*
Y544812D01*
G01X1919683Y563509D02*
X1927610Y555582D01*
G01X1900674Y563509D02*
X1919683D01*
G01X1929720Y573220D02*
X1934200Y577700D01*
G01X1929720Y562084D02*
Y573220D01*
G01X1931753Y560051D02*
X1929720Y562084D01*
G01X1931753Y544818D02*
Y560051D01*
G01X1938071Y538500D02*
X1931753Y544818D01*
G01X1939348Y538500D02*
X1938071D01*
G01X1939700Y538852D02*
X1939348Y538500D01*
G01X1939700Y540900D02*
Y538852D01*
G01X1931350Y609250D02*
X1934350D01*
G01X1929600Y607500D02*
X1931350Y609250D01*
G01X1948810Y614500D02*
X1927000D01*
G01X1966976Y596334D02*
X1948810Y614500D01*
G01X1959661Y152439D02*
Y186100D01*
G01X1962800Y149300D02*
X1959661Y152439D01*
G01X1973240Y447726D02*
Y525760D01*
G01X1960088Y434574D02*
X1973240Y447726D01*
G01X1972480Y448596D02*
Y524752D01*
G01X1959610Y435726D02*
X1972480Y448596D01*
G01X1970176Y467080D02*
Y450270D01*
G01X1971728Y449474D02*
Y468662D01*
G01X1959132Y436878D02*
X1971728Y449474D01*
G01X1970976Y450006D02*
Y467984D01*
G01X1966650Y506740D02*
Y515350D01*
G01X1961910Y502000D02*
X1966650Y506740D01*
G01X1961910Y478073D02*
Y502000D01*
G01X1960722Y476885D02*
X1961910Y478073D01*
G01X1973240Y525760D02*
X1971124Y527876D01*
G01X1963262Y510402D02*
X1964270Y511410D01*
G01X1965850Y507094D02*
Y514250D01*
G01X1961140Y502384D02*
X1965850Y507094D01*
G01X1961140Y478367D02*
Y502384D01*
G01X1960530Y477757D02*
X1961140Y478367D01*
G01X1972480Y524752D02*
X1969972Y527260D01*
G01X1963940Y473316D02*
X1970176Y467080D01*
G01X1963940Y501220D02*
Y473316D01*
G01X1970176Y507456D02*
X1963940Y501220D01*
G01X1970176Y521914D02*
Y507456D01*
G01X1967308Y524782D02*
X1970176Y521914D01*
G01X1971728Y523736D02*
X1968128Y527336D01*
G01X1971728Y506528D02*
Y523736D01*
G01X1965650Y500450D02*
X1971728Y506528D01*
G01X1965650Y474740D02*
Y500450D01*
G01X1971728Y468662D02*
X1965650Y474740D01*
G01X1970976Y522790D02*
X1966976Y526790D01*
G01X1970976Y506956D02*
Y522790D01*
G01X1964810Y500790D02*
X1970976Y506956D01*
G01X1964810Y474150D02*
Y500790D01*
G01X1970976Y467984D02*
X1964810Y474150D01*
G01X1971124Y527876D02*
Y613776D01*
G01X1969972Y527260D02*
Y611228D01*
G01X1968128Y527336D02*
Y610272D01*
G01X1966976Y526790D02*
Y596334D01*
G01X1971124Y613776D02*
X1965400Y619500D01*
G01X1969972Y611228D02*
X1961700Y619500D01*
G01X1968128Y610272D02*
X1961700Y616700D01*
G54D14*
G01X105550Y-47300D02*
X100500Y-42250D01*
G01X144200Y-47300D02*
X105550D01*
G01X145585Y-45915D02*
X144200Y-47300D01*
G01X443146Y-45915D02*
X145585D01*
G01X146299Y-42355D02*
X443146D01*
G01X292584Y567849D02*
X297635Y572900D01*
G01X292584Y557662D02*
Y567849D01*
G01X294289Y555957D02*
X292584Y557662D01*
G01X272836Y572500D02*
X273824D01*
G01X269781Y569445D02*
X272836Y572500D01*
G01X269781Y568257D02*
Y569445D01*
G01X269159Y567635D02*
X269781Y568257D01*
G01X269159Y557662D02*
Y567635D01*
G01X270864Y555957D02*
X269159Y557662D01*
G01X273822Y550914D02*
X273910D01*
G01X272136Y552600D02*
X273822Y550914D01*
G01X272136Y554800D02*
Y552600D01*
G01X272636Y555300D02*
X272136Y554800D01*
G01X272636Y557199D02*
Y555300D01*
G01X271499Y558336D02*
X272636Y557199D01*
G01X271499Y559664D02*
Y558336D01*
G01X272436Y560601D02*
X271499Y559664D01*
G01X272436Y561999D02*
Y560601D01*
G01X271499Y562936D02*
X272436Y561999D01*
G01X271499Y564164D02*
Y562936D01*
G01X272536Y565201D02*
X271499Y564164D01*
G01X272536Y566099D02*
Y565201D01*
G01X271936Y566699D02*
X272536Y566099D01*
G01X270864Y566699D02*
X271936D01*
G01X280115Y550914D02*
X280203D01*
G01X278429Y552600D02*
X280115Y550914D01*
G01X278429Y554292D02*
Y552600D01*
G01X279336Y555199D02*
X278429Y554292D01*
G01X279336Y556792D02*
Y555199D01*
G01X278192Y557936D02*
X279336Y556792D01*
G01X278192Y559356D02*
Y557936D01*
G01X279036Y560200D02*
X278192Y559356D01*
G01X279036Y561900D02*
Y560200D01*
G01X278192Y562744D02*
X279036Y561900D01*
G01X278192Y563956D02*
Y562744D01*
G01X279136Y564900D02*
X278192Y563956D01*
G01X279136Y566100D02*
Y564900D01*
G01X278537Y566699D02*
X279136Y566100D01*
G01X277557Y566699D02*
X278537D01*
G01X275852Y557662D02*
X277557Y555957D01*
G01X275852Y569315D02*
Y557662D01*
G01X279037Y572500D02*
X275852Y569315D01*
G01X280203Y572500D02*
X279037D01*
G01X319328Y67547D02*
X321061Y65814D01*
G01X319328Y76021D02*
Y67547D01*
G01X319692Y76385D02*
X319328Y76021D01*
G01X319692Y85898D02*
Y76385D01*
G01X318992Y86598D02*
X319692Y85898D01*
G01X318992Y88100D02*
Y86598D01*
G01X321061Y90169D02*
X318992Y88100D01*
G01X321061Y92757D02*
Y90169D01*
G01X351179Y66623D02*
Y65822D01*
G01X350569Y67233D02*
X351179Y66623D01*
G01X349066Y67233D02*
X350569D01*
G01X348456Y67843D02*
X349066Y67233D01*
G01X348456Y69233D02*
Y67843D01*
G01X349066Y69843D02*
X348456Y69233D01*
G01X350569Y69843D02*
X349066D01*
G01X351179Y70453D02*
X350569Y69843D01*
G01X351179Y71258D02*
Y70453D01*
G01X349453Y72984D02*
X351179Y71258D01*
G01X349453Y74891D02*
Y72984D01*
G01X351092Y76530D02*
X349453Y74891D01*
G01X351092Y82265D02*
Y76530D01*
G01X349334Y84023D02*
X351092Y82265D01*
G01X349334Y85542D02*
Y84023D01*
G01X349792Y86000D02*
X349334Y85542D01*
G01X349792Y88577D02*
Y86000D01*
G01X351179Y89964D02*
X349792Y88577D01*
G01X324407Y67175D02*
Y65814D01*
G01X326423Y69191D02*
X324407Y67175D01*
G01X326423Y70964D02*
Y69191D01*
G01X325743Y71644D02*
X326423Y70964D01*
G01X323983Y71644D02*
X325743D01*
G01X322795Y72832D02*
X323983Y71644D01*
G01X322795Y75516D02*
Y72832D01*
G01X322092Y76219D02*
X322795Y75516D01*
G01X322092Y78517D02*
Y76219D01*
G01X322702Y79127D02*
X322092Y78517D01*
G01X323767Y79127D02*
X322702D01*
G01X324267Y79627D02*
X323767Y79127D01*
G01X324267Y81237D02*
Y79627D01*
G01X323767Y81737D02*
X324267Y81237D01*
G01X322702Y81737D02*
X323767D01*
G01X322092Y82347D02*
X322702Y81737D01*
G01X322092Y85300D02*
Y82347D01*
G01X324407Y87615D02*
X322092Y85300D01*
G01X324407Y89964D02*
Y87615D01*
G01X347833Y77457D02*
Y73757D01*
G01X348443Y78067D02*
X347833Y77457D01*
G01X348954Y78067D02*
X348443D01*
G01X349454Y78567D02*
X348954Y78067D01*
G01X349454Y79667D02*
Y78567D01*
G01X348844Y80277D02*
X349454Y79667D01*
G01X348281Y80277D02*
X348844D01*
G01X347681Y80877D02*
X348281Y80277D01*
G01X347681Y87240D02*
Y80877D01*
G01X347833Y87392D02*
X347681Y87240D01*
G01X354525Y68491D02*
Y65822D01*
G01X354526Y68492D02*
X354525Y68491D01*
G01X354526Y70667D02*
Y68492D01*
G01X352921Y72272D02*
X354526Y70667D01*
G01X352921Y75530D02*
Y72272D01*
G01X353092Y75701D02*
X352921Y75530D01*
G01X353092Y85500D02*
Y75701D01*
G01X352557Y86035D02*
X353092Y85500D01*
G01X352557Y88465D02*
Y86035D01*
G01X354415Y90323D02*
X352557Y88465D01*
G01X354415Y92757D02*
Y90323D01*
G01X344087Y66785D02*
X344486Y65822D01*
G01X342851Y73002D02*
X344087Y66785D01*
G01X342851Y74142D02*
Y73002D01*
G01X341963Y76284D02*
X342851Y74142D01*
G01X341963Y83875D02*
Y76284D01*
G01X344486Y89964D02*
X341963Y83875D01*
G01X354927Y74158D02*
X354526Y73757D01*
G01X354427Y87392D02*
X354927Y86892D01*
G01X354415Y87392D02*
X354427D01*
G01X339404Y70014D02*
X341140Y65822D01*
G01X339404Y76241D02*
Y70014D01*
G01X339792Y77550D02*
X339404Y76241D01*
G01X339792Y85700D02*
Y77550D01*
G01X339268Y86224D02*
X339792Y85700D01*
G01X339268Y88144D02*
Y86224D01*
G01X340270Y89908D02*
X339268Y88144D01*
G01X341140Y92757D02*
X340270Y89908D01*
G01X333862Y84599D02*
X337793D01*
G01X333064Y83801D02*
X333862Y84599D01*
G01X333064Y82169D02*
Y83801D01*
G01X333733Y81500D02*
X333064Y82169D01*
G01X336246Y81500D02*
X333733D01*
G01X336927Y80819D02*
X336246Y81500D01*
G01X336927Y79319D02*
Y80819D01*
G01X336208Y78600D02*
X336927Y79319D01*
G01X331995Y78600D02*
X336208D01*
G01X331402Y78007D02*
X331995Y78600D01*
G01X331402Y76251D02*
Y78007D01*
G01X331953Y75700D02*
X331402Y76251D01*
G01X335850Y75700D02*
X331953D01*
G01X337793Y73757D02*
X335850Y75700D01*
G01X326892Y74619D02*
X327754Y73757D01*
G01X326892Y86530D02*
Y74619D01*
G01X327754Y87392D02*
X326892Y86530D01*
G01X345504Y84714D02*
X344486D01*
G01X346029Y84189D02*
X345504Y84714D01*
G01X346029Y83081D02*
Y84189D01*
G01X345529Y82581D02*
X346029Y83081D01*
G01X344257Y82581D02*
X345529D01*
G01X343631Y81955D02*
X344257Y82581D01*
G01X343631Y81045D02*
Y81955D01*
G01X344225Y80451D02*
X343631Y81045D01*
G01X345576Y80451D02*
X344225D01*
G01X346177Y79850D02*
X345576Y80451D01*
G01X346177Y78687D02*
Y79850D01*
G01X345617Y78127D02*
X346177Y78687D01*
G01X344226Y78127D02*
X345617D01*
G01X343616Y77517D02*
X344226Y78127D01*
G01X343616Y76527D02*
Y77517D01*
G01X344226Y75917D02*
X343616Y76527D01*
G01X345677Y75917D02*
X344226D01*
G01X346193Y75401D02*
X345677Y75917D01*
G01X346193Y74274D02*
Y75401D01*
G01X345676Y73757D02*
X346193Y74274D01*
G01X344486Y73757D02*
X345676D01*
G01X342592Y514686D02*
X344486Y510114D01*
G01X342592Y516600D02*
Y514686D01*
G01X342874Y516882D02*
X342592Y516600D01*
G01X342874Y520642D02*
Y516882D01*
G01X341692Y521824D02*
X342874Y520642D01*
G01X341692Y526550D02*
Y521824D01*
G01X342799Y527657D02*
X341692Y526550D01*
G01X321061Y518157D02*
Y529014D01*
G01X354140Y526159D02*
Y528637D01*
G01X354665Y525634D02*
X354140Y526159D01*
G01X354665Y521912D02*
Y525634D01*
G01X353944Y521191D02*
X354665Y521912D01*
G01X353944Y518739D02*
Y521191D01*
G01X354526Y518157D02*
X353944Y518739D01*
G01X324407Y515364D02*
Y529014D01*
G01X336104Y525998D02*
X336767Y526661D01*
G01X336104Y525008D02*
Y525998D01*
G01X336661Y524451D02*
X336104Y525008D01*
G01X339199Y524451D02*
X336661D01*
G01X339809Y523841D02*
X339199Y524451D01*
G01X339809Y522851D02*
Y523841D01*
G01X339199Y522241D02*
X339809Y522851D01*
G01X335155Y522241D02*
X339199D01*
G01X334424Y521510D02*
X335155Y522241D01*
G01X334424Y520531D02*
Y521510D01*
G01X334924Y520031D02*
X334424Y520531D01*
G01X335672Y520031D02*
X334924D01*
G01X336248Y519455D02*
X335672Y520031D01*
G01X336248Y518238D02*
Y519455D01*
G01X336849Y517637D02*
X336248Y518238D01*
G01X337839Y517637D02*
X336849D01*
G01X338458Y518256D02*
X337839Y517637D01*
G01X338458Y519455D02*
Y518256D01*
G01X339034Y520031D02*
X338458Y519455D01*
G01X340505Y520031D02*
X339034D01*
G01X341140Y519396D02*
X340505Y520031D01*
G01X341140Y518157D02*
Y519396D01*
G01X352220Y516405D02*
Y527981D01*
G01X351179Y515364D02*
X352220Y516405D01*
G01X345719Y516597D02*
X344486Y515364D01*
G01X345719Y517434D02*
Y516597D01*
G01X344486Y518667D02*
X345719Y517434D01*
G01X344486Y519641D02*
Y518667D01*
G01X345096Y520251D02*
X344486Y519641D01*
G01X348259Y520251D02*
X345096D01*
G01X348869Y520861D02*
X348259Y520251D01*
G01X348869Y521851D02*
Y520861D01*
G01X348259Y522461D02*
X348869Y521851D01*
G01X343895Y522461D02*
X348259D01*
G01X343330Y523026D02*
X343895Y522461D01*
G01X343330Y524016D02*
Y523026D01*
G01X343985Y524671D02*
X343330Y524016D01*
G01X348213Y524671D02*
X343985D01*
G01X348808Y525266D02*
X348213Y524671D01*
G01X348808Y526256D02*
Y525266D01*
G01X348183Y526881D02*
X348808Y526256D01*
G01X332625Y524837D02*
X336055Y528267D01*
G01X332625Y517469D02*
Y524837D01*
G01X337793Y512301D02*
X332625Y517469D01*
G01X337793Y509999D02*
Y512301D01*
G01X350526Y517434D02*
Y527323D01*
G01X349292Y516200D02*
X350526Y517434D01*
G01X349292Y514251D02*
Y516200D01*
G01X347833Y512792D02*
X349292Y514251D01*
G01X354526Y512792D02*
X354307D01*
G01X357154Y515420D02*
X354526Y512792D01*
G01X302054Y566699D02*
X300982D01*
G01X302754Y565999D02*
X302054Y566699D01*
G01X302754Y564725D02*
Y565999D01*
G01X301617Y563588D02*
X302754Y564725D01*
G01X301617Y562512D02*
Y563588D01*
G01X302629Y561500D02*
X301617Y562512D01*
G01X302629Y560300D02*
Y561500D01*
G01X301617Y559288D02*
X302629Y560300D01*
G01X301617Y558212D02*
Y559288D01*
G01X302729Y557100D02*
X301617Y558212D01*
G01X302729Y554467D02*
Y557100D01*
G01X302554Y554292D02*
X302729Y554467D01*
G01X302554Y552600D02*
Y554292D01*
G01X304240Y550914D02*
X302554Y552600D01*
G01X304328Y550914D02*
X304240D01*
G01X342799Y530507D02*
Y527657D01*
G01X344486Y532194D02*
X342799Y530507D01*
G01X344486Y536957D02*
Y532194D01*
G01X354140Y528637D02*
X354525Y529022D01*
G01X338779Y526661D02*
X341140Y529022D01*
G01X336767Y526661D02*
X338779D01*
G01X352220Y527981D02*
X351179Y529022D01*
G01X344992Y526881D02*
X348183D01*
G01X344486Y527387D02*
X344992Y526881D01*
G01X344486Y529022D02*
Y527387D01*
G01X336055Y535219D02*
X337793Y536957D01*
G01X336055Y528267D02*
Y535219D01*
G01X297547Y550914D02*
X297635D01*
G01X295861Y552600D02*
X297547Y550914D01*
G01X295861Y554292D02*
Y552600D01*
G01X296036Y554467D02*
X295861Y554292D01*
G01X296036Y557100D02*
Y554467D01*
G01X294924Y558212D02*
X296036Y557100D01*
G01X294924Y559288D02*
Y558212D01*
G01X295936Y560300D02*
X294924Y559288D01*
G01X295936Y561500D02*
Y560300D01*
G01X294924Y562512D02*
X295936Y561500D01*
G01X294924Y563588D02*
Y562512D01*
G01X296061Y564725D02*
X294924Y563588D01*
G01X296061Y565999D02*
Y564725D01*
G01X295361Y566699D02*
X296061Y565999D01*
G01X294289Y566699D02*
X295361D01*
G01X299277Y557662D02*
X300982Y555957D01*
G01X299277Y567849D02*
Y557662D01*
G01X304328Y572900D02*
X299277Y567849D01*
G01X347833Y534459D02*
Y536957D01*
G01X349542Y532750D02*
X347833Y534459D01*
G01X349542Y528307D02*
Y532750D01*
G01X350526Y527323D02*
X349542Y528307D01*
G01X354525Y532199D02*
X356158Y530566D01*
G01X354525Y536956D02*
Y532199D01*
G01X354526Y536957D02*
X354525Y536956D01*
G01X399765Y67543D02*
X398029Y65807D01*
G01X399765Y85746D02*
Y67543D01*
G01X398029Y87482D02*
X399765Y85746D01*
G01X398029Y89964D02*
Y87482D01*
G01X407690Y66186D02*
X408069Y65807D01*
G01X406341Y69443D02*
X407690Y66186D01*
G01X406341Y75338D02*
Y69443D01*
G01X406546Y75803D02*
X406341Y75338D01*
G01X406546Y85712D02*
Y75803D01*
G01X406310Y86282D02*
X406546Y85712D01*
G01X406310Y88513D02*
Y86282D01*
G01X408068Y92757D02*
X406310Y88513D01*
G01X403109Y67436D02*
X404723Y65822D01*
G01X403109Y81099D02*
Y67436D01*
G01X402661Y81547D02*
X403109Y81099D01*
G01X402661Y85469D02*
Y81547D01*
G01X403705Y86513D02*
X402661Y85469D01*
G01X403705Y88947D02*
Y86513D01*
G01X404722Y89964D02*
X403705Y88947D01*
G01X354927Y86892D02*
Y74158D01*
G01X414761Y65824D02*
X414763Y65822D01*
G01X414761Y70869D02*
Y65824D01*
G01X416379Y72487D02*
X414761Y70869D01*
G01X416379Y83013D02*
Y72487D01*
G01X416092Y83300D02*
X416379Y83013D01*
G01X416092Y85400D02*
Y83300D01*
G01X416692Y86000D02*
X416092Y85400D01*
G01X404292Y100600D02*
X416692Y88200D01*
G01X414763Y75400D02*
Y73757D01*
G01X414068Y76095D02*
X414763Y75400D01*
G01X409994Y76095D02*
X414068D01*
G01X409384Y76705D02*
X409994Y76095D01*
G01X409384Y77695D02*
Y76705D01*
G01X409994Y78305D02*
X409384Y77695D01*
G01X413648Y78305D02*
X409994D01*
G01X414258Y78915D02*
X413648Y78305D01*
G01X414258Y79905D02*
Y78915D01*
G01X413648Y80515D02*
X414258Y79905D01*
G01X410008Y80515D02*
X413648D01*
G01X409470Y81053D02*
X410008Y80515D01*
G01X409470Y82043D02*
Y81053D01*
G01X410152Y82725D02*
X409470Y82043D01*
G01X413264Y82725D02*
X410152D01*
G01X414016Y83477D02*
X413264Y82725D01*
G01X414016Y86647D02*
Y83477D01*
G01X414761Y87392D02*
X414016Y86647D01*
G01X403891Y100600D02*
X404292D01*
G01X401375Y103116D02*
X403891Y100600D01*
G01X414819Y103116D02*
X416835Y101100D01*
G01X410742Y100650D02*
X423292Y88100D01*
G01X410592Y100650D02*
X410742D01*
G01X408126Y103116D02*
X410592Y100650D01*
G01X408068Y519519D02*
Y518157D01*
G01X408678Y520129D02*
X408068Y519519D01*
G01X410410Y520129D02*
X408678D01*
G01X411020Y520739D02*
X410410Y520129D01*
G01X411020Y521729D02*
Y520739D01*
G01X410410Y522339D02*
X411020Y521729D01*
G01X409013Y522339D02*
X410410D01*
G01X408418Y522934D02*
X409013Y522339D01*
G01X408418Y523924D02*
Y522934D01*
G01X409043Y524549D02*
X408418Y523924D01*
G01X412997Y524549D02*
X409043D01*
G01X413576Y525128D02*
X412997Y524549D01*
G01X413576Y526118D02*
Y525128D01*
G01X412935Y526759D02*
X413576Y526118D01*
G01X396307Y516967D02*
Y529688D01*
G01X394682Y515342D02*
X396307Y516967D01*
G01X394682Y512792D02*
Y515342D01*
G01X398029Y515364D02*
Y529007D01*
G01X414761Y515333D02*
Y512792D01*
G01X412892Y517202D02*
X414761Y515333D01*
G01X412892Y519099D02*
Y517202D01*
G01X416379Y522586D02*
X412892Y519099D01*
G01X416379Y532947D02*
Y522586D01*
G01X404722Y515364D02*
Y529021D01*
G01X357154Y526870D02*
Y515420D01*
G01X408678Y526759D02*
X412935D01*
G01X408068Y527369D02*
X408678Y526759D01*
G01X408068Y529006D02*
Y527369D01*
G01X408069Y529007D02*
X408068Y529006D01*
G01X394594Y537057D02*
X394595Y537058D01*
G01X394594Y534647D02*
Y537057D01*
G01X396683Y532558D02*
X394594Y534647D01*
G01X396683Y530064D02*
Y532558D01*
G01X396307Y529688D02*
X396683Y530064D01*
G01X414763Y534563D02*
X416379Y532947D01*
G01X414763Y536957D02*
Y534563D01*
G01X404722Y529021D02*
X404723Y529022D01*
G01X356158Y527866D02*
X357154Y526870D01*
G01X356158Y530566D02*
Y527866D01*
G01X443146Y-42355D02*
G02Y-45915I0J-1780D01*
G01X443264Y67438D02*
X444880Y65822D01*
G01X443264Y76128D02*
Y67438D01*
G01X442992Y76400D02*
X443264Y76128D01*
G01X442992Y85900D02*
Y76400D01*
G01X443392Y86300D02*
X442992Y85900D01*
G01X443392Y88200D02*
Y86300D01*
G01X430192Y101400D02*
X443392Y88200D01*
G01X416692D02*
Y86000D01*
G01X438187Y65824D02*
X438189Y65822D01*
G01X438187Y68105D02*
Y65824D01*
G01X435955Y70337D02*
X438187Y68105D01*
G01X435955Y72063D02*
Y70337D01*
G01X436500Y72608D02*
X435955Y72063D01*
G01X436500Y75192D02*
Y72608D01*
G01X436192Y75500D02*
X436500Y75192D01*
G01X436192Y76922D02*
Y75500D01*
G01X436992Y77722D02*
X436192Y76922D01*
G01X439083Y77722D02*
X436992D01*
G01X439916Y78555D02*
X439083Y77722D01*
G01X439916Y80255D02*
Y78555D01*
G01X439149Y81022D02*
X439916Y80255D01*
G01X436992Y81022D02*
X439149D01*
G01X436192Y81822D02*
X436992Y81022D01*
G01X436192Y85500D02*
Y81822D01*
G01X436992Y86300D02*
X436192Y85500D01*
G01X436992Y87800D02*
Y86300D01*
G01X423692Y101100D02*
X436992Y87800D01*
G01X431494Y68198D02*
Y65807D01*
G01X429777Y69915D02*
X431494Y68198D01*
G01X429777Y75748D02*
Y69915D01*
G01X430192Y76163D02*
X429777Y75748D01*
G01X430192Y82500D02*
Y76163D01*
G01X429292Y83400D02*
X430192Y82500D01*
G01X429292Y85300D02*
Y83400D01*
G01X430292Y86300D02*
X429292Y85300D01*
G01X430292Y87800D02*
Y86300D01*
G01X416992Y101100D02*
X430292Y87800D01*
G01X424801Y69755D02*
Y65807D01*
G01X423078Y71478D02*
X424801Y69755D01*
G01X423078Y78036D02*
Y71478D01*
G01X423792Y78750D02*
X423078Y78036D01*
G01X426692Y78750D02*
X423792D01*
G01X427492Y79550D02*
X426692Y78750D01*
G01X427492Y81150D02*
Y79550D01*
G01X426692Y81950D02*
X427492Y81150D01*
G01X423792Y81950D02*
X426692D01*
G01X422992Y82750D02*
X423792Y81950D01*
G01X422992Y86000D02*
Y82750D01*
G01X423292Y86300D02*
X422992Y86000D01*
G01X423292Y88100D02*
Y86300D01*
G01X429396Y101400D02*
X430192D01*
G01X427696Y103100D02*
X429396Y101400D01*
G01X423528Y101100D02*
X423692D01*
G01X421512Y103116D02*
X423528Y101100D01*
G01X416835D02*
X416992D01*
G01X443992Y517400D02*
Y526900D01*
G01X443092Y516500D02*
X443992Y517400D01*
G01X443092Y514000D02*
Y516500D01*
G01X443492Y513600D02*
X443092Y514000D01*
G01X443492Y511900D02*
Y513600D01*
G01X435192Y503600D02*
X443492Y511900D01*
G01X435192Y499400D02*
Y503600D01*
G01X444880Y536955D02*
X444882Y536957D01*
G01X444880Y531788D02*
Y536955D01*
G01X443265Y530173D02*
X444880Y531788D01*
G01X443265Y527627D02*
Y530173D01*
G01X443992Y526900D02*
X443265Y527627D01*
G01X497635Y550914D02*
X497723D01*
G01X495949Y552600D02*
X497635Y550914D01*
G01X495949Y554292D02*
Y552600D01*
G01X496856Y555199D02*
X495949Y554292D01*
G01X496856Y556792D02*
Y555199D01*
G01X495712Y557936D02*
X496856Y556792D01*
G01X495712Y559356D02*
Y557936D01*
G01X496556Y560200D02*
X495712Y559356D01*
G01X496556Y561900D02*
Y560200D01*
G01X495712Y562744D02*
X496556Y561900D01*
G01X495712Y563956D02*
Y562744D01*
G01X496656Y564900D02*
X495712Y563956D01*
G01X496656Y566100D02*
Y564900D01*
G01X496057Y566699D02*
X496656Y566100D01*
G01X495077Y566699D02*
X496057D01*
G01X493372Y557662D02*
X495077Y555957D01*
G01X493372Y569315D02*
Y557662D01*
G01X496557Y572500D02*
X493372Y569315D01*
G01X497723Y572500D02*
X496557D01*
G01X530183Y557662D02*
X531888Y555957D01*
G01X530183Y569315D02*
Y557662D01*
G01X533368Y572500D02*
X530183Y569315D01*
G01X534534Y572500D02*
X533368D01*
G01X527167D02*
X528155D01*
G01X524112Y569445D02*
X527167Y572500D01*
G01X524112Y568257D02*
Y569445D01*
G01X523490Y567635D02*
X524112Y568257D01*
G01X523490Y557662D02*
Y567635D01*
G01X525195Y555957D02*
X523490Y557662D01*
G01X528153Y550914D02*
X528241D01*
G01X526467Y552600D02*
X528153Y550914D01*
G01X526467Y554800D02*
Y552600D01*
G01X526967Y555300D02*
X526467Y554800D01*
G01X526967Y557199D02*
Y555300D01*
G01X525830Y558336D02*
X526967Y557199D01*
G01X525830Y559664D02*
Y558336D01*
G01X526767Y560601D02*
X525830Y559664D01*
G01X526767Y561999D02*
Y560601D01*
G01X525830Y562936D02*
X526767Y561999D01*
G01X525830Y564164D02*
Y562936D01*
G01X526867Y565201D02*
X525830Y564164D01*
G01X526867Y566099D02*
Y565201D01*
G01X526267Y566699D02*
X526867Y566099D01*
G01X525195Y566699D02*
X526267D01*
G01X491342Y550914D02*
X491430D01*
G01X489656Y552600D02*
X491342Y550914D01*
G01X489656Y554800D02*
Y552600D01*
G01X490156Y555300D02*
X489656Y554800D01*
G01X490156Y557199D02*
Y555300D01*
G01X489019Y558336D02*
X490156Y557199D01*
G01X489019Y559664D02*
Y558336D01*
G01X489956Y560601D02*
X489019Y559664D01*
G01X489956Y561999D02*
Y560601D01*
G01X489019Y562936D02*
X489956Y561999D01*
G01X489019Y564164D02*
Y562936D01*
G01X490056Y565201D02*
X489019Y564164D01*
G01X490056Y566099D02*
Y565201D01*
G01X489456Y566699D02*
X490056Y566099D01*
G01X488384Y566699D02*
X489456D01*
G01X510104Y567849D02*
X515155Y572900D01*
G01X510104Y557662D02*
Y567849D01*
G01X511809Y555957D02*
X510104Y557662D01*
G01X534446Y550914D02*
X534534D01*
G01X532760Y552600D02*
X534446Y550914D01*
G01X532760Y554292D02*
Y552600D01*
G01X533667Y555199D02*
X532760Y554292D01*
G01X533667Y556792D02*
Y555199D01*
G01X532523Y557936D02*
X533667Y556792D01*
G01X532523Y559356D02*
Y557936D01*
G01X533367Y560200D02*
X532523Y559356D01*
G01X533367Y561900D02*
Y560200D01*
G01X532523Y562744D02*
X533367Y561900D01*
G01X532523Y563956D02*
Y562744D01*
G01X533467Y564900D02*
X532523Y563956D01*
G01X533467Y566100D02*
Y564900D01*
G01X532868Y566699D02*
X533467Y566100D01*
G01X531888Y566699D02*
X532868D01*
G01X521760Y550914D02*
X521848D01*
G01X520074Y552600D02*
X521760Y550914D01*
G01X520074Y554292D02*
Y552600D01*
G01X520249Y554467D02*
X520074Y554292D01*
G01X520249Y557100D02*
Y554467D01*
G01X519137Y558212D02*
X520249Y557100D01*
G01X519137Y559288D02*
Y558212D01*
G01X520149Y560300D02*
X519137Y559288D01*
G01X520149Y561500D02*
Y560300D01*
G01X519137Y562512D02*
X520149Y561500D01*
G01X519137Y563588D02*
Y562512D01*
G01X520274Y564725D02*
X519137Y563588D01*
G01X520274Y565999D02*
Y564725D01*
G01X519574Y566699D02*
X520274Y565999D01*
G01X518502Y566699D02*
X519574D01*
G01X515067Y550914D02*
X515155D01*
G01X513381Y552600D02*
X515067Y550914D01*
G01X513381Y554292D02*
Y552600D01*
G01X513556Y554467D02*
X513381Y554292D01*
G01X513556Y557100D02*
Y554467D01*
G01X512444Y558212D02*
X513556Y557100D01*
G01X512444Y559288D02*
Y558212D01*
G01X513456Y560300D02*
X512444Y559288D01*
G01X513456Y561500D02*
Y560300D01*
G01X512444Y562512D02*
X513456Y561500D01*
G01X512444Y563588D02*
Y562512D01*
G01X513581Y564725D02*
X512444Y563588D01*
G01X513581Y565999D02*
Y564725D01*
G01X512881Y566699D02*
X513581Y565999D01*
G01X511809Y566699D02*
X512881D01*
G01X516797Y567849D02*
X521848Y572900D01*
G01X516797Y557662D02*
Y567849D01*
G01X518502Y555957D02*
X516797Y557662D01*
G01X490356Y572500D02*
X491344D01*
G01X487301Y569445D02*
X490356Y572500D01*
G01X487301Y568257D02*
Y569445D01*
G01X486679Y567635D02*
X487301Y568257D01*
G01X486679Y557662D02*
Y567635D01*
G01X488384Y555957D02*
X486679Y557662D01*
G01X558571Y550914D02*
X558659D01*
G01X556885Y552600D02*
X558571Y550914D01*
G01X556885Y554292D02*
Y552600D01*
G01X557060Y554467D02*
X556885Y554292D01*
G01X557060Y557100D02*
Y554467D01*
G01X555948Y558212D02*
X557060Y557100D01*
G01X555948Y559288D02*
Y558212D01*
G01X556960Y560300D02*
X555948Y559288D01*
G01X556960Y561500D02*
Y560300D01*
G01X555948Y562512D02*
X556960Y561500D01*
G01X555948Y563588D02*
Y562512D01*
G01X557085Y564725D02*
X555948Y563588D01*
G01X557085Y565999D02*
Y564725D01*
G01X556385Y566699D02*
X557085Y565999D01*
G01X555313Y566699D02*
X556385D01*
G01X551878Y550914D02*
X551966D01*
G01X550192Y552600D02*
X551878Y550914D01*
G01X550192Y554292D02*
Y552600D01*
G01X550367Y554467D02*
X550192Y554292D01*
G01X550367Y557100D02*
Y554467D01*
G01X549255Y558212D02*
X550367Y557100D01*
G01X549255Y559288D02*
Y558212D01*
G01X550267Y560300D02*
X549255Y559288D01*
G01X550267Y561500D02*
Y560300D01*
G01X549255Y562512D02*
X550267Y561500D01*
G01X549255Y563588D02*
Y562512D01*
G01X550392Y564725D02*
X549255Y563588D01*
G01X550392Y565999D02*
Y564725D01*
G01X549692Y566699D02*
X550392Y565999D01*
G01X548620Y566699D02*
X549692D01*
G01X553608Y567849D02*
X558659Y572900D01*
G01X553608Y557662D02*
Y567849D01*
G01X555313Y555957D02*
X553608Y557662D01*
G01X546915Y567849D02*
X551966Y572900D01*
G01X546915Y557662D02*
Y567849D01*
G01X548620Y555957D02*
X546915Y557662D01*
G01X968936Y67547D02*
X970669Y65814D01*
G01X968936Y76021D02*
Y67547D01*
G01X969300Y76385D02*
X968936Y76021D01*
G01X969300Y85898D02*
Y76385D01*
G01X968600Y86598D02*
X969300Y85898D01*
G01X968600Y88100D02*
Y86598D01*
G01X970669Y90169D02*
X968600Y88100D01*
G01X970669Y92757D02*
Y90169D01*
G01X971700Y76219D02*
X972403Y75516D01*
G01X971700Y78517D02*
Y76219D01*
G01X972310Y79127D02*
X971700Y78517D01*
G01Y82347D02*
X972310Y81737D01*
G01X971700Y85300D02*
Y82347D01*
G01X974015Y87615D02*
X971700Y85300D01*
G01X970669Y518157D02*
Y529014D01*
G01X923430Y550914D02*
X923518D01*
G01X921744Y552600D02*
X923430Y550914D01*
G01X921744Y554800D02*
Y552600D01*
G01X922244Y555300D02*
X921744Y554800D01*
G01X922244Y557199D02*
Y555300D01*
G01X921107Y558336D02*
X922244Y557199D01*
G01X921107Y559664D02*
Y558336D01*
G01X922044Y560601D02*
X921107Y559664D01*
G01X922044Y561999D02*
Y560601D01*
G01X921107Y562936D02*
X922044Y561999D01*
G01X921107Y564164D02*
Y562936D01*
G01X922144Y565201D02*
X921107Y564164D01*
G01X922144Y566099D02*
Y565201D01*
G01X921544Y566699D02*
X922144Y566099D01*
G01X920472Y566699D02*
X921544D01*
G01X922444Y572500D02*
X923432D01*
G01X919389Y569445D02*
X922444Y572500D01*
G01X919389Y568257D02*
Y569445D01*
G01X918767Y567635D02*
X919389Y568257D01*
G01X918767Y557662D02*
Y567635D01*
G01X920472Y555957D02*
X918767Y557662D01*
G01X953848Y550914D02*
X953936D01*
G01X952162Y552600D02*
X953848Y550914D01*
G01X952162Y554292D02*
Y552600D01*
G01X952337Y554467D02*
X952162Y554292D01*
G01X952337Y557100D02*
Y554467D01*
G01X951225Y558212D02*
X952337Y557100D01*
G01X951225Y559288D02*
Y558212D01*
G01X952237Y560300D02*
X951225Y559288D01*
G01X952237Y561500D02*
Y560300D01*
G01X951225Y562512D02*
X952237Y561500D01*
G01X951225Y563588D02*
Y562512D01*
G01X952362Y564725D02*
X951225Y563588D01*
G01X952362Y565999D02*
Y564725D01*
G01X951662Y566699D02*
X952362Y565999D01*
G01X950590Y566699D02*
X951662D01*
G01X942192Y567849D02*
X947243Y572900D01*
G01X942192Y557662D02*
Y567849D01*
G01X943897Y555957D02*
X942192Y557662D01*
G01X925460D02*
X927165Y555957D01*
G01X925460Y569315D02*
Y557662D01*
G01X928645Y572500D02*
X925460Y569315D01*
G01X929811Y572500D02*
X928645D01*
G01X947155Y550914D02*
X947243D01*
G01X945469Y552600D02*
X947155Y550914D01*
G01X945469Y554292D02*
Y552600D01*
G01X945644Y554467D02*
X945469Y554292D01*
G01X945644Y557100D02*
Y554467D01*
G01X944532Y558212D02*
X945644Y557100D01*
G01X944532Y559288D02*
Y558212D01*
G01X945544Y560300D02*
X944532Y559288D01*
G01X945544Y561500D02*
Y560300D01*
G01X944532Y562512D02*
X945544Y561500D01*
G01X944532Y563588D02*
Y562512D01*
G01X945669Y564725D02*
X944532Y563588D01*
G01X945669Y565999D02*
Y564725D01*
G01X944969Y566699D02*
X945669Y565999D01*
G01X943897Y566699D02*
X944969D01*
G01X929723Y550914D02*
X929811D01*
G01X928037Y552600D02*
X929723Y550914D01*
G01X928037Y554292D02*
Y552600D01*
G01X928944Y555199D02*
X928037Y554292D01*
G01X928944Y556792D02*
Y555199D01*
G01X927800Y557936D02*
X928944Y556792D01*
G01X927800Y559356D02*
Y557936D01*
G01X928644Y560200D02*
X927800Y559356D01*
G01X928644Y561900D02*
Y560200D01*
G01X927800Y562744D02*
X928644Y561900D01*
G01X927800Y563956D02*
Y562744D01*
G01X928744Y564900D02*
X927800Y563956D01*
G01X928744Y566100D02*
Y564900D01*
G01X928145Y566699D02*
X928744Y566100D01*
G01X927165Y566699D02*
X928145D01*
G01X948885Y567849D02*
X953936Y572900D01*
G01X948885Y557662D02*
Y567849D01*
G01X950590Y555957D02*
X948885Y557662D01*
G01X1004535Y74158D02*
X1004134Y73757D01*
G01X1004535Y86892D02*
Y74158D01*
G01X1004035Y87392D02*
X1004535Y86892D01*
G01X1004023Y87392D02*
X1004035D01*
G01X1004133Y68491D02*
Y65822D01*
G01X1004134Y68492D02*
X1004133Y68491D01*
G01X1004134Y70667D02*
Y68492D01*
G01X1002529Y72272D02*
X1004134Y70667D01*
G01X1002529Y75530D02*
Y72272D01*
G01X1002700Y75701D02*
X1002529Y75530D01*
G01X1002700Y85500D02*
Y75701D01*
G01X1002165Y86035D02*
X1002700Y85500D01*
G01X1002165Y88465D02*
Y86035D01*
G01X1004023Y90323D02*
X1002165Y88465D01*
G01X1004023Y92757D02*
Y90323D01*
G01X983470Y84599D02*
X987401D01*
G01X982672Y83801D02*
X983470Y84599D01*
G01X982672Y82169D02*
Y83801D01*
G01X983341Y81500D02*
X982672Y82169D01*
G01X985854Y81500D02*
X983341D01*
G01X986535Y80819D02*
X985854Y81500D01*
G01X986535Y79319D02*
Y80819D01*
G01X985816Y78600D02*
X986535Y79319D01*
G01X981603Y78600D02*
X985816D01*
G01X981010Y78007D02*
X981603Y78600D01*
G01X981010Y76251D02*
Y78007D01*
G01X981561Y75700D02*
X981010Y76251D01*
G01X985458Y75700D02*
X981561D01*
G01X987401Y73757D02*
X985458Y75700D01*
G01X976500Y74619D02*
X977362Y73757D01*
G01X976500Y86530D02*
Y74619D01*
G01X977362Y87392D02*
X976500Y86530D01*
G01X993695Y66785D02*
X994094Y65822D01*
G01X992459Y73002D02*
X993695Y66785D01*
G01X992459Y74142D02*
Y73002D01*
G01X991571Y76284D02*
X992459Y74142D01*
G01X991571Y83875D02*
Y76284D01*
G01X994094Y89964D02*
X991571Y83875D01*
G01X989012Y70014D02*
X990748Y65822D01*
G01X989012Y76241D02*
Y70014D01*
G01X989400Y77550D02*
X989012Y76241D01*
G01X989400Y85700D02*
Y77550D01*
G01X988876Y86224D02*
X989400Y85700D01*
G01X988876Y88144D02*
Y86224D01*
G01X989878Y89908D02*
X988876Y88144D01*
G01X990748Y92757D02*
X989878Y89908D01*
G01X997441Y77457D02*
Y73757D01*
G01X998051Y78067D02*
X997441Y77457D01*
G01X998562Y78067D02*
X998051D01*
G01X999062Y78567D02*
X998562Y78067D01*
G01X999062Y79667D02*
Y78567D01*
G01X998452Y80277D02*
X999062Y79667D01*
G01X997889Y80277D02*
X998452D01*
G01X997289Y80877D02*
X997889Y80277D01*
G01X997289Y87240D02*
Y80877D01*
G01X997441Y87392D02*
X997289Y87240D01*
G01X1000787Y66623D02*
Y65822D01*
G01X1000177Y67233D02*
X1000787Y66623D01*
G01X998674Y67233D02*
X1000177D01*
G01X998064Y67843D02*
X998674Y67233D01*
G01X998064Y69233D02*
Y67843D01*
G01X998674Y69843D02*
X998064Y69233D01*
G01X1000177Y69843D02*
X998674D01*
G01X1000787Y70453D02*
X1000177Y69843D01*
G01X1000787Y71258D02*
Y70453D01*
G01X999061Y72984D02*
X1000787Y71258D01*
G01X999061Y74891D02*
Y72984D01*
G01X1000700Y76530D02*
X999061Y74891D01*
G01X1000700Y82265D02*
Y76530D01*
G01X998942Y84023D02*
X1000700Y82265D01*
G01X998942Y85542D02*
Y84023D01*
G01X999400Y86000D02*
X998942Y85542D01*
G01X999400Y88577D02*
Y86000D01*
G01X1000787Y89964D02*
X999400Y88577D01*
G01X995112Y84714D02*
X994094D01*
G01X995637Y84189D02*
X995112Y84714D01*
G01X995637Y83081D02*
Y84189D01*
G01X995137Y82581D02*
X995637Y83081D01*
G01X993865Y82581D02*
X995137D01*
G01X993239Y81955D02*
X993865Y82581D01*
G01X993239Y81045D02*
Y81955D01*
G01X993833Y80451D02*
X993239Y81045D01*
G01X995184Y80451D02*
X993833D01*
G01X995785Y79850D02*
X995184Y80451D01*
G01X995785Y78687D02*
Y79850D01*
G01X995225Y78127D02*
X995785Y78687D01*
G01X993834Y78127D02*
X995225D01*
G01X993224Y77517D02*
X993834Y78127D01*
G01X993224Y76527D02*
Y77517D01*
G01X993834Y75917D02*
X993224Y76527D01*
G01X995285Y75917D02*
X993834D01*
G01X995801Y75401D02*
X995285Y75917D01*
G01X995801Y74274D02*
Y75401D01*
G01X995284Y73757D02*
X995801Y74274D01*
G01X994094Y73757D02*
X995284D01*
G01X974015Y67175D02*
Y65814D01*
G01X976031Y69191D02*
X974015Y67175D01*
G01X976031Y70964D02*
Y69191D01*
G01X975351Y71644D02*
X976031Y70964D01*
G01X973591Y71644D02*
X975351D01*
G01X972403Y72832D02*
X973591Y71644D01*
G01X972403Y75516D02*
Y72832D01*
G01X973375Y79127D02*
X972310D01*
G01X973875Y79627D02*
X973375Y79127D01*
G01X973875Y81237D02*
Y79627D01*
G01X973375Y81737D02*
X973875Y81237D01*
G01X972310Y81737D02*
X973375D01*
G01X974015Y89964D02*
Y87615D01*
G01X1000134Y517434D02*
Y527323D01*
G01X998900Y516200D02*
X1000134Y517434D01*
G01X998900Y514251D02*
Y516200D01*
G01X997441Y512792D02*
X998900Y514251D01*
G01X992200Y514686D02*
X994094Y510114D01*
G01X992200Y516600D02*
Y514686D01*
G01X992482Y516882D02*
X992200Y516600D01*
G01X992482Y520642D02*
Y516882D01*
G01X991300Y521824D02*
X992482Y520642D01*
G01X991300Y526550D02*
Y521824D01*
G01X992407Y527657D02*
X991300Y526550D01*
G01X985712Y525998D02*
X986375Y526661D01*
G01X985712Y525008D02*
Y525998D01*
G01X986269Y524451D02*
X985712Y525008D01*
G01X988807Y524451D02*
X986269D01*
G01X989417Y523841D02*
X988807Y524451D01*
G01X989417Y522851D02*
Y523841D01*
G01X988807Y522241D02*
X989417Y522851D01*
G01X984763Y522241D02*
X988807D01*
G01X984032Y521510D02*
X984763Y522241D01*
G01X984032Y520531D02*
Y521510D01*
G01X984532Y520031D02*
X984032Y520531D01*
G01X985280Y520031D02*
X984532D01*
G01X985856Y519455D02*
X985280Y520031D01*
G01X985856Y518238D02*
Y519455D01*
G01X986457Y517637D02*
X985856Y518238D01*
G01X987447Y517637D02*
X986457D01*
G01X988066Y518256D02*
X987447Y517637D01*
G01X988066Y519455D02*
Y518256D01*
G01X988642Y520031D02*
X988066Y519455D01*
G01X990113Y520031D02*
X988642D01*
G01X990748Y519396D02*
X990113Y520031D01*
G01X990748Y518157D02*
Y519396D01*
G01X1004134Y512792D02*
X1003915D01*
G01X1006762Y515420D02*
X1004134Y512792D01*
G01X1006762Y526870D02*
Y515420D01*
G01X982233Y524837D02*
X985663Y528267D01*
G01X982233Y517469D02*
Y524837D01*
G01X987401Y512301D02*
X982233Y517469D01*
G01X987401Y509999D02*
Y512301D01*
G01X1001828Y516405D02*
Y527981D01*
G01X1000787Y515364D02*
X1001828Y516405D01*
G01X995327Y516597D02*
X994094Y515364D01*
G01X995327Y517434D02*
Y516597D01*
G01X994094Y518667D02*
X995327Y517434D01*
G01X994094Y519641D02*
Y518667D01*
G01X994704Y520251D02*
X994094Y519641D01*
G01X997867Y520251D02*
X994704D01*
G01X998477Y520861D02*
X997867Y520251D01*
G01X998477Y521851D02*
Y520861D01*
G01X997867Y522461D02*
X998477Y521851D01*
G01X993503Y522461D02*
X997867D01*
G01X992938Y523026D02*
X993503Y522461D01*
G01X992938Y524016D02*
Y523026D01*
G01X993593Y524671D02*
X992938Y524016D01*
G01X997821Y524671D02*
X993593D01*
G01X998416Y525266D02*
X997821Y524671D01*
G01X998416Y526256D02*
Y525266D01*
G01X997791Y526881D02*
X998416Y526256D01*
G01X974015Y515364D02*
Y529014D01*
G01X1003748Y526159D02*
Y528637D01*
G01X1004273Y525634D02*
X1003748Y526159D01*
G01X1004273Y521912D02*
Y525634D01*
G01X1003552Y521191D02*
X1004273Y521912D01*
G01X1003552Y518739D02*
Y521191D01*
G01X1004134Y518157D02*
X1003552Y518739D01*
G01X997441Y534459D02*
Y536957D01*
G01X999150Y532750D02*
X997441Y534459D01*
G01X999150Y528307D02*
Y532750D01*
G01X1000134Y527323D02*
X999150Y528307D01*
G01X992407Y530507D02*
Y527657D01*
G01X994094Y532194D02*
X992407Y530507D01*
G01X994094Y536957D02*
Y532194D01*
G01X988387Y526661D02*
X990748Y529022D01*
G01X986375Y526661D02*
X988387D01*
G01X1005766Y527866D02*
X1006762Y526870D01*
G01X1005766Y530566D02*
Y527866D01*
G01X1004133Y532199D02*
X1005766Y530566D01*
G01X1004133Y536956D02*
Y532199D01*
G01X1004134Y536957D02*
X1004133Y536956D01*
G01X985663Y535219D02*
X987401Y536957D01*
G01X985663Y528267D02*
Y535219D01*
G01X1001828Y527981D02*
X1000787Y529022D01*
G01X994600Y526881D02*
X997791D01*
G01X994094Y527387D02*
X994600Y526881D01*
G01X994094Y529022D02*
Y527387D01*
G01X1003748Y528637D02*
X1004133Y529022D01*
G01X1057298Y66186D02*
X1057677Y65807D01*
G01X1055949Y69443D02*
X1057298Y66186D01*
G01X1055949Y75338D02*
Y69443D01*
G01X1056154Y75803D02*
X1055949Y75338D01*
G01X1056154Y85712D02*
Y75803D01*
G01X1055918Y86282D02*
X1056154Y85712D01*
G01X1055918Y88513D02*
Y86282D01*
G01X1057676Y92757D02*
X1055918Y88513D01*
G01X1064369Y65824D02*
X1064371Y65822D01*
G01X1064369Y70869D02*
Y65824D01*
G01X1065987Y72487D02*
X1064369Y70869D01*
G01X1065987Y83013D02*
Y72487D01*
G01X1065700Y83300D02*
X1065987Y83013D01*
G01X1065700Y85400D02*
Y83300D01*
G01X1066300Y86000D02*
X1065700Y85400D01*
G01X1066300Y88200D02*
Y86000D01*
G01X1053900Y100600D02*
X1066300Y88200D01*
G01X1074409Y69755D02*
Y65807D01*
G01X1072686Y71478D02*
X1074409Y69755D01*
G01X1072686Y78036D02*
Y71478D01*
G01X1073400Y78750D02*
X1072686Y78036D01*
G01X1076300Y78750D02*
X1073400D01*
G01X1077100Y79550D02*
X1076300Y78750D01*
G01X1077100Y81150D02*
Y79550D01*
G01X1076300Y81950D02*
X1077100Y81150D01*
G01X1073400Y81950D02*
X1076300D01*
G01X1072600Y82750D02*
X1073400Y81950D01*
G01X1072600Y86000D02*
Y82750D01*
G01X1072900Y86300D02*
X1072600Y86000D01*
G01X1072900Y88100D02*
Y86300D01*
G01X1060350Y100650D02*
X1072900Y88100D01*
G01X1092872Y67438D02*
X1094488Y65822D01*
G01X1092872Y76128D02*
Y67438D01*
G01X1092600Y76400D02*
X1092872Y76128D01*
G01X1092600Y85900D02*
Y76400D01*
G01X1093000Y86300D02*
X1092600Y85900D01*
G01X1093000Y88200D02*
Y86300D01*
G01X1079800Y101400D02*
X1093000Y88200D01*
G01X1087795Y65824D02*
X1087797Y65822D01*
G01X1087795Y68105D02*
Y65824D01*
G01X1085563Y70337D02*
X1087795Y68105D01*
G01X1085563Y72063D02*
Y70337D01*
G01X1086108Y72608D02*
X1085563Y72063D01*
G01X1086108Y75192D02*
Y72608D01*
G01X1085800Y75500D02*
X1086108Y75192D01*
G01X1085800Y76922D02*
Y75500D01*
G01X1086600Y77722D02*
X1085800Y76922D01*
G01X1088691Y77722D02*
X1086600D01*
G01X1089524Y78555D02*
X1088691Y77722D01*
G01X1089524Y80255D02*
Y78555D01*
G01X1088757Y81022D02*
X1089524Y80255D01*
G01X1086600Y81022D02*
X1088757D01*
G01X1085800Y81822D02*
X1086600Y81022D01*
G01X1085800Y85500D02*
Y81822D01*
G01X1086600Y86300D02*
X1085800Y85500D01*
G01X1086600Y87800D02*
Y86300D01*
G01X1073300Y101100D02*
X1086600Y87800D01*
G01X1052717Y67436D02*
X1054331Y65822D01*
G01X1052717Y81099D02*
Y67436D01*
G01X1052269Y81547D02*
X1052717Y81099D01*
G01X1052269Y85469D02*
Y81547D01*
G01X1053313Y86513D02*
X1052269Y85469D01*
G01X1053313Y88947D02*
Y86513D01*
G01X1054330Y89964D02*
X1053313Y88947D01*
G01X1064371Y75400D02*
Y73757D01*
G01X1063676Y76095D02*
X1064371Y75400D01*
G01X1059602Y76095D02*
X1063676D01*
G01X1058992Y76705D02*
X1059602Y76095D01*
G01X1058992Y77695D02*
Y76705D01*
G01X1059602Y78305D02*
X1058992Y77695D01*
G01X1063256Y78305D02*
X1059602D01*
G01X1063866Y78915D02*
X1063256Y78305D01*
G01X1063866Y79905D02*
Y78915D01*
G01X1063256Y80515D02*
X1063866Y79905D01*
G01X1059616Y80515D02*
X1063256D01*
G01X1059078Y81053D02*
X1059616Y80515D01*
G01X1059078Y82043D02*
Y81053D01*
G01X1059760Y82725D02*
X1059078Y82043D01*
G01X1062872Y82725D02*
X1059760D01*
G01X1063624Y83477D02*
X1062872Y82725D01*
G01X1063624Y86647D02*
Y83477D01*
G01X1064369Y87392D02*
X1063624Y86647D01*
G01X1049373Y67543D02*
X1047637Y65807D01*
G01X1049373Y85746D02*
Y67543D01*
G01X1047637Y87482D02*
X1049373Y85746D01*
G01X1047637Y89964D02*
Y87482D01*
G01X1081102Y68198D02*
Y65807D01*
G01X1079385Y69915D02*
X1081102Y68198D01*
G01X1079385Y75748D02*
Y69915D01*
G01X1079800Y76163D02*
X1079385Y75748D01*
G01X1079800Y82500D02*
Y76163D01*
G01X1078900Y83400D02*
X1079800Y82500D01*
G01X1078900Y85300D02*
Y83400D01*
G01X1079900Y86300D02*
X1078900Y85300D01*
G01X1079900Y87800D02*
Y86300D01*
G01X1066600Y101100D02*
X1079900Y87800D01*
G01X1053499Y100600D02*
X1053900D01*
G01X1050983Y103116D02*
X1053499Y100600D01*
G01X1060200Y100650D02*
X1060350D01*
G01X1057734Y103116D02*
X1060200Y100650D01*
G01X1079004Y101400D02*
X1079800D01*
G01X1077304Y103100D02*
X1079004Y101400D01*
G01X1073136Y101100D02*
X1073300D01*
G01X1071120Y103116D02*
X1073136Y101100D01*
G01X1066443D02*
X1066600D01*
G01X1064427Y103116D02*
X1066443Y101100D01*
G01X1047637Y515364D02*
Y529007D01*
G01X1054330Y515364D02*
Y529021D01*
G01X1064369Y515333D02*
Y512792D01*
G01X1062500Y517202D02*
X1064369Y515333D01*
G01X1062500Y519099D02*
Y517202D01*
G01X1065987Y522586D02*
X1062500Y519099D01*
G01X1065987Y532947D02*
Y522586D01*
G01X1045915Y516967D02*
Y529688D01*
G01X1044290Y515342D02*
X1045915Y516967D01*
G01X1044290Y512792D02*
Y515342D01*
G01X1093600Y517400D02*
Y526900D01*
G01X1092700Y516500D02*
X1093600Y517400D01*
G01X1092700Y514000D02*
Y516500D01*
G01X1093100Y513600D02*
X1092700Y514000D01*
G01X1093100Y511900D02*
Y513600D01*
G01X1084800Y503600D02*
X1093100Y511900D01*
G01X1084800Y499400D02*
Y503600D01*
G01X1057676Y519519D02*
Y518157D01*
G01X1058286Y520129D02*
X1057676Y519519D01*
G01X1060018Y520129D02*
X1058286D01*
G01X1060628Y520739D02*
X1060018Y520129D01*
G01X1060628Y521729D02*
Y520739D01*
G01X1060018Y522339D02*
X1060628Y521729D01*
G01X1058621Y522339D02*
X1060018D01*
G01X1058026Y522934D02*
X1058621Y522339D01*
G01X1058026Y523924D02*
Y522934D01*
G01X1058651Y524549D02*
X1058026Y523924D01*
G01X1062605Y524549D02*
X1058651D01*
G01X1063184Y525128D02*
X1062605Y524549D01*
G01X1063184Y526118D02*
Y525128D01*
G01X1062543Y526759D02*
X1063184Y526118D01*
G01X1054330Y529021D02*
X1054331Y529022D01*
G01X1064371Y534563D02*
X1065987Y532947D01*
G01X1064371Y536957D02*
Y534563D01*
G01X1044202Y537057D02*
X1044203Y537058D01*
G01X1044202Y534647D02*
Y537057D01*
G01X1046291Y532558D02*
X1044202Y534647D01*
G01X1046291Y530064D02*
Y532558D01*
G01X1045915Y529688D02*
X1046291Y530064D01*
G01X1094488Y536955D02*
X1094490Y536957D01*
G01X1094488Y531788D02*
Y536955D01*
G01X1092873Y530173D02*
X1094488Y531788D01*
G01X1092873Y527627D02*
Y530173D01*
G01X1093600Y526900D02*
X1092873Y527627D01*
G01X1058286Y526759D02*
X1062543D01*
G01X1057676Y527369D02*
X1058286Y526759D01*
G01X1057676Y529006D02*
Y527369D01*
G01X1057677Y529007D02*
X1057676Y529006D01*
G01X1142980Y557662D02*
X1144685Y555957D01*
G01X1142980Y569315D02*
Y557662D01*
G01X1146165Y572500D02*
X1142980Y569315D01*
G01X1147331Y572500D02*
X1146165D01*
G01X1147243Y550914D02*
X1147331D01*
G01X1145557Y552600D02*
X1147243Y550914D01*
G01X1145557Y554292D02*
Y552600D01*
G01X1146464Y555199D02*
X1145557Y554292D01*
G01X1146464Y556792D02*
Y555199D01*
G01X1145320Y557936D02*
X1146464Y556792D01*
G01X1145320Y559356D02*
Y557936D01*
G01X1146164Y560200D02*
X1145320Y559356D01*
G01X1146164Y561900D02*
Y560200D01*
G01X1145320Y562744D02*
X1146164Y561900D01*
G01X1145320Y563956D02*
Y562744D01*
G01X1146264Y564900D02*
X1145320Y563956D01*
G01X1146264Y566100D02*
Y564900D01*
G01X1145665Y566699D02*
X1146264Y566100D01*
G01X1144685Y566699D02*
X1145665D01*
G01X1139964Y572500D02*
X1140952D01*
G01X1136909Y569445D02*
X1139964Y572500D01*
G01X1136909Y568257D02*
Y569445D01*
G01X1136287Y567635D02*
X1136909Y568257D01*
G01X1136287Y557662D02*
Y567635D01*
G01X1137992Y555957D02*
X1136287Y557662D01*
G01X1140950Y550914D02*
X1141038D01*
G01X1139264Y552600D02*
X1140950Y550914D01*
G01X1139264Y554800D02*
Y552600D01*
G01X1139764Y555300D02*
X1139264Y554800D01*
G01X1139764Y557199D02*
Y555300D01*
G01X1138627Y558336D02*
X1139764Y557199D01*
G01X1138627Y559664D02*
Y558336D01*
G01X1139564Y560601D02*
X1138627Y559664D01*
G01X1139564Y561999D02*
Y560601D01*
G01X1138627Y562936D02*
X1139564Y561999D01*
G01X1138627Y564164D02*
Y562936D01*
G01X1139664Y565201D02*
X1138627Y564164D01*
G01X1139664Y566099D02*
Y565201D01*
G01X1139064Y566699D02*
X1139664Y566099D01*
G01X1137992Y566699D02*
X1139064D01*
G01X1176775Y572500D02*
X1177763D01*
G01X1173720Y569445D02*
X1176775Y572500D01*
G01X1173720Y568257D02*
Y569445D01*
G01X1173098Y567635D02*
X1173720Y568257D01*
G01X1173098Y557662D02*
Y567635D01*
G01X1174803Y555957D02*
X1173098Y557662D01*
G01X1201486Y550914D02*
X1201574D01*
G01X1199800Y552600D02*
X1201486Y550914D01*
G01X1199800Y554292D02*
Y552600D01*
G01X1199975Y554467D02*
X1199800Y554292D01*
G01X1199975Y557100D02*
Y554467D01*
G01X1198863Y558212D02*
X1199975Y557100D01*
G01X1198863Y559288D02*
Y558212D01*
G01X1199875Y560300D02*
X1198863Y559288D01*
G01X1199875Y561500D02*
Y560300D01*
G01X1198863Y562512D02*
X1199875Y561500D01*
G01X1198863Y563588D02*
Y562512D01*
G01X1200000Y564725D02*
X1198863Y563588D01*
G01X1200000Y565999D02*
Y564725D01*
G01X1199300Y566699D02*
X1200000Y565999D01*
G01X1198228Y566699D02*
X1199300D01*
G01X1164675Y550914D02*
X1164763D01*
G01X1162989Y552600D02*
X1164675Y550914D01*
G01X1162989Y554292D02*
Y552600D01*
G01X1163164Y554467D02*
X1162989Y554292D01*
G01X1163164Y557100D02*
Y554467D01*
G01X1162052Y558212D02*
X1163164Y557100D01*
G01X1162052Y559288D02*
Y558212D01*
G01X1163064Y560300D02*
X1162052Y559288D01*
G01X1163064Y561500D02*
Y560300D01*
G01X1162052Y562512D02*
X1163064Y561500D01*
G01X1162052Y563588D02*
Y562512D01*
G01X1163189Y564725D02*
X1162052Y563588D01*
G01X1163189Y565999D02*
Y564725D01*
G01X1162489Y566699D02*
X1163189Y565999D01*
G01X1161417Y566699D02*
X1162489D01*
G01X1208179Y550914D02*
X1208267D01*
G01X1206493Y552600D02*
X1208179Y550914D01*
G01X1206493Y554292D02*
Y552600D01*
G01X1206668Y554467D02*
X1206493Y554292D01*
G01X1206668Y557100D02*
Y554467D01*
G01X1205556Y558212D02*
X1206668Y557100D01*
G01X1205556Y559288D02*
Y558212D01*
G01X1206568Y560300D02*
X1205556Y559288D01*
G01X1206568Y561500D02*
Y560300D01*
G01X1205556Y562512D02*
X1206568Y561500D01*
G01X1205556Y563588D02*
Y562512D01*
G01X1206693Y564725D02*
X1205556Y563588D01*
G01X1206693Y565999D02*
Y564725D01*
G01X1205993Y566699D02*
X1206693Y565999D01*
G01X1204921Y566699D02*
X1205993D01*
G01X1177761Y550914D02*
X1177849D01*
G01X1176075Y552600D02*
X1177761Y550914D01*
G01X1176075Y554800D02*
Y552600D01*
G01X1176575Y555300D02*
X1176075Y554800D01*
G01X1176575Y557199D02*
Y555300D01*
G01X1175438Y558336D02*
X1176575Y557199D01*
G01X1175438Y559664D02*
Y558336D01*
G01X1176375Y560601D02*
X1175438Y559664D01*
G01X1176375Y561999D02*
Y560601D01*
G01X1175438Y562936D02*
X1176375Y561999D01*
G01X1175438Y564164D02*
Y562936D01*
G01X1176475Y565201D02*
X1175438Y564164D01*
G01X1176475Y566099D02*
Y565201D01*
G01X1175875Y566699D02*
X1176475Y566099D01*
G01X1174803Y566699D02*
X1175875D01*
G01X1184054Y550914D02*
X1184142D01*
G01X1182368Y552600D02*
X1184054Y550914D01*
G01X1182368Y554292D02*
Y552600D01*
G01X1183275Y555199D02*
X1182368Y554292D01*
G01X1183275Y556792D02*
Y555199D01*
G01X1182131Y557936D02*
X1183275Y556792D01*
G01X1182131Y559356D02*
Y557936D01*
G01X1182975Y560200D02*
X1182131Y559356D01*
G01X1182975Y561900D02*
Y560200D01*
G01X1182131Y562744D02*
X1182975Y561900D01*
G01X1182131Y563956D02*
Y562744D01*
G01X1183075Y564900D02*
X1182131Y563956D01*
G01X1183075Y566100D02*
Y564900D01*
G01X1182476Y566699D02*
X1183075Y566100D01*
G01X1181496Y566699D02*
X1182476D01*
G01X1203216Y567849D02*
X1208267Y572900D01*
G01X1203216Y557662D02*
Y567849D01*
G01X1204921Y555957D02*
X1203216Y557662D01*
G01X1166405Y567849D02*
X1171456Y572900D01*
G01X1166405Y557662D02*
Y567849D01*
G01X1168110Y555957D02*
X1166405Y557662D01*
G01X1182976Y572500D02*
X1184142D01*
G01X1179791Y569315D02*
X1182976Y572500D01*
G01X1179791Y557662D02*
Y569315D01*
G01X1181496Y555957D02*
X1179791Y557662D01*
G01X1171368Y550914D02*
X1171456D01*
G01X1169682Y552600D02*
X1171368Y550914D01*
G01X1169682Y554292D02*
Y552600D01*
G01X1169857Y554467D02*
X1169682Y554292D01*
G01X1169857Y557100D02*
Y554467D01*
G01X1168745Y558212D02*
X1169857Y557100D01*
G01X1168745Y559288D02*
Y558212D01*
G01X1169757Y560300D02*
X1168745Y559288D01*
G01X1169757Y561500D02*
Y560300D01*
G01X1168745Y562512D02*
X1169757Y561500D01*
G01X1168745Y563588D02*
Y562512D01*
G01X1169882Y564725D02*
X1168745Y563588D01*
G01X1169882Y565999D02*
Y564725D01*
G01X1169182Y566699D02*
X1169882Y565999D01*
G01X1168110Y566699D02*
X1169182D01*
G01X1159712Y567849D02*
X1164763Y572900D01*
G01X1159712Y557662D02*
Y567849D01*
G01X1161417Y555957D02*
X1159712Y557662D01*
G01X1196523Y567849D02*
X1201574Y572900D01*
G01X1196523Y557662D02*
Y567849D01*
G01X1198228Y555957D02*
X1196523Y557662D01*
M02*
